G04 ================== begin FILE IDENTIFICATION RECORD ==================*
G04 Layout Name:  15105-sa.brd*
G04 Film Name:    TSILK*
G04 File Format:  Gerber RS274X*
G04 File Origin:  Cadence Allegro 16.5-S056*
G04 Origin Date:  Wed Nov 16 02:01:56 2016*
G04 *
G04 Layer:  VIA CLASS/FILMMASKTOP*
G04 Layer:  REF DES/ASSEMBLY_TOP*
G04 Layer:  PACKAGE GEOMETRY/SILKSCREEN_TOP*
G04 Layer:  DRAWING FORMAT/LAYER_PCB_STORY*
G04 Layer:  DRAWING FORMAT/LAYER_SILK_T*
G04 Layer:  BOARD GEOMETRY/SILKSCREEN_TOP*
G04 *
G04 Offset:    (0.00 0.00)*
G04 Mirror:    No*
G04 Mode:      Positive*
G04 Rotation:  0*
G04 FullContactRelief:  No*
G04 UndefLineWidth:     6.00*
G04 ================== end FILE IDENTIFICATION RECORD ====================*
%FSLAX35Y35*MOIN*%
%IR0*IPPOS*OFA0.00000B0.00000*MIA0B0*SFA1.00000B1.00000*%
%ADD10C,.02*%
%ADD11C,.03*%
%ADD12C,.012*%
%ADD13C,.013*%
%ADD14C,.014*%
%ADD15C,.015*%
%ADD16C,.016*%
%ADD17C,.025*%
%ADD18C,.027*%
%ADD19C,.019*%
%ADD20C,.002*%
%ADD21C,.006*%
%ADD22C,.008*%
G75*
%LPD*%
G75*
G36*
G01X50816Y327807D02*
Y332807D01*
X48316Y330307D01*
X50816Y327807D01*
G37*
G36*
G01X33666Y379907D02*
Y368707D01*
X51066D01*
Y379907D01*
X33666D01*
G37*
G36*
G01X38100Y432400D02*
Y435400D01*
X41100D01*
X38100Y432400D01*
G37*
G36*
G01X63150Y748750D02*
X68150Y743750D01*
Y748750D01*
X63150D01*
G37*
G36*
G01X94866Y233808D02*
X92366Y231308D01*
X97366D01*
X94866Y233808D01*
G37*
G36*
G01X93200Y276200D02*
Y281200D01*
X88200Y276200D01*
X93200D01*
G37*
G36*
G01X93840Y243746D02*
Y249694D01*
G03X95790Y252316I-850J2668D01*
G01X113990D01*
G03X115940Y249694I2800J46D01*
G01Y243746D01*
X93840D01*
G37*
G36*
G01X92752Y592150D02*
X97752D01*
X95252Y589650D01*
X92752Y592150D01*
G37*
G36*
G01X81993Y721423D02*
G03I-1000J0D01*
G37*
G36*
G01X130100Y290300D02*
X120100D01*
Y295300D01*
X130100D01*
Y290300D01*
G37*
G36*
G01X126600Y725800D02*
X117600D01*
Y733800D01*
X126600D01*
Y725800D01*
G37*
G36*
G01X101500Y776100D02*
X103200Y777800D01*
X104900Y776100D01*
X101500D01*
G37*
G36*
G01X104711Y810201D02*
X102711Y808201D01*
X106711D01*
X104711Y810201D01*
G37*
G36*
G01X154380Y173331D02*
X144380D01*
Y178331D01*
X154380D01*
Y173331D01*
G37*
G36*
G01X149200Y214400D02*
X147800Y213000D01*
X150600D01*
X149200Y214400D01*
G37*
G36*
G01X131500Y272100D02*
X136500D01*
X131500Y277100D01*
Y272100D01*
G37*
G36*
G01X164000Y298800D02*
X159000D01*
X164000Y293800D01*
Y298800D01*
G37*
G36*
G01X132100Y394850D02*
X137100Y399850D01*
X132100D01*
Y394850D01*
G37*
G36*
G01X158000Y788800D02*
Y797800D01*
X166000D01*
Y788800D01*
X158000D01*
G37*
G36*
G01X176690Y177222D02*
X171690D01*
X174190Y179722D01*
X176690Y177222D01*
G37*
G36*
G01X207318Y235006D02*
X190118D01*
Y216206D01*
X207318D01*
Y235006D01*
G37*
G36*
G01X190018Y213608D02*
X207018D01*
Y237604D01*
X190018D01*
Y213608D01*
G37*
G36*
G01X197500Y709800D02*
Y718800D01*
X205500D01*
Y709800D01*
X197500D01*
G37*
G36*
G01X165200Y733700D02*
Y742700D01*
X173200D01*
Y733700D01*
X165200D01*
G37*
G36*
G01X197500Y765300D02*
Y774300D01*
X205500D01*
Y765300D01*
X197500D01*
G37*
G36*
G01X209000Y585950D02*
X217000D01*
Y595050D01*
X209000D01*
Y585950D01*
G37*
G36*
G01X257047Y63589D02*
X259547Y61089D01*
Y66089D01*
X257047Y63589D01*
G37*
G36*
G01X243831Y62189D02*
Y119989D01*
X242063D01*
Y62189D01*
X243831D01*
G37*
G36*
G01X235231Y279459D02*
Y249101D01*
X272231D01*
Y279459D01*
X235231D01*
G37*
G36*
G01X272490Y251580D02*
X234981D01*
Y276980D01*
X272490D01*
Y251580D01*
G37*
G36*
G01X243000Y502000D02*
X240000Y499000D01*
X243000Y496000D01*
Y502000D01*
G37*
G36*
G01X265900Y501400D02*
X264500Y502800D01*
Y500000D01*
X265900Y501400D01*
G37*
G36*
G01X273350Y138000D02*
Y142050D01*
X269300Y138000D01*
X273350D01*
G37*
G36*
G01X288829Y344840D02*
X277629D01*
Y327440D01*
X288829D01*
Y344840D01*
G37*
G36*
G01X279500Y508400D02*
X280900Y507000D01*
Y509800D01*
X279500Y508400D01*
G37*
G36*
G01X267888Y576965D02*
X279088D01*
Y594365D01*
X267888D01*
Y576965D01*
G37*
G36*
G01X269200Y629500D02*
Y626500D01*
X266200D01*
X269200Y629500D01*
G37*
G36*
G01X277106Y753398D02*
X306406D01*
Y739398D01*
X277106D01*
Y753398D01*
G37*
G36*
G01X301834Y279390D02*
Y249032D01*
X338834D01*
Y279390D01*
X301834D01*
G37*
G36*
G01X339093Y251511D02*
X301584D01*
Y276911D01*
X339093D01*
Y251511D01*
G37*
G36*
G01X460700Y102700D02*
Y88700D01*
X479700D01*
Y102700D01*
X460700D01*
G37*
G36*
G01X466032Y166564D02*
X469567Y163028D01*
X466032Y159493D01*
Y161899D01*
X448034D01*
X438952D01*
Y164199D01*
X448034D01*
X466032D01*
Y166564D01*
G37*
G36*
G01X498309Y322841D02*
X509509D01*
Y340241D01*
X498309D01*
Y322841D01*
G37*
G36*
G01X474200Y373600D02*
Y382600D01*
X482200D01*
Y373600D01*
X474200D01*
G37*
G36*
G01X490606Y805398D02*
X519906D01*
Y791398D01*
X490606D01*
Y805398D01*
G37*
G36*
G01X509673Y-19527D02*
Y109220D01*
X692173D01*
Y-19527D01*
X509673D01*
G37*
G36*
G01X522400Y168950D02*
X520400Y166950D01*
X524400D01*
X522400Y168950D01*
G37*
G36*
G01X529415Y186166D02*
Y181834D01*
X562385D01*
Y186166D01*
X529415D01*
G37*
G36*
G01X518226Y255361D02*
X535426D01*
Y274161D01*
X518226D01*
Y255361D01*
G37*
G36*
G01X535526Y276659D02*
X518526D01*
Y252663D01*
X535526D01*
Y276659D01*
G37*
G36*
G01X566931Y367980D02*
X569931D01*
Y364980D01*
X566931Y367980D01*
G37*
G36*
G01X557000Y651500D02*
Y646500D01*
X577000D01*
Y651500D01*
X557000D01*
G37*
G36*
G01X605200Y351250D02*
X601800D01*
X603500Y352950D01*
X605200Y351250D01*
G37*
G36*
G01X599100Y647000D02*
Y665000D01*
X600900D01*
Y647000D01*
X599100D01*
G37*
G36*
G01X600900Y655100D02*
Y656900D01*
X606300D01*
Y655100D01*
X600900D01*
G37*
G36*
G01X616613Y226858D02*
Y230908D01*
X612563Y226858D01*
X616613D01*
G37*
G36*
G01X619150Y370450D02*
Y365450D01*
X624150Y370450D01*
X619150D01*
G37*
G36*
G01X610800Y647000D02*
Y665000D01*
X612600D01*
Y647000D01*
X610800D01*
G37*
G36*
G01X606300D02*
Y665000D01*
X608100D01*
Y647000D01*
X606300D01*
G37*
G36*
G01X612600Y655100D02*
Y656900D01*
X618000D01*
Y655100D01*
X612600D01*
G37*
G36*
G01Y663200D02*
Y665000D01*
X619800D01*
Y663200D01*
X612600D01*
G37*
G36*
G01X709402Y-14079D02*
Y-9766D01*
X728264D01*
Y-14079D01*
X709402D01*
G37*
G36*
G01X756614Y-16369D02*
Y-11677D01*
X785097D01*
Y-16369D01*
X756614D01*
G37*
G36*
G01X791051Y-16547D02*
Y-11543D01*
X829204D01*
Y-16547D01*
X791051D01*
G37*
G36*
G01X791738Y98800D02*
X777738D01*
Y79800D01*
X791738D01*
Y98800D01*
G37*
G36*
G01X794638Y130200D02*
X780638D01*
Y111200D01*
X794638D01*
Y130200D01*
G37*
G36*
G01X829332Y-16551D02*
Y-11647D01*
X861132D01*
Y-16551D01*
X829332D01*
G37*
G36*
G01X872126Y-16828D02*
Y-12326D01*
X894780D01*
Y-16828D01*
X872126D01*
G37*
G36*
G01X872130Y-12142D02*
Y-8113D01*
X900566D01*
Y-12142D01*
X872130D01*
G37*
G36*
G01X872081Y-7897D02*
Y-4011D01*
X897484D01*
Y-7897D01*
X872081D01*
G37*
G36*
G01X860106Y782398D02*
X889406D01*
Y768398D01*
X860106D01*
Y782398D01*
G37*
G36*
G01X890600Y47200D02*
X879400D01*
Y29800D01*
X890600D01*
Y47200D01*
G37*
G36*
G01X896400Y58050D02*
X898800Y55650D01*
Y60450D01*
X896400Y58050D01*
G37*
G36*
G01X890950Y330600D02*
Y322600D01*
X900050D01*
Y330600D01*
X890950D01*
G37*
G36*
G01X1015403Y17807D02*
X996903D01*
Y30207D01*
X1015403D01*
Y17807D01*
G37*
G36*
G01X1005700Y71600D02*
X1016900D01*
Y54150D01*
X1005700D01*
Y71600D01*
G37*
G36*
G01X1031265Y7875D02*
X1029265Y9875D01*
X1033265D01*
X1031265Y7875D01*
G37*
G36*
G01X1022763Y264495D02*
X1028763D01*
X1022763Y270495D01*
Y264495D01*
G37*
G36*
G01X1036495Y386328D02*
X1036434Y386267D01*
X1036373Y385780D01*
X1036312Y385719D01*
X1036251Y385233D01*
X1036191Y385172D01*
X1036130Y384625D01*
X1036069Y384564D01*
X1036008Y384077D01*
X1035947Y384017D01*
X1035886Y383530D01*
X1035826Y383469D01*
X1035765Y382922D01*
X1035704Y382861D01*
X1035643Y382375D01*
X1035582Y382314D01*
X1035521Y381827D01*
X1035461Y381766D01*
X1035400Y381219D01*
X1035339Y381158D01*
X1035278Y380671D01*
X1035218Y380611D01*
X1035157Y380124D01*
X1035096Y380063D01*
X1035035Y379516D01*
X1034974Y379455D01*
X1034913Y378969D01*
X1034853Y378908D01*
X1034792Y378421D01*
X1034731Y378360D01*
X1034670Y377813D01*
X1034609Y377752D01*
X1034549Y377266D01*
X1034488Y377205D01*
X1034427Y376718D01*
X1034366Y376658D01*
X1034305Y376110D01*
X1034244Y376049D01*
X1034184Y375563D01*
X1034123Y375502D01*
X1034062Y375016D01*
X1034001Y374955D01*
X1033940Y374407D01*
X1033879Y374346D01*
X1033819Y373860D01*
X1033758Y373799D01*
Y373738D01*
X1039110D01*
X1039171Y374103D01*
X1039232Y374164D01*
X1039292Y374651D01*
X1039353Y374711D01*
X1039414Y375258D01*
X1039475Y375319D01*
X1039536Y375806D01*
X1039596Y375867D01*
X1039657Y376353D01*
X1039718Y376414D01*
X1039779Y376962D01*
X1039840Y377022D01*
X1039901Y377509D01*
X1039961Y377570D01*
X1040022Y378056D01*
X1040083Y378117D01*
X1040144Y378664D01*
X1040205Y378725D01*
X1040266Y379212D01*
X1040326Y379273D01*
X1040387Y379759D01*
X1040448Y379820D01*
X1040509Y380368D01*
X1040570Y380428D01*
X1040631Y380915D01*
X1040691Y380976D01*
X1040752Y381462D01*
X1040813Y381523D01*
X1040874Y382010D01*
X1040934Y382070D01*
X1040995Y382618D01*
X1041056Y382679D01*
X1041117Y383165D01*
X1041178Y383226D01*
X1041238Y383712D01*
X1041299Y383773D01*
X1041360Y384321D01*
X1041421Y384382D01*
X1041482Y384868D01*
X1041543Y384929D01*
X1041603Y385416D01*
X1041664Y385476D01*
X1041725Y386024D01*
X1041786Y386084D01*
X1041847Y386571D01*
X1041908Y386632D01*
Y386693D01*
X1036555D01*
X1036495Y386328D01*
G37*
G36*
G01X1012228Y385963D02*
X1012289Y385476D01*
X1012349Y385416D01*
X1012410Y384686D01*
X1012471Y384625D01*
X1012532Y383834D01*
X1012593Y383773D01*
X1012654Y383043D01*
X1012714Y382983D01*
X1012775Y382253D01*
X1012836Y382192D01*
X1012897Y381462D01*
X1012958Y381401D01*
X1013018Y380671D01*
X1013079Y380611D01*
X1013140Y379820D01*
X1013201Y379759D01*
X1013262Y379029D01*
X1013323Y378969D01*
X1013383Y378239D01*
X1013444Y378178D01*
X1013505Y377448D01*
X1013566Y377387D01*
X1013627Y376658D01*
X1013688Y376597D01*
X1013748Y375867D01*
X1013809Y375806D01*
X1013870Y375016D01*
X1013931Y374955D01*
X1013992Y374225D01*
X1014053Y374164D01*
X1014113Y373738D01*
X1018553D01*
X1018736Y373981D01*
X1018857Y374286D01*
X1019040Y374529D01*
X1019161Y374833D01*
X1019344Y375076D01*
X1019405Y375258D01*
X1019587Y375502D01*
X1019708Y375806D01*
X1019891Y376049D01*
X1020013Y376353D01*
X1020195Y376597D01*
X1020317Y376901D01*
X1020499Y377144D01*
X1020560Y377327D01*
X1020742Y377570D01*
X1020864Y377874D01*
X1021047Y378117D01*
X1021168Y378421D01*
X1021351Y378664D01*
X1021472Y378969D01*
X1021655Y379212D01*
X1021777Y379516D01*
X1021959Y379759D01*
X1022020Y379942D01*
X1022202Y380185D01*
X1022324Y380489D01*
X1022506Y380732D01*
X1022628Y381036D01*
X1022810Y381280D01*
Y381341D01*
X1022932Y381462D01*
X1022993Y381401D01*
X1023054Y380306D01*
X1023114Y380246D01*
X1023175Y379151D01*
X1023236Y379090D01*
X1023297Y377995D01*
X1023358Y377935D01*
X1023419Y376779D01*
X1023479Y376718D01*
X1023540Y375623D01*
X1023601Y375563D01*
X1023662Y374468D01*
X1023723Y374407D01*
X1023783Y373738D01*
X1028223D01*
X1028345Y374042D01*
X1028527Y374286D01*
X1028588Y374468D01*
X1028771Y374711D01*
X1028831Y374894D01*
X1029014Y375137D01*
X1029075Y375319D01*
X1029257Y375563D01*
X1029379Y375867D01*
X1029561Y376110D01*
X1029622Y376293D01*
X1029805Y376536D01*
X1029866Y376718D01*
X1030048Y376962D01*
X1030108Y377144D01*
X1030291Y377387D01*
X1030352Y377570D01*
X1030534Y377813D01*
X1030595Y377995D01*
X1030778Y378239D01*
X1030838Y378421D01*
X1031021Y378664D01*
X1031082Y378847D01*
X1031264Y379090D01*
X1031325Y379273D01*
X1031508Y379516D01*
X1031629Y379820D01*
X1031812Y380063D01*
X1031872Y380246D01*
X1032055Y380489D01*
X1032116Y380671D01*
X1032298Y380915D01*
X1032359Y381097D01*
X1032542Y381341D01*
X1032602Y381523D01*
X1032785Y381766D01*
X1032845Y381949D01*
X1033028Y382192D01*
X1033089Y382375D01*
X1033271Y382618D01*
X1033332Y382800D01*
X1033514Y383043D01*
X1033575Y383226D01*
X1033758Y383469D01*
X1033879Y383773D01*
X1034062Y384017D01*
X1034123Y384199D01*
X1034305Y384442D01*
X1034366Y384625D01*
X1034549Y384868D01*
X1034609Y385051D01*
X1034792Y385294D01*
X1034853Y385476D01*
X1035035Y385719D01*
X1035096Y385902D01*
X1035278Y386145D01*
X1035339Y386328D01*
X1035521Y386571D01*
Y386632D01*
X1035582Y386693D01*
X1030473D01*
X1030413Y386449D01*
X1030170Y386024D01*
X1030108Y385780D01*
X1029926Y385476D01*
X1029866Y385233D01*
X1029744Y385051D01*
X1029683Y384807D01*
X1029501Y384503D01*
X1029440Y384260D01*
X1029257Y383956D01*
X1029196Y383712D01*
X1029075Y383530D01*
X1029014Y383287D01*
X1028831Y382983D01*
X1028771Y382740D01*
X1028588Y382435D01*
X1028527Y382192D01*
X1028406Y382010D01*
X1028345Y381766D01*
X1028162Y381462D01*
X1028102Y381219D01*
X1027919Y380915D01*
X1027858Y380671D01*
X1027737Y380489D01*
X1027676Y380246D01*
X1027494Y379942D01*
X1027432Y379699D01*
X1027250Y379394D01*
X1027189Y379151D01*
X1027068Y378969D01*
X1027007Y378725D01*
X1026885Y378604D01*
X1026825Y378664D01*
X1026764Y379881D01*
X1026703Y379942D01*
X1026642Y381219D01*
X1026581Y381280D01*
X1026520Y382557D01*
X1026460Y382618D01*
X1026399Y383956D01*
X1026338Y384017D01*
X1026277Y385294D01*
X1026216Y385355D01*
X1026155Y386632D01*
X1026095Y386693D01*
X1021594D01*
X1021412Y386267D01*
X1021229Y386024D01*
X1021047Y385598D01*
X1020864Y385355D01*
X1020682Y384929D01*
X1020499Y384686D01*
X1020317Y384260D01*
X1020134Y384017D01*
X1020013Y383712D01*
X1019830Y383469D01*
X1019648Y383043D01*
X1019465Y382800D01*
X1019283Y382375D01*
X1019100Y382131D01*
X1018979Y381827D01*
X1018796Y381584D01*
X1018614Y381158D01*
X1018431Y380915D01*
X1018249Y380489D01*
X1018066Y380246D01*
X1017884Y379820D01*
X1017701Y379577D01*
X1017580Y379273D01*
X1017397Y379029D01*
X1017215Y378604D01*
X1017094Y378482D01*
X1017032Y378543D01*
X1016972Y380489D01*
X1016911Y380550D01*
X1016850Y382557D01*
X1016789Y382618D01*
X1016729Y384625D01*
X1016668Y384686D01*
X1016607Y386693D01*
X1012106D01*
X1012228Y385963D01*
G37*
G36*
G01X1040022Y393140D02*
X1039536Y393079D01*
X1039353Y392957D01*
X1039110Y392896D01*
X1038867Y392775D01*
X1038562Y392531D01*
X1038502D01*
X1037833Y391801D01*
Y391741D01*
X1037650Y391497D01*
X1037529Y391254D01*
X1037468Y390950D01*
X1037407Y390889D01*
X1037346Y390281D01*
X1037407Y389490D01*
X1037468Y389429D01*
X1037529Y389186D01*
X1037711Y388943D01*
Y388882D01*
X1038258Y388395D01*
X1038319D01*
X1038441Y388274D01*
X1038684Y388213D01*
X1038745Y388152D01*
X1039232Y388092D01*
X1039292Y388030D01*
X1040266Y388092D01*
X1040326Y388152D01*
X1040631Y388213D01*
X1040691Y388274D01*
X1040934Y388335D01*
X1041178Y388456D01*
X1041543Y388760D01*
X1041603D01*
X1042273Y389490D01*
X1042333Y389673D01*
X1042516Y389916D01*
X1042577Y390159D01*
X1042638Y390220D01*
X1042698Y390707D01*
X1042759Y390768D01*
X1042698Y391680D01*
X1042638Y391741D01*
X1042577Y391984D01*
X1042455Y392227D01*
X1042029Y392714D01*
X1041786Y392896D01*
X1041421Y393079D01*
X1040995Y393140D01*
X1040934Y393200D01*
X1040083D01*
X1040022Y393140D01*
G37*
G36*
G01X1050050Y25100D02*
X1047650Y22700D01*
X1052450D01*
X1050050Y25100D01*
G37*
G36*
G01X1055565Y168775D02*
X1153965D01*
Y192375D01*
X1055565D01*
Y168775D01*
G37*
G36*
G01Y144137D02*
X1153965D01*
Y167737D01*
X1055565D01*
Y144137D01*
G37*
G36*
G01X1055543Y193369D02*
X1153943D01*
Y216969D01*
X1055543D01*
Y193369D01*
G37*
G36*
G01X1077122Y386449D02*
X1076940Y386206D01*
X1076879Y386024D01*
X1076696Y385780D01*
X1076635Y385598D01*
X1076453Y385355D01*
X1076392Y385172D01*
X1076210Y384929D01*
X1076088Y384625D01*
X1075905Y384382D01*
X1075845Y384199D01*
X1075662Y383956D01*
X1075601Y383773D01*
X1075419Y383530D01*
X1075358Y383347D01*
X1075176Y383104D01*
X1075054Y382800D01*
X1074871Y382557D01*
X1074811Y382375D01*
X1074628Y382131D01*
X1074568Y381949D01*
X1074385Y381705D01*
X1074324Y381523D01*
X1074142Y381280D01*
X1074081Y381097D01*
X1073899Y380854D01*
X1073777Y380550D01*
X1073594Y380306D01*
X1073534Y380124D01*
X1073351Y379881D01*
X1073290Y379699D01*
X1073108Y379455D01*
Y379394D01*
X1072986Y379273D01*
X1072925Y379334D01*
X1072864Y380306D01*
X1072804Y380368D01*
X1072743Y381523D01*
X1072682Y381584D01*
X1072621Y382800D01*
X1072560Y382861D01*
X1072500Y384017D01*
X1072439Y384077D01*
X1072378Y385294D01*
X1072317Y385355D01*
X1072257Y386510D01*
X1072195Y386571D01*
Y386693D01*
X1067330D01*
X1067391Y386632D01*
X1067452Y386024D01*
X1067512Y385963D01*
X1067573Y385355D01*
X1067634Y385294D01*
X1067695Y384746D01*
X1067756Y384686D01*
X1067817Y384077D01*
X1067877Y384017D01*
X1067938Y383408D01*
X1067999Y383347D01*
X1068060Y382800D01*
X1068121Y382740D01*
X1068181Y382131D01*
X1068242Y382070D01*
X1068303Y381462D01*
X1068364Y381401D01*
X1068425Y380854D01*
X1068486Y380793D01*
X1068546Y380185D01*
X1068607Y380124D01*
X1068668Y379516D01*
X1068729Y379455D01*
X1068790Y378908D01*
X1068851Y378847D01*
X1068911Y378239D01*
X1068972Y378178D01*
X1069033Y377570D01*
X1069094Y377509D01*
X1069155Y376962D01*
X1069216Y376901D01*
X1069276Y376293D01*
X1069337Y376232D01*
X1069398Y375623D01*
X1069458Y375563D01*
X1069520Y375016D01*
X1069580Y374955D01*
X1069641Y374346D01*
X1069702Y374286D01*
X1069763Y373677D01*
X1069823Y373616D01*
X1069702Y373373D01*
X1069520Y373130D01*
X1069398Y372826D01*
X1069216Y372582D01*
X1069155Y372400D01*
X1068972Y372157D01*
X1068911Y371975D01*
X1068729Y371731D01*
X1068668Y371549D01*
X1068486Y371305D01*
X1068364Y371001D01*
X1068181Y370758D01*
X1068121Y370575D01*
X1067938Y370332D01*
X1067877Y370150D01*
X1067695Y369906D01*
X1067634Y369724D01*
X1067452Y369481D01*
X1067330Y369177D01*
X1067147Y368933D01*
X1067087Y368751D01*
X1066904Y368508D01*
X1066844Y368325D01*
X1066661Y368082D01*
X1066600Y367899D01*
X1066418Y367656D01*
X1066296Y367352D01*
X1066175Y367230D01*
X1071283D01*
X1071344Y367413D01*
X1071527Y367656D01*
X1071587Y367839D01*
X1071770Y368082D01*
X1071831Y368264D01*
X1072013Y368508D01*
X1072135Y368812D01*
X1072317Y369055D01*
X1072378Y369238D01*
X1072560Y369481D01*
X1072621Y369663D01*
X1072804Y369906D01*
X1072864Y370089D01*
X1073047Y370332D01*
X1073169Y370636D01*
X1073351Y370880D01*
X1073412Y371062D01*
X1073594Y371305D01*
X1073655Y371488D01*
X1073838Y371731D01*
X1073899Y371914D01*
X1074081Y372157D01*
X1074142Y372339D01*
X1074324Y372582D01*
X1074446Y372887D01*
X1074628Y373130D01*
X1074689Y373312D01*
X1074871Y373556D01*
X1074932Y373738D01*
X1075115Y373981D01*
X1075176Y374164D01*
X1075358Y374407D01*
X1075480Y374711D01*
X1075662Y374955D01*
X1075723Y375137D01*
X1075905Y375380D01*
X1075966Y375563D01*
X1076149Y375806D01*
X1076210Y375988D01*
X1076392Y376232D01*
X1076514Y376536D01*
X1076696Y376779D01*
X1076757Y376962D01*
X1076940Y377205D01*
X1077000Y377387D01*
X1077183Y377630D01*
X1077244Y377813D01*
X1077426Y378056D01*
X1077487Y378239D01*
X1077669Y378482D01*
X1077791Y378786D01*
X1077973Y379029D01*
X1078034Y379212D01*
X1078217Y379455D01*
X1078277Y379638D01*
X1078460Y379881D01*
X1078521Y380063D01*
X1078703Y380306D01*
X1078825Y380611D01*
X1079007Y380854D01*
X1079068Y381036D01*
X1079251Y381280D01*
X1079311Y381462D01*
X1079494Y381705D01*
X1079555Y381888D01*
X1079737Y382131D01*
X1079859Y382435D01*
X1080041Y382679D01*
X1080102Y382861D01*
X1080284Y383104D01*
X1080345Y383287D01*
X1080528Y383530D01*
X1080588Y383712D01*
X1080771Y383956D01*
X1080893Y384260D01*
X1081075Y384503D01*
X1081136Y384686D01*
X1081318Y384929D01*
X1081379Y385111D01*
X1081562Y385355D01*
X1081623Y385537D01*
X1081805Y385780D01*
X1081866Y385963D01*
X1082048Y386206D01*
X1082170Y386510D01*
X1082292Y386632D01*
Y386753D01*
X1077244D01*
X1077122Y386449D01*
G37*
G36*
G01X1042942Y386145D02*
X1043002Y386084D01*
X1043063Y385294D01*
X1043124Y385233D01*
X1043185Y384503D01*
X1043245Y384442D01*
X1043307Y383712D01*
X1043367Y383652D01*
X1043428Y382922D01*
X1043489Y382861D01*
X1043550Y382131D01*
X1043610Y382070D01*
X1043671Y381341D01*
X1043732Y381280D01*
X1043793Y380489D01*
X1043854Y380428D01*
X1043915Y379699D01*
X1043975Y379638D01*
X1044036Y378908D01*
X1044097Y378847D01*
X1044158Y378117D01*
X1044219Y378056D01*
X1044279Y377327D01*
X1044340Y377266D01*
X1044401Y376536D01*
X1044462Y376475D01*
X1044523Y375684D01*
X1044584Y375623D01*
X1044644Y374894D01*
X1044705Y374833D01*
X1044766Y374103D01*
X1044827Y374042D01*
Y373738D01*
X1049327D01*
X1049449Y373981D01*
X1049632Y374225D01*
X1049753Y374529D01*
X1049936Y374772D01*
X1050057Y375076D01*
X1050240Y375319D01*
X1050362Y375623D01*
X1050544Y375867D01*
X1050666Y376171D01*
X1050848Y376414D01*
X1050970Y376718D01*
X1051152Y376962D01*
X1051213Y377144D01*
X1051395Y377387D01*
X1051517Y377692D01*
X1051699Y377935D01*
X1051821Y378239D01*
X1052004Y378482D01*
X1052125Y378786D01*
X1052308Y379029D01*
X1052429Y379334D01*
X1052612Y379577D01*
X1052733Y379881D01*
X1052916Y380124D01*
X1052977Y380306D01*
X1053159Y380550D01*
X1053281Y380854D01*
X1053463Y381097D01*
X1053646Y381462D01*
X1053707Y381401D01*
X1053767Y380915D01*
X1053828Y380185D01*
X1053889Y379820D01*
X1053950Y378969D01*
X1054010Y378908D01*
X1054071Y377813D01*
X1054132Y377752D01*
X1054193Y376658D01*
X1054254Y376597D01*
X1054315Y375441D01*
X1054375Y375380D01*
X1054436Y374286D01*
X1054497Y374225D01*
Y373738D01*
X1058937D01*
X1059058Y373981D01*
X1059241Y374225D01*
X1059302Y374407D01*
X1059484Y374651D01*
X1059545Y374833D01*
X1059728Y375076D01*
X1059788Y375258D01*
X1059971Y375502D01*
X1060032Y375684D01*
X1060214Y375928D01*
X1060275Y376110D01*
X1060457Y376353D01*
X1060518Y376536D01*
X1060701Y376779D01*
X1060762Y376962D01*
X1060944Y377205D01*
X1061005Y377387D01*
X1061187Y377630D01*
X1061309Y377935D01*
X1061492Y378178D01*
X1061552Y378360D01*
X1061734Y378604D01*
X1061795Y378786D01*
X1061978Y379029D01*
X1062039Y379212D01*
X1062221Y379455D01*
X1062282Y379638D01*
X1062464Y379881D01*
X1062525Y380063D01*
X1062708Y380306D01*
X1062769Y380489D01*
X1062951Y380732D01*
X1063012Y380915D01*
X1063194Y381158D01*
X1063255Y381341D01*
X1063438Y381584D01*
X1063498Y381766D01*
X1063681Y382010D01*
X1063803Y382314D01*
X1063985Y382557D01*
X1064046Y382740D01*
X1064228Y382983D01*
X1064289Y383165D01*
X1064471Y383408D01*
X1064532Y383591D01*
X1064715Y383834D01*
X1064775Y384017D01*
X1064958Y384260D01*
X1065019Y384442D01*
X1065201Y384686D01*
X1065262Y384868D01*
X1065445Y385111D01*
X1065505Y385294D01*
X1065688Y385537D01*
X1065749Y385719D01*
X1065931Y385963D01*
X1066053Y386267D01*
X1066235Y386510D01*
X1066296Y386632D01*
Y386693D01*
X1061248D01*
X1061005Y386206D01*
X1060944Y385963D01*
X1060762Y385659D01*
X1060701Y385416D01*
X1060579Y385233D01*
X1060518Y384990D01*
X1060336Y384686D01*
X1060275Y384442D01*
X1060092Y384138D01*
X1060032Y383895D01*
X1059910Y383712D01*
X1059849Y383469D01*
X1059667Y383165D01*
X1059606Y382922D01*
X1059423Y382618D01*
X1059363Y382375D01*
X1059241Y382192D01*
X1059180Y381949D01*
X1058998Y381645D01*
X1058937Y381401D01*
X1058755Y381097D01*
X1058694Y380854D01*
X1058572Y380671D01*
X1058511Y380428D01*
X1058329Y380124D01*
X1058268Y379881D01*
X1058086Y379577D01*
X1058025Y379334D01*
X1057903Y379151D01*
X1057842Y378908D01*
X1057660Y378604D01*
X1057599Y378664D01*
X1057538Y379638D01*
X1057477Y380003D01*
X1057416Y380976D01*
X1057356Y381341D01*
X1057295Y382314D01*
X1057234Y382679D01*
X1057173Y383652D01*
X1057112Y384017D01*
X1057051Y384990D01*
X1056991Y385355D01*
X1056930Y386328D01*
X1056869Y386693D01*
X1052368D01*
Y386632D01*
X1052186Y386388D01*
X1052004Y385963D01*
X1051821Y385719D01*
X1051639Y385294D01*
X1051456Y385051D01*
X1051274Y384625D01*
X1051091Y384382D01*
X1050970Y384077D01*
X1050787Y383834D01*
X1050605Y383408D01*
X1050422Y383165D01*
X1050240Y382740D01*
X1050057Y382496D01*
X1049875Y382070D01*
X1049692Y381827D01*
X1049571Y381523D01*
X1049388Y381280D01*
X1049206Y380854D01*
X1049023Y380611D01*
X1048841Y380185D01*
X1048658Y379942D01*
X1048476Y379516D01*
X1048294Y379273D01*
X1048172Y378969D01*
X1047990Y378725D01*
X1047868Y378482D01*
X1047807Y378543D01*
X1047746Y379881D01*
X1047685Y380611D01*
X1047625Y381949D01*
X1047564Y382679D01*
X1047503Y384017D01*
X1047442Y384868D01*
X1047381Y386084D01*
X1047321Y386693D01*
X1042881D01*
X1042942Y386145D01*
G37*
G36*
G01X1107288Y386936D02*
X1106558Y386875D01*
X1106497Y386814D01*
X1106072Y386753D01*
X1106011Y386693D01*
X1105707Y386632D01*
X1105525Y386510D01*
X1105281Y386449D01*
X1104673Y386145D01*
X1104369Y385902D01*
X1104308D01*
X1103943Y385598D01*
X1103882D01*
X1102970Y384686D01*
X1102909Y384746D01*
X1102970Y385172D01*
X1103031Y385233D01*
X1103092Y385719D01*
X1103153Y385780D01*
X1103213Y386267D01*
X1103274Y386328D01*
X1103335Y386632D01*
Y386693D01*
X1098713D01*
X1098652Y386632D01*
X1098591Y386145D01*
X1098530Y386084D01*
X1098470Y385537D01*
X1098408Y385476D01*
X1098348Y384990D01*
X1098287Y384929D01*
X1098226Y384442D01*
X1098165Y384382D01*
X1098105Y383834D01*
X1098044Y383773D01*
X1097983Y383287D01*
X1097922Y383226D01*
X1097861Y382740D01*
X1097800Y382679D01*
X1097740Y382192D01*
X1097679Y382131D01*
X1097618Y381584D01*
X1097557Y381523D01*
X1097496Y381036D01*
X1097436Y380976D01*
X1097375Y380489D01*
X1097314Y380428D01*
X1097253Y379881D01*
X1097192Y379820D01*
X1097131Y379334D01*
X1097071Y379273D01*
X1097010Y378786D01*
X1096949Y378725D01*
X1096888Y378178D01*
X1096827Y378117D01*
X1096766Y377630D01*
X1096706Y377570D01*
X1096645Y377083D01*
X1096584Y377022D01*
X1096523Y376536D01*
X1096462Y376475D01*
X1096401Y375928D01*
X1096341Y375867D01*
X1096280Y375380D01*
X1096219Y375319D01*
X1096158Y374833D01*
X1096097Y374772D01*
X1096037Y374225D01*
X1095976Y374164D01*
X1095915Y373738D01*
X1100902D01*
X1100963Y374103D01*
X1101024Y374164D01*
X1101084Y374711D01*
X1101145Y374772D01*
X1101206Y375258D01*
X1101267Y375319D01*
X1101328Y375806D01*
X1101389Y375867D01*
X1101449Y376353D01*
X1101510Y376414D01*
X1101571Y376901D01*
X1101632Y376962D01*
X1101693Y377509D01*
X1101754Y377570D01*
X1101814Y378056D01*
X1101875Y378117D01*
X1101936Y378604D01*
X1101997Y378664D01*
X1102058Y379151D01*
X1102119Y379212D01*
X1102179Y379699D01*
X1102240Y379759D01*
X1102301Y380185D01*
X1102362Y380246D01*
X1102423Y380550D01*
X1102484Y380611D01*
X1102544Y380854D01*
X1102605Y380915D01*
X1102666Y381158D01*
X1102727Y381219D01*
X1102788Y381462D01*
X1102970Y381705D01*
X1103031Y381888D01*
X1103274Y382192D01*
Y382253D01*
X1103700Y382740D01*
X1103761D01*
X1104186Y383104D01*
X1104551Y383287D01*
X1105038Y383347D01*
X1105099Y383408D01*
X1105707Y383347D01*
X1105950Y383165D01*
X1106072D01*
Y383043D01*
X1106194Y382922D01*
X1106254Y382557D01*
X1106315Y382496D01*
X1106254Y381766D01*
X1106194Y381705D01*
X1106132Y381097D01*
X1106072Y381036D01*
X1106011Y380489D01*
X1105950Y380428D01*
X1105889Y379942D01*
X1105829Y379881D01*
X1105768Y379334D01*
X1105707Y379273D01*
X1105646Y378786D01*
X1105585Y378725D01*
X1105525Y378239D01*
X1105464Y378178D01*
X1105403Y377630D01*
X1105342Y377570D01*
X1105281Y377083D01*
X1105220Y377022D01*
X1105160Y376475D01*
X1105099Y376414D01*
X1105038Y375928D01*
X1104977Y375867D01*
X1104916Y375380D01*
X1104855Y375319D01*
X1104795Y374772D01*
X1104734Y374711D01*
X1104673Y374225D01*
X1104612Y374164D01*
X1104551Y373738D01*
X1109538D01*
X1109599Y374225D01*
X1109660Y374286D01*
X1109721Y374772D01*
X1109782Y374833D01*
X1109843Y375380D01*
X1109903Y375441D01*
X1109964Y375928D01*
X1110025Y375988D01*
X1110086Y376536D01*
X1110147Y376597D01*
X1110208Y377083D01*
X1110268Y377144D01*
X1110329Y377630D01*
X1110390Y377692D01*
X1110451Y378239D01*
X1110512Y378299D01*
X1110572Y378786D01*
X1110633Y378847D01*
X1110694Y379394D01*
X1110755Y379455D01*
X1110816Y379942D01*
X1110877Y380003D01*
X1110937Y380550D01*
X1110998Y380611D01*
X1111059Y381097D01*
X1111120Y381158D01*
X1111181Y381705D01*
X1111242Y381766D01*
X1111302Y382375D01*
X1111363Y382435D01*
X1111424Y383165D01*
X1111485Y383226D01*
X1111424Y384807D01*
X1111363Y384868D01*
X1111302Y385111D01*
X1111242Y385172D01*
Y385294D01*
X1111059Y385537D01*
Y385598D01*
X1110633Y386084D01*
X1110147Y386510D01*
X1109660Y386753D01*
X1109356Y386814D01*
X1109295Y386875D01*
X1108687Y386936D01*
X1108626Y386997D01*
X1107349D01*
X1107288Y386936D01*
G37*
G36*
G01X1091840D02*
X1091110Y386875D01*
X1091049Y386814D01*
X1090684Y386753D01*
X1090624Y386693D01*
X1090320Y386632D01*
X1090259Y386571D01*
X1090016Y386510D01*
X1089955Y386449D01*
X1089712Y386388D01*
X1089468Y386267D01*
X1089225Y386084D01*
X1089164D01*
X1088860Y385841D01*
X1088799D01*
X1088313Y385416D01*
X1088252D01*
X1087583Y384746D01*
X1087522Y384807D01*
X1087583Y385294D01*
X1087644Y385355D01*
X1087705Y385841D01*
X1087765Y385902D01*
X1087826Y386388D01*
X1087887Y386449D01*
Y386693D01*
X1083265D01*
X1083204Y386267D01*
X1083143Y386206D01*
X1083082Y385659D01*
X1083021Y385598D01*
X1082960Y385111D01*
X1082900Y385051D01*
X1082839Y384564D01*
X1082778Y384503D01*
X1082717Y383956D01*
X1082657Y383895D01*
X1082595Y383408D01*
X1082535Y383347D01*
X1082474Y382861D01*
X1082413Y382800D01*
X1082352Y382314D01*
X1082292Y382253D01*
X1082231Y381705D01*
X1082170Y381645D01*
X1082109Y381158D01*
X1082048Y381097D01*
X1081988Y380611D01*
X1081927Y380550D01*
X1081866Y380003D01*
X1081805Y379942D01*
X1081744Y379455D01*
X1081683Y379394D01*
X1081623Y378908D01*
X1081562Y378847D01*
X1081501Y378299D01*
X1081440Y378239D01*
X1081379Y377752D01*
X1081318Y377692D01*
X1081258Y377205D01*
X1081197Y377144D01*
X1081136Y376658D01*
X1081075Y376597D01*
X1081014Y376049D01*
X1080953Y375988D01*
X1080893Y375502D01*
X1080832Y375441D01*
X1080771Y374955D01*
X1080710Y374894D01*
X1080649Y374346D01*
X1080588Y374286D01*
X1080528Y373799D01*
X1080467Y373738D01*
X1085515D01*
X1085576Y374286D01*
X1085636Y374346D01*
X1085697Y374833D01*
X1085758Y374894D01*
X1085819Y375380D01*
X1085880Y375441D01*
X1085941Y375928D01*
X1086001Y375988D01*
X1086062Y376475D01*
X1086123Y376536D01*
X1086184Y377083D01*
X1086245Y377144D01*
X1086306Y377630D01*
X1086366Y377692D01*
X1086427Y378178D01*
X1086488Y378239D01*
X1086549Y378725D01*
X1086610Y378786D01*
X1086671Y379273D01*
X1086731Y379334D01*
X1086792Y379820D01*
X1086853Y379881D01*
X1086914Y380246D01*
X1086975Y380306D01*
X1087035Y380611D01*
X1087096Y380671D01*
X1087157Y380976D01*
X1087583Y381827D01*
X1087826Y382131D01*
Y382192D01*
X1088373Y382800D01*
X1088677Y383043D01*
X1089164Y383287D01*
X1089651Y383347D01*
X1089712Y383408D01*
X1090320Y383347D01*
X1090684Y383043D01*
X1090806Y382861D01*
X1090867Y382375D01*
X1090806Y381584D01*
X1090745Y381523D01*
X1090684Y380976D01*
X1090624Y380915D01*
X1090563Y380368D01*
X1090502Y380306D01*
X1090441Y379759D01*
X1090381Y379699D01*
X1090320Y379212D01*
X1090259Y379151D01*
X1090198Y378604D01*
X1090137Y378543D01*
X1090076Y378056D01*
X1090016Y377995D01*
X1089955Y377509D01*
X1089894Y377448D01*
X1089833Y376901D01*
X1089772Y376840D01*
X1089712Y376353D01*
X1089651Y376293D01*
X1089590Y375745D01*
X1089529Y375684D01*
X1089468Y375198D01*
X1089407Y375137D01*
X1089347Y374651D01*
X1089286Y374590D01*
X1089225Y374042D01*
X1089164Y373981D01*
Y373738D01*
X1094090D01*
X1094151Y374042D01*
X1094212Y374103D01*
X1094273Y374651D01*
X1094334Y374711D01*
X1094395Y375198D01*
X1094455Y375258D01*
X1094516Y375806D01*
X1094577Y375867D01*
X1094638Y376353D01*
X1094699Y376414D01*
X1094759Y376901D01*
X1094820Y376962D01*
X1094881Y377509D01*
X1094942Y377570D01*
X1095003Y378056D01*
X1095064Y378117D01*
X1095124Y378664D01*
X1095185Y378725D01*
X1095246Y379212D01*
X1095307Y379273D01*
X1095368Y379759D01*
X1095429Y379820D01*
X1095489Y380368D01*
X1095550Y380428D01*
X1095611Y380915D01*
X1095672Y380976D01*
X1095732Y381523D01*
X1095794Y381584D01*
X1095854Y382192D01*
X1095915Y382253D01*
X1095976Y382922D01*
X1096037Y382983D01*
X1096097Y383956D01*
X1096037Y384686D01*
X1095976Y384746D01*
X1095915Y385051D01*
X1095854Y385111D01*
X1095794Y385355D01*
X1095611Y385598D01*
Y385659D01*
X1095185Y386145D01*
X1094759Y386510D01*
X1094395Y386693D01*
X1094151Y386753D01*
X1094090Y386814D01*
X1093665Y386875D01*
X1093604Y386936D01*
X1092631Y386997D01*
X1091901D01*
X1091840Y386936D01*
G37*
G36*
G01X1112035Y-19527D02*
Y109220D01*
X1294535D01*
Y-19527D01*
X1112035D01*
G37*
G36*
G01X1114586Y389186D02*
X1114708Y388943D01*
X1114161D01*
X1114100Y389004D01*
X1113918Y389429D01*
X1113735Y389673D01*
Y389794D01*
X1113553Y389855D01*
X1113127Y389916D01*
Y388943D01*
X1112701D01*
Y390739D01*
X1113127D01*
Y390281D01*
X1113431D01*
X1114039Y390342D01*
X1114100Y390524D01*
X1114039Y390889D01*
X1113857D01*
X1113796Y390950D01*
X1113127D01*
Y390740D01*
X1112701D01*
Y391315D01*
X1113857D01*
X1114221Y391254D01*
X1114465Y391071D01*
X1114526Y390829D01*
X1114586Y390768D01*
X1114526Y390403D01*
X1114282Y390099D01*
X1114039Y390038D01*
X1113978Y389977D01*
X1114100Y389855D01*
X1114161D01*
X1114221Y389794D01*
X1114343Y389612D01*
X1114404Y389429D01*
X1114586Y389186D01*
G37*
G36*
G01X1115073Y388456D02*
X1114769Y388213D01*
X1114526Y388152D01*
X1114343Y388030D01*
X1113309Y387970D01*
X1113249Y388030D01*
X1112884Y388092D01*
X1112519Y388274D01*
X1112275Y388456D01*
X1111850Y388943D01*
X1111607Y389429D01*
X1111545Y390342D01*
X1111546Y390348D01*
X1111931D01*
X1111910Y390159D01*
X1111971Y389551D01*
X1112093Y389308D01*
X1112336Y389004D01*
Y388943D01*
X1112762Y388578D01*
X1113005Y388456D01*
X1113431Y388395D01*
X1113492Y388335D01*
X1114221Y388395D01*
X1114282Y388456D01*
X1114526Y388517D01*
X1114891Y388821D01*
X1115316Y389308D01*
X1115377Y389551D01*
X1115438Y389612D01*
X1115499Y390038D01*
X1115438Y390646D01*
X1115377Y390707D01*
X1115316Y390950D01*
X1115012Y391315D01*
Y391436D01*
X1114891D01*
X1114526Y391741D01*
X1114404D01*
X1114343Y391801D01*
X1113978Y391862D01*
X1113918Y391923D01*
X1113188Y391862D01*
X1113127Y391801D01*
X1112884Y391741D01*
X1112640Y391558D01*
X1112579D01*
X1112154Y391071D01*
X1111971Y390707D01*
X1111931Y390349D01*
X1111546D01*
X1111607Y390829D01*
X1111850Y391315D01*
X1112032Y391558D01*
X1112519Y391984D01*
X1112884Y392166D01*
X1113249Y392227D01*
X1113309Y392288D01*
X1114100D01*
X1114161Y392227D01*
X1114526Y392166D01*
X1114769Y392045D01*
X1115073Y391801D01*
X1115134D01*
X1115560Y391315D01*
X1115681Y391071D01*
X1115742Y390829D01*
X1115803Y390768D01*
X1115864Y389673D01*
X1115803Y389612D01*
X1115742Y389308D01*
X1115560Y388943D01*
X1115134Y388456D01*
X1115073D01*
G37*
G36*
G01X1157551Y192426D02*
Y168804D01*
X1283535D01*
Y192426D01*
X1157551D01*
G37*
G36*
G01X1264100Y373400D02*
X1293400D01*
Y359400D01*
X1264100D01*
Y373400D01*
G37*
G36*
G01X1284370Y179443D02*
Y184443D01*
X1286870Y181943D01*
X1284370Y179443D01*
G37*
G36*
G01X1304828Y710867D02*
X1334128D01*
Y696867D01*
X1304828D01*
Y710867D01*
G37*
G36*
G01X1323150Y277250D02*
Y273200D01*
X1327200Y277250D01*
X1323150D01*
G37*
G36*
G01X1354293Y155099D02*
Y164871D01*
X1365949D01*
Y155099D01*
X1354293D01*
G37*
%LPC*%
G75*
G36*
G01X621023Y-13780D02*
X580823D01*
Y-7780D01*
X511709D01*
Y109057D01*
X690137D01*
Y-6680D01*
X690123D01*
Y-7780D01*
X621023D01*
Y-13780D01*
G37*
G36*
G01X727067Y-13477D02*
X725312D01*
Y-10377D01*
X726799D01*
X727199Y-10549D01*
X727457Y-10807D01*
X727592Y-11212D01*
X727473Y-11630D01*
X727416Y-11724D01*
X727712Y-12020D01*
X727840Y-12469D01*
X727721Y-12888D01*
X727488Y-13235D01*
X727067Y-13477D01*
G37*
G36*
G01X722895Y-13177D02*
G02X722295I-300J0D01*
G01Y-10677D01*
G02X722895I300J0D01*
G01Y-11627D01*
X724045D01*
Y-10677D01*
G02X724645I300J0D01*
G01Y-13177D01*
G02X724045I-300J0D01*
G01Y-12227D01*
X722895D01*
Y-13177D01*
G37*
G36*
G01X717604Y-13477D02*
X717228D01*
X716861Y-13373D01*
X716503Y-13167D01*
X716190Y-12855D01*
X716027Y-12528D01*
X715924Y-12069D01*
X715976Y-11603D01*
X716176Y-11105D01*
X716439Y-10788D01*
X716800Y-10532D01*
X717263Y-10377D01*
X717687D01*
X718046Y-10479D01*
X718321Y-10617D01*
G02X718053Y-11153I-134J-268D01*
G01X717828Y-11041D01*
X717603Y-10977D01*
X717361D01*
X717074Y-11072D01*
X716851Y-11232D01*
X716698Y-11415D01*
X716564Y-11751D01*
X716532Y-12035D01*
X716597Y-12326D01*
X716684Y-12499D01*
X716871Y-12687D01*
X717095Y-12815D01*
X717312Y-12877D01*
X717520D01*
X717744Y-12813D01*
X717940Y-12715D01*
X718125Y-12568D01*
G02X718499Y-13036I187J-234D01*
G01X718266Y-13223D01*
X717962Y-13375D01*
X717604Y-13477D01*
G37*
G36*
G01X713387Y-13177D02*
G02X712787I-300J0D01*
G01Y-10677D01*
G02X713353Y-10539I300J0D01*
G01X714170Y-12110D01*
X714987Y-10539D01*
G02X715553Y-10677I266J-138D01*
G01Y-13177D01*
G02X714953I-300J0D01*
G01Y-11904D01*
X714436Y-12898D01*
G02X713904I-266J138D01*
G01X713387Y-11904D01*
Y-13177D01*
G37*
G36*
G01X711567Y-13477D02*
X709812D01*
Y-10377D01*
X711299D01*
X711699Y-10549D01*
X711957Y-10807D01*
X712092Y-11212D01*
X711973Y-11630D01*
X711916Y-11724D01*
X712212Y-12020D01*
X712340Y-12469D01*
X712221Y-12888D01*
X711988Y-13235D01*
X711567Y-13477D01*
G37*
G36*
G01X784121Y-15514D02*
X782155D01*
Y-12414D01*
X784121D01*
G02Y-13014I0J-300D01*
G01X782755D01*
Y-13622D01*
X783455D01*
G02Y-14222I0J-300D01*
G01X782755D01*
Y-14914D01*
X784121D01*
G02Y-15514I0J-300D01*
G37*
G36*
G01X779655Y-15214D02*
G02X779055I-300J0D01*
G01Y-12414D01*
X780450D01*
X780880Y-12575D01*
X781205Y-12835D01*
X781330Y-13339D01*
X781205Y-13839D01*
X780847Y-14139D01*
X780811Y-14155D01*
X781287Y-15076D01*
G02X780755Y-15352I-266J-138D01*
G01X780213Y-14306D01*
X779655D01*
Y-15214D01*
G37*
G36*
G01X774209Y-15514D02*
X773772D01*
X773317Y-15362D01*
X772954Y-15135D01*
G02X773272Y-14627I159J254D01*
G01X773575Y-14816D01*
X773870Y-14914D01*
X774101D01*
X774335Y-14826D01*
X774491Y-14697D01*
X774545Y-14569D01*
X774509Y-14440D01*
X774386Y-14293D01*
X774109Y-14171D01*
X773594Y-14084D01*
X773169Y-13842D01*
X772962Y-13359D01*
X773096Y-12890D01*
X773400Y-12586D01*
X773801Y-12414D01*
X774197D01*
X774590Y-12526D01*
X774888Y-12776D01*
G02X774504Y-13236I-192J-230D01*
G01X774302Y-13068D01*
X774113Y-13014D01*
X773925D01*
X773742Y-13092D01*
X773630Y-13204D01*
X773598Y-13319D01*
X773641Y-13420D01*
X773798Y-13510D01*
X774283Y-13591D01*
X774756Y-13801D01*
X775051Y-14154D01*
X775181Y-14609D01*
X774985Y-15065D01*
X774641Y-15352D01*
X774209Y-15514D01*
G37*
G36*
G01X770926Y-15512D02*
G02X770850I-38J298D01*
G01X770458Y-15462D01*
X770080Y-15247D01*
X769772Y-14940D01*
X769565Y-14577D01*
X769463Y-14168D01*
Y-13760D01*
X769565Y-13351D01*
X769772Y-12988D01*
X770080Y-12681D01*
X770458Y-12466D01*
X770888Y-12412D01*
X771318Y-12466D01*
X771696Y-12681D01*
X772004Y-12988D01*
X772211Y-13351D01*
X772313Y-13760D01*
Y-14168D01*
X772211Y-14577D01*
X772004Y-14940D01*
X771696Y-15247D01*
X771318Y-15462D01*
X770926Y-15512D01*
G37*
G36*
G01X768621Y-15514D02*
X766655D01*
Y-12714D01*
G02X767255I300J0D01*
G01Y-14914D01*
X768621D01*
G02Y-15514I0J-300D01*
G37*
G36*
G01X765022D02*
X764646D01*
X764279Y-15410D01*
X763921Y-15204D01*
X763608Y-14892D01*
X763445Y-14565D01*
X763342Y-14106D01*
X763394Y-13640D01*
X763594Y-13142D01*
X763857Y-12825D01*
X764218Y-12569D01*
X764681Y-12414D01*
X765105D01*
X765464Y-12516D01*
X765739Y-12654D01*
G02X765471Y-13190I-134J-268D01*
G01X765246Y-13078D01*
X765021Y-13014D01*
X764779D01*
X764492Y-13109D01*
X764269Y-13269D01*
X764116Y-13452D01*
X763982Y-13788D01*
X763950Y-14072D01*
X764015Y-14363D01*
X764102Y-14536D01*
X764289Y-14724D01*
X764513Y-14852D01*
X764730Y-14914D01*
X764938D01*
X765162Y-14850D01*
X765358Y-14752D01*
X765543Y-14605D01*
G02X765917Y-15073I187J-234D01*
G01X765684Y-15260D01*
X765380Y-15412D01*
X765022Y-15514D01*
G37*
G36*
G01X760930Y-15214D02*
G02X760330I-300J0D01*
G01Y-12714D01*
G02X760868Y-12532I300J0D01*
G01X762246Y-14329D01*
Y-12714D01*
G02X762846I300J0D01*
G01Y-15214D01*
G02X762308Y-15396I-300J0D01*
G01X760930Y-13599D01*
Y-15214D01*
G37*
G36*
G01X759321Y-15514D02*
X757355D01*
Y-12414D01*
X759321D01*
G02Y-13014I0J-300D01*
G01X757955D01*
Y-13622D01*
X758655D01*
G02Y-14222I0J-300D01*
G01X757955D01*
Y-14914D01*
X759321D01*
G02Y-15514I0J-300D01*
G37*
G36*
G01X777631Y-15412D02*
X777088Y-15520D01*
X776545Y-15412D01*
X776096Y-15074D01*
X775871Y-14570D01*
Y-12714D01*
G02X776471I300J0D01*
G01Y-14442D01*
X776580Y-14688D01*
X776797Y-14850D01*
X777088Y-14908D01*
X777379Y-14850D01*
X777596Y-14688D01*
X777705Y-14442D01*
Y-12714D01*
G02X778305I300J0D01*
G01Y-14570D01*
X778080Y-15074D01*
X777631Y-15412D01*
G37*
G36*
G01X827650Y-15300D02*
G02X827050I-300J0D01*
G01Y-14259D01*
X826260Y-12955D01*
G02X826774Y-12645I257J155D01*
G01X827350Y-13596D01*
X827926Y-12645D01*
G02X828440Y-12955I257J-155D01*
G01X827650Y-14259D01*
Y-15300D01*
G37*
G36*
G01X823758D02*
G02X823158I-300J0D01*
G01Y-12500D01*
X825042D01*
G02Y-13100I0J-300D01*
G01X823758D01*
Y-13708D01*
X824458D01*
G02Y-14308I0J-300D01*
G01X823758D01*
Y-15300D01*
G37*
G36*
G01X821650Y-15600D02*
X820650D01*
G02Y-15000I0J300D01*
G01X820850D01*
Y-13100D01*
X820650D01*
G02Y-12500I0J300D01*
G01X821650D01*
G02Y-13100I0J-300D01*
G01X821450D01*
Y-15000D01*
X821650D01*
G02Y-15600I0J-300D01*
G37*
G36*
G01X818350Y-15300D02*
G02X817750I-300J0D01*
G01Y-13100D01*
X817092D01*
G02Y-12500I0J300D01*
G01X819008D01*
G02Y-13100I0J-300D01*
G01X818350D01*
Y-15300D01*
G37*
G36*
G01X814292D02*
G02X813692I-300J0D01*
G01Y-12800D01*
G02X814230Y-12618I300J0D01*
G01X815608Y-14415D01*
Y-12800D01*
G02X816208I300J0D01*
G01Y-15300D01*
G02X815670Y-15482I-300J0D01*
G01X814292Y-13685D01*
Y-15300D01*
G37*
G36*
G01X812683Y-15600D02*
X810717D01*
Y-12500D01*
X812683D01*
G02Y-13100I0J-300D01*
G01X811317D01*
Y-13708D01*
X812017D01*
G02Y-14308I0J-300D01*
G01X811317D01*
Y-15000D01*
X812683D01*
G02Y-15600I0J-300D01*
G37*
G36*
G01X808721D02*
X807833D01*
G02X807533Y-15300I0J300D01*
G01Y-12500D01*
X808721D01*
X809138Y-12656D01*
X809453Y-12867D01*
X809705Y-13170D01*
X809917Y-13539D01*
X809969Y-14050D01*
X809917Y-14561D01*
X809705Y-14930D01*
X809453Y-15233D01*
X809138Y-15444D01*
X808721Y-15600D01*
G37*
G36*
G01X806150D02*
X805150D01*
G02Y-15000I0J300D01*
G01X805350D01*
Y-13100D01*
X805150D01*
G02Y-12500I0J300D01*
G01X806150D01*
G02Y-13100I0J-300D01*
G01X805950D01*
Y-15000D01*
X806150D01*
G02Y-15600I0J-300D01*
G37*
G36*
G01X798917Y-15300D02*
G02X798317I-300J0D01*
G01Y-12500D01*
X799712D01*
X800142Y-12661D01*
X800467Y-12921D01*
X800592Y-13425D01*
X800467Y-13925D01*
X800109Y-14225D01*
X800073Y-14241D01*
X800549Y-15162D01*
G02X800017Y-15438I-266J-138D01*
G01X799475Y-14392D01*
X798917D01*
Y-15300D01*
G37*
G36*
G01X795973Y-15377D02*
G02X795391Y-15368I-290J77D01*
G01X794808Y-12868D01*
G02X795392Y-12732I292J68D01*
G01X795703Y-14063D01*
X796060Y-12723D01*
G02X796640I290J-77D01*
G01X796997Y-14063D01*
X797308Y-12732D01*
G02X797892Y-12868I292J-68D01*
G01X797309Y-15368D01*
G02X796727Y-15377I-292J68D01*
G01X796350Y-13964D01*
X795973Y-15377D01*
G37*
G36*
G01X792717Y-15300D02*
G02X792117I-300J0D01*
G01Y-12500D01*
X793471D01*
X793928Y-12671D01*
X794274Y-13076D01*
X794392Y-13550D01*
X794275Y-14022D01*
X793968Y-14391D01*
X793466Y-14558D01*
X792717D01*
Y-15300D01*
G37*
G36*
G01X858906Y-15718D02*
X857024D01*
Y-12418D01*
X858631D01*
X859068Y-12606D01*
X859357Y-12894D01*
X859509Y-13351D01*
X859377Y-13811D01*
X859354Y-13850D01*
X859613Y-14109D01*
X859756Y-14610D01*
X859624Y-15071D01*
X859370Y-15451D01*
X858906Y-15718D01*
G37*
G36*
G01X854607Y-15318D02*
G02X853807I-400J0D01*
G01Y-12818D01*
G02X854607I400J0D01*
G01Y-13668D01*
X855557D01*
Y-12818D01*
G02X856357I400J0D01*
G01Y-15318D01*
G02X855557I-400J0D01*
G01Y-14468D01*
X854607D01*
Y-15318D01*
G37*
G36*
G01X848007D02*
G02X847207I-400J0D01*
G01Y-12818D01*
G02X848007I400J0D01*
G01Y-13668D01*
X848957D01*
Y-12818D01*
G02X849757I400J0D01*
G01Y-15318D01*
G02X848957I-400J0D01*
G01Y-14468D01*
X848007D01*
Y-15318D01*
G37*
G36*
G01X845530Y-15718D02*
X845126D01*
X844733Y-15606D01*
X844354Y-15388D01*
X844020Y-15055D01*
X843844Y-14703D01*
X843735Y-14215D01*
X843791Y-13720D01*
X844001Y-13194D01*
X844283Y-12855D01*
X844666Y-12582D01*
X845159Y-12418D01*
X845613D01*
X845994Y-12526D01*
X846278Y-12668D01*
G02X845920Y-13384I-179J-358D01*
G01X845704Y-13276D01*
X845501Y-13218D01*
X845289D01*
X845032Y-13304D01*
X844831Y-13447D01*
X844697Y-13608D01*
X844573Y-13916D01*
X844545Y-14171D01*
X844604Y-14433D01*
X844678Y-14581D01*
X844844Y-14748D01*
X845047Y-14864D01*
X845238Y-14918D01*
X845418D01*
X845619Y-14861D01*
X845798Y-14771D01*
X845974Y-14631D01*
G02X846474Y-15255I250J-312D01*
G01X846232Y-15449D01*
X845911Y-15609D01*
X845530Y-15718D01*
G37*
G36*
G01X842282Y-15318D02*
G02X841482I-400J0D01*
G01Y-13218D01*
X840924D01*
G02Y-12418I0J400D01*
G01X842840D01*
G02Y-13218I0J-400D01*
G01X842282D01*
Y-15318D01*
G37*
G36*
G01X839082Y-15718D02*
X838082D01*
G02Y-14918I0J400D01*
G01X838182D01*
Y-13218D01*
X838082D01*
G02Y-12418I0J400D01*
G01X839082D01*
G02Y-13218I0J-400D01*
G01X838982D01*
Y-14918D01*
X839082D01*
G02Y-15718I0J-400D01*
G37*
G36*
G01X835001Y-15421D02*
G02X834225Y-15409I-386J103D01*
G01X833642Y-12909D01*
G02X834422Y-12727I390J91D01*
G01X834641Y-13669D01*
X834896Y-12715D01*
G02X835668I386J-103D01*
G01X835923Y-13669D01*
X836142Y-12727D01*
G02X836922Y-12909I390J-91D01*
G01X836339Y-15409D01*
G02X835563Y-15421I-390J91D01*
G01X835282Y-14370D01*
X835001Y-15421D01*
G37*
G36*
G01X832222Y-15718D02*
X831750D01*
X831268Y-15557D01*
X830895Y-15324D01*
G02X831319Y-14646I212J339D01*
G01X831612Y-14829D01*
X831880Y-14918D01*
X832076D01*
X832278Y-14842D01*
X832402Y-14739D01*
X832433Y-14666D01*
X832413Y-14592D01*
X832318Y-14479D01*
X832074Y-14371D01*
X831554Y-14284D01*
X831084Y-14016D01*
X830850Y-13470D01*
X831001Y-12942D01*
X831337Y-12606D01*
X831775Y-12418D01*
X832205D01*
X832631Y-12540D01*
X832947Y-12803D01*
G02X832433Y-13417I-257J-307D01*
G01X832249Y-13262D01*
X832093Y-13218D01*
X831939D01*
X831793Y-13280D01*
X831713Y-13360D01*
X831698Y-13416D01*
X831714Y-13454D01*
X831826Y-13518D01*
X832306Y-13599D01*
X832812Y-13823D01*
X833135Y-14210D01*
X833281Y-14720D01*
X833062Y-15231D01*
X832686Y-15544D01*
X832222Y-15718D01*
G37*
G36*
G01X883526Y-15156D02*
G02X883260I-133J269D01*
G01X883177Y-15115D01*
G02X883010Y-14846I133J269D01*
G01Y-14762D01*
G02X883177Y-14493I300J0D01*
G01X883260Y-14452D01*
G02X883526I133J-269D01*
G01X883609Y-14493D01*
G02X883776Y-14762I-133J-269D01*
G01Y-14846D01*
G02X883609Y-15115I-300J0D01*
G01X883526Y-15156D01*
G37*
G36*
G01X893027Y-16229D02*
X892651D01*
X892284Y-16125D01*
X891926Y-15919D01*
X891613Y-15607D01*
X891450Y-15280D01*
X891347Y-14821D01*
X891399Y-14355D01*
X891599Y-13857D01*
X891862Y-13540D01*
X892223Y-13284D01*
X892686Y-13129D01*
X893110D01*
X893469Y-13231D01*
X893744Y-13369D01*
G02X893476Y-13905I-134J-268D01*
G01X893251Y-13793D01*
X893026Y-13729D01*
X892784D01*
X892497Y-13824D01*
X892274Y-13984D01*
X892121Y-14167D01*
X891987Y-14503D01*
X891955Y-14787D01*
X892020Y-15078D01*
X892107Y-15251D01*
X892294Y-15439D01*
X892518Y-15567D01*
X892735Y-15629D01*
X892943D01*
X893167Y-15565D01*
X893363Y-15467D01*
X893548Y-15320D01*
G02X893922Y-15788I187J-234D01*
G01X893689Y-15975D01*
X893385Y-16127D01*
X893027Y-16229D01*
G37*
G36*
G01X888810Y-15929D02*
G02X888210I-300J0D01*
G01Y-13429D01*
G02X888776Y-13291I300J0D01*
G01X889593Y-14862D01*
X890410Y-13291D01*
G02X890976Y-13429I266J-138D01*
G01Y-15929D01*
G02X890376I-300J0D01*
G01Y-14656D01*
X889859Y-15650D01*
G02X889327I-266J138D01*
G01X888810Y-14656D01*
Y-15929D01*
G37*
G36*
G01X886990Y-16229D02*
X885235D01*
Y-13129D01*
X886722D01*
X887122Y-13301D01*
X887380Y-13559D01*
X887515Y-13964D01*
X887396Y-14382D01*
X887339Y-14476D01*
X887635Y-14772D01*
X887763Y-15221D01*
X887644Y-15640D01*
X887411Y-15987D01*
X886990Y-16229D01*
G37*
G36*
G01X879801Y-15929D02*
G02X879201I-300J0D01*
G01Y-13129D01*
X881085D01*
G02Y-13729I0J-300D01*
G01X879801D01*
Y-14337D01*
X880501D01*
G02Y-14937I0J-300D01*
G01X879801D01*
Y-15929D01*
G37*
G36*
G01X876701D02*
G02X876101I-300J0D01*
G01Y-13129D01*
X877985D01*
G02Y-13729I0J-300D01*
G01X876701D01*
Y-14337D01*
X877401D01*
G02Y-14937I0J-300D01*
G01X876701D01*
Y-15929D01*
G37*
G36*
G01X874131Y-16227D02*
G02X874055I-38J298D01*
G01X873663Y-16177D01*
X873285Y-15962D01*
X872977Y-15655D01*
X872770Y-15292D01*
X872668Y-14883D01*
Y-14475D01*
X872770Y-14066D01*
X872977Y-13703D01*
X873285Y-13396D01*
X873663Y-13181D01*
X874093Y-13127D01*
X874523Y-13181D01*
X874901Y-13396D01*
X875209Y-13703D01*
X875416Y-14066D01*
X875518Y-14475D01*
Y-14883D01*
X875416Y-15292D01*
X875209Y-15655D01*
X874901Y-15962D01*
X874523Y-16177D01*
X874131Y-16227D01*
G37*
G36*
G01X883526Y-16281D02*
G02X883260I-133J269D01*
G01X883177Y-16240D01*
G02X883010Y-15971I133J269D01*
G01Y-15887D01*
G02X883177Y-15618I300J0D01*
G01X883260Y-15577D01*
G02X883526I133J-269D01*
G01X883609Y-15618D01*
G02X883776Y-15887I-133J-269D01*
G01Y-15971D01*
G02X883609Y-16240I-300J0D01*
G01X883526Y-16281D01*
G37*
G36*
G01X880284Y-10570D02*
G02X880018I-133J269D01*
G01X879935Y-10529D01*
G02X879768Y-10260I133J269D01*
G01Y-10176D01*
G02X879935Y-9907I300J0D01*
G01X880018Y-9866D01*
G02X880284I133J-269D01*
G01X880367Y-9907D01*
G02X880534Y-10176I-133J-269D01*
G01Y-10260D01*
G02X880367Y-10529I-300J0D01*
G01X880284Y-10570D01*
G37*
G36*
G01X898176Y-11343D02*
G02X897576I-300J0D01*
G01Y-8843D01*
G02X898176I300J0D01*
G01Y-9793D01*
X899326D01*
Y-8843D01*
G02X899926I300J0D01*
G01Y-11343D01*
G02X899326I-300J0D01*
G01Y-10393D01*
X898176D01*
Y-11343D01*
G37*
G36*
G01X895985Y-11643D02*
X895609D01*
X895242Y-11539D01*
X894884Y-11333D01*
X894571Y-11021D01*
X894408Y-10694D01*
X894305Y-10235D01*
X894357Y-9769D01*
X894557Y-9271D01*
X894820Y-8954D01*
X895181Y-8698D01*
X895644Y-8543D01*
X896068D01*
X896427Y-8645D01*
X896702Y-8783D01*
G02X896434Y-9319I-134J-268D01*
G01X896209Y-9207D01*
X895984Y-9143D01*
X895742D01*
X895455Y-9238D01*
X895232Y-9398D01*
X895079Y-9581D01*
X894945Y-9917D01*
X894913Y-10201D01*
X894978Y-10492D01*
X895065Y-10665D01*
X895252Y-10853D01*
X895476Y-10981D01*
X895693Y-11043D01*
X895901D01*
X896125Y-10979D01*
X896321Y-10881D01*
X896506Y-10734D01*
G02X896880Y-11202I187J-234D01*
G01X896647Y-11389D01*
X896343Y-11541D01*
X895985Y-11643D01*
G37*
G36*
G01X892851Y-11343D02*
G02X892251I-300J0D01*
G01Y-9143D01*
X891593D01*
G02Y-8543I0J300D01*
G01X893509D01*
G02Y-9143I0J-300D01*
G01X892851D01*
Y-11343D01*
G37*
G36*
G01X889951Y-11643D02*
X888951D01*
G02Y-11043I0J300D01*
G01X889151D01*
Y-9143D01*
X888951D01*
G02Y-8543I0J300D01*
G01X889951D01*
G02Y-9143I0J-300D01*
G01X889751D01*
Y-11043D01*
X889951D01*
G02Y-11643I0J-300D01*
G37*
G36*
G01X885974Y-11420D02*
G02X885392Y-11411I-290J77D01*
G01X884809Y-8911D01*
G02X885393Y-8775I292J68D01*
G01X885704Y-10106D01*
X886061Y-8766D01*
G02X886641I290J-77D01*
G01X886998Y-10106D01*
X887309Y-8775D01*
G02X887893Y-8911I292J-68D01*
G01X887310Y-11411D01*
G02X886728Y-11420I-292J68D01*
G01X886351Y-10007D01*
X885974Y-11420D01*
G37*
G36*
G01X883472Y-11643D02*
X883035D01*
X882580Y-11491D01*
X882217Y-11264D01*
G02X882535Y-10756I159J254D01*
G01X882838Y-10945D01*
X883133Y-11043D01*
X883364D01*
X883598Y-10955D01*
X883754Y-10826D01*
X883808Y-10698D01*
X883772Y-10569D01*
X883649Y-10422D01*
X883372Y-10300D01*
X882857Y-10213D01*
X882432Y-9971D01*
X882225Y-9488D01*
X882359Y-9019D01*
X882663Y-8715D01*
X883064Y-8543D01*
X883460D01*
X883853Y-8655D01*
X884151Y-8905D01*
G02X883767Y-9365I-192J-230D01*
G01X883565Y-9197D01*
X883376Y-9143D01*
X883188D01*
X883005Y-9221D01*
X882893Y-9333D01*
X882861Y-9448D01*
X882904Y-9549D01*
X883061Y-9639D01*
X883546Y-9720D01*
X884019Y-9930D01*
X884314Y-10283D01*
X884444Y-10738D01*
X884248Y-11194D01*
X883904Y-11481D01*
X883472Y-11643D01*
G37*
G36*
G01X876393Y-11343D02*
G02X875793I-300J0D01*
G01Y-8843D01*
G02X876331Y-8661I300J0D01*
G01X877709Y-10458D01*
Y-8843D01*
G02X878309I300J0D01*
G01Y-11343D01*
G02X877771Y-11525I-300J0D01*
G01X876393Y-9728D01*
Y-11343D01*
G37*
G36*
G01X873989Y-11641D02*
G02X873913I-38J298D01*
G01X873521Y-11591D01*
X873143Y-11376D01*
X872835Y-11069D01*
X872628Y-10706D01*
X872526Y-10297D01*
Y-9889D01*
X872628Y-9480D01*
X872835Y-9117D01*
X873143Y-8810D01*
X873521Y-8595D01*
X873951Y-8541D01*
X874381Y-8595D01*
X874759Y-8810D01*
X875067Y-9117D01*
X875274Y-9480D01*
X875376Y-9889D01*
Y-10297D01*
X875274Y-10706D01*
X875067Y-11069D01*
X874759Y-11376D01*
X874381Y-11591D01*
X873989Y-11641D01*
G37*
G36*
G01X880284Y-11695D02*
G02X880018I-133J269D01*
G01X879935Y-11654D01*
G02X879768Y-11385I133J269D01*
G01Y-11301D01*
G02X879935Y-11032I300J0D01*
G01X880018Y-10991D01*
G02X880284I133J-269D01*
G01X880367Y-11032D01*
G02X880534Y-11301I-133J-269D01*
G01Y-11385D01*
G02X880367Y-11654I-300J0D01*
G01X880284Y-11695D01*
G37*
G36*
G01X895522Y-7486D02*
X894634D01*
G02X894334Y-7186I0J300D01*
G01Y-4386D01*
X895522D01*
X895939Y-4542D01*
X896254Y-4753D01*
X896506Y-5056D01*
X896718Y-5425D01*
X896770Y-5936D01*
X896718Y-6447D01*
X896506Y-6816D01*
X896254Y-7119D01*
X895939Y-7330D01*
X895522Y-7486D01*
G37*
G36*
G01X893284D02*
X891318D01*
Y-4386D01*
X893284D01*
G02Y-4986I0J-300D01*
G01X891918D01*
Y-5594D01*
X892618D01*
G02Y-6194I0J-300D01*
G01X891918D01*
Y-6886D01*
X893284D01*
G02Y-7486I0J-300D01*
G37*
G36*
G01X890184D02*
X888218D01*
Y-4686D01*
G02X888818I300J0D01*
G01Y-6886D01*
X890184D01*
G02Y-7486I0J-300D01*
G37*
G36*
G01X883451Y-7186D02*
G02X882851I-300J0D01*
G01Y-4986D01*
X882193D01*
G02Y-4386I0J300D01*
G01X884109D01*
G02Y-4986I0J-300D01*
G01X883451D01*
Y-7186D01*
G37*
G36*
G01X879518D02*
G02X878918I-300J0D01*
G01Y-4386D01*
X880313D01*
X880743Y-4547D01*
X881068Y-4807D01*
X881193Y-5311D01*
X881068Y-5811D01*
X880710Y-6111D01*
X880674Y-6127D01*
X881150Y-7048D01*
G02X880618Y-7324I-266J-138D01*
G01X880076Y-6278D01*
X879518D01*
Y-7186D01*
G37*
G36*
G01X876186Y-7301D02*
G02X875632Y-7071I-277J115D01*
G01X876674Y-4571D01*
G02X877228I277J-115D01*
G01X878270Y-7071D01*
G02X877716Y-7301I-277J-115D01*
G01X877428Y-6611D01*
X876474D01*
X876186Y-7301D01*
G37*
G36*
G01X874394Y-7384D02*
X873851Y-7492D01*
X873308Y-7384D01*
X872859Y-7046D01*
X872634Y-6542D01*
Y-4686D01*
G02X873234I300J0D01*
G01Y-6414D01*
X873343Y-6660D01*
X873560Y-6822D01*
X873851Y-6880D01*
X874142Y-6822D01*
X874359Y-6660D01*
X874468Y-6414D01*
Y-4686D01*
G02X875068I300J0D01*
G01Y-6542D01*
X874843Y-7046D01*
X874394Y-7384D01*
G37*
G36*
G01X1223385Y-13780D02*
X1183185D01*
Y-7780D01*
X1114071D01*
Y109057D01*
X1292499D01*
Y-6680D01*
X1292485D01*
Y-7780D01*
X1223385D01*
Y-13780D01*
G37*
G36*
G01X1363546Y160858D02*
G02X1362946I-300J0D01*
G01Y163058D01*
X1362288D01*
G02Y163658I0J300D01*
G01X1364204D01*
G02Y163058I0J-300D01*
G01X1363546D01*
Y160858D01*
G37*
G36*
G01X1360367Y160558D02*
X1359930D01*
X1359475Y160710D01*
X1359112Y160937D01*
G02X1359430Y161445I159J254D01*
G01X1359733Y161256D01*
X1360028Y161158D01*
X1360259D01*
X1360493Y161246D01*
X1360649Y161375D01*
X1360703Y161503D01*
X1360667Y161632D01*
X1360544Y161779D01*
X1360267Y161901D01*
X1359752Y161988D01*
X1359327Y162230D01*
X1359120Y162713D01*
X1359254Y163182D01*
X1359558Y163486D01*
X1359959Y163658D01*
X1360355D01*
X1360748Y163546D01*
X1361046Y163296D01*
G02X1360662Y162836I-192J-230D01*
G01X1360460Y163004D01*
X1360271Y163058D01*
X1360083D01*
X1359900Y162980D01*
X1359788Y162868D01*
X1359756Y162753D01*
X1359799Y162652D01*
X1359956Y162562D01*
X1360441Y162481D01*
X1360914Y162271D01*
X1361209Y161918D01*
X1361339Y161463D01*
X1361143Y161007D01*
X1360799Y160720D01*
X1360367Y160558D01*
G37*
G36*
G01X1356513Y160858D02*
G02X1355913I-300J0D01*
G01Y163658D01*
X1357308D01*
X1357738Y163497D01*
X1358063Y163237D01*
X1358188Y162733D01*
X1358063Y162233D01*
X1357705Y161933D01*
X1357669Y161917D01*
X1358145Y160996D01*
G02X1357613Y160720I-266J-138D01*
G01X1357071Y161766D01*
X1356513D01*
Y160858D01*
G37*
G36*
G01X1362588Y156058D02*
G02X1361988I-300J0D01*
G01Y158558D01*
G02X1362526Y158740I300J0D01*
G01X1363904Y156943D01*
Y158558D01*
G02X1364504I300J0D01*
G01Y156058D01*
G02X1363966Y155876I-300J0D01*
G01X1362588Y157673D01*
Y156058D01*
G37*
G36*
G01X1360446D02*
G02X1359846I-300J0D01*
G01Y158258D01*
X1359188D01*
G02Y158858I0J300D01*
G01X1361104D01*
G02Y158258I0J-300D01*
G01X1360446D01*
Y156058D01*
G37*
G36*
G01X1357543Y155758D02*
X1355788D01*
Y158858D01*
X1357275D01*
X1357675Y158686D01*
X1357933Y158428D01*
X1358068Y158023D01*
X1357949Y157605D01*
X1357892Y157511D01*
X1358188Y157215D01*
X1358316Y156766D01*
X1358197Y156347D01*
X1357964Y156000D01*
X1357543Y155758D01*
G37*
%LPD*%
G75*
G36*
G01X536963Y-6280D02*
G02X534963I-1000J0D01*
G01Y-4280D01*
G02X536963I1000J0D01*
G01Y-6280D01*
G37*
G36*
G01X534010D02*
G02X532010I-1000J0D01*
G01Y-4280D01*
G02X534010I1000J0D01*
G01Y-6280D01*
G37*
G36*
G01X531057D02*
G02X529057I-1000J0D01*
G01Y-4280D01*
G02X531057I1000J0D01*
G01Y-6280D01*
G37*
G36*
G01X528104D02*
G02X526104I-1000J0D01*
G01Y-4280D01*
G02X528104I1000J0D01*
G01Y-6280D01*
G37*
G36*
G01X525151D02*
G02X523151I-1000J0D01*
G01Y-4280D01*
G02X525151I1000J0D01*
G01Y-6280D01*
G37*
G36*
G01X515309D02*
G02X513309I-1000J0D01*
G01Y-4280D01*
G02X515309I1000J0D01*
G01Y-6280D01*
G37*
G36*
G01X571411D02*
G02X569411I-1000J0D01*
G01Y-4280D01*
G02X571411I1000J0D01*
G01Y-6280D01*
G37*
G36*
G01X568458D02*
G02X566458I-1000J0D01*
G01Y-4280D01*
G02X568458I1000J0D01*
G01Y-6280D01*
G37*
G36*
G01X558616D02*
G02X556616I-1000J0D01*
G01Y-4280D01*
G02X558616I1000J0D01*
G01Y-6280D01*
G37*
G36*
G01X548775D02*
G02X546775I-1000J0D01*
G01Y-4280D01*
G02X548775I1000J0D01*
G01Y-6280D01*
G37*
G36*
G01X545822D02*
G02X543822I-1000J0D01*
G01Y-4280D01*
G02X545822I1000J0D01*
G01Y-6280D01*
G37*
G36*
G01X539916D02*
G02X537916I-1000J0D01*
G01Y-4280D01*
G02X539916I1000J0D01*
G01Y-6280D01*
G37*
G36*
G01X542869D02*
G02X540869I-1000J0D01*
G01Y-4280D01*
G02X542869I1000J0D01*
G01Y-6280D01*
G37*
G36*
G01X536923Y105520D02*
G02Y107520I0J1000D01*
G01X540923D01*
G02Y105520I0J-1000D01*
G01X536923D01*
G37*
G36*
G01X601923Y-6280D02*
G02X599923I-1000J0D01*
G01Y-4280D01*
G02X601923I1000J0D01*
G01Y-6280D01*
G37*
G36*
G01X574364D02*
G02X572364I-1000J0D01*
G01Y-4280D01*
G02X574364I1000J0D01*
G01Y-6280D01*
G37*
G36*
G01X577317D02*
G02X575317I-1000J0D01*
G01Y-4280D01*
G02X577317I1000J0D01*
G01Y-6280D01*
G37*
G36*
G01X580270D02*
G02X578270I-1000J0D01*
G01Y-4280D01*
G02X580270I1000J0D01*
G01Y-6280D01*
G37*
G36*
G01X586176D02*
G02X584176I-1000J0D01*
G01Y-4280D01*
G02X586176I1000J0D01*
G01Y-6280D01*
G37*
G36*
G01X583223D02*
G02X581223I-1000J0D01*
G01Y-4280D01*
G02X583223I1000J0D01*
G01Y-6280D01*
G37*
G36*
G01X589129D02*
G02X587129I-1000J0D01*
G01Y-4280D01*
G02X589129I1000J0D01*
G01Y-6280D01*
G37*
G36*
G01X592082D02*
G02X590082I-1000J0D01*
G01Y-4280D01*
G02X592082I1000J0D01*
G01Y-6280D01*
G37*
G36*
G01X579923Y105520D02*
G02Y107520I0J1000D01*
G01X583923D01*
G02Y105520I0J-1000D01*
G01X579923D01*
G37*
G36*
G01X614718Y-6280D02*
G02X612718I-1000J0D01*
G01Y-4280D01*
G02X614718I1000J0D01*
G01Y-6280D01*
G37*
G36*
G01X617671D02*
G02X615671I-1000J0D01*
G01Y-4280D01*
G02X617671I1000J0D01*
G01Y-6280D01*
G37*
G36*
G01X620624D02*
G02X618624I-1000J0D01*
G01Y-4280D01*
G02X620624I1000J0D01*
G01Y-6280D01*
G37*
G36*
G01X623577D02*
G02X621577I-1000J0D01*
G01Y-4280D01*
G02X623577I1000J0D01*
G01Y-6280D01*
G37*
G36*
G01X629483D02*
G02X627483I-1000J0D01*
G01Y-4280D01*
G02X629483I1000J0D01*
G01Y-6280D01*
G37*
G36*
G01X626530D02*
G02X624530I-1000J0D01*
G01Y-4280D01*
G02X626530I1000J0D01*
G01Y-6280D01*
G37*
G36*
G01X632436D02*
G02X630436I-1000J0D01*
G01Y-4280D01*
G02X632436I1000J0D01*
G01Y-6280D01*
G37*
G36*
G01X635389D02*
G02X633389I-1000J0D01*
G01Y-4280D01*
G02X635389I1000J0D01*
G01Y-6280D01*
G37*
G36*
G01X611765D02*
G02X609765I-1000J0D01*
G01Y-4280D01*
G02X611765I1000J0D01*
G01Y-6280D01*
G37*
G36*
G01X623923Y105520D02*
G02Y107520I0J1000D01*
G01X627923D01*
G02Y105520I0J-1000D01*
G01X623923D01*
G37*
G36*
G01X658025Y-6280D02*
G02X656025I-1000J0D01*
G01Y-4280D01*
G02X658025I1000J0D01*
G01Y-6280D01*
G37*
G36*
G01X660978D02*
G02X658978I-1000J0D01*
G01Y-4280D01*
G02X660978I1000J0D01*
G01Y-6280D01*
G37*
G36*
G01X663931D02*
G02X661931I-1000J0D01*
G01Y-4280D01*
G02X663931I1000J0D01*
G01Y-6280D01*
G37*
G36*
G01X666884D02*
G02X664884I-1000J0D01*
G01Y-4280D01*
G02X666884I1000J0D01*
G01Y-6280D01*
G37*
G36*
G01X672790D02*
G02X670790I-1000J0D01*
G01Y-4280D01*
G02X672790I1000J0D01*
G01Y-6280D01*
G37*
G36*
G01X669837D02*
G02X667837I-1000J0D01*
G01Y-4280D01*
G02X669837I1000J0D01*
G01Y-6280D01*
G37*
G36*
G01X655072D02*
G02X653072I-1000J0D01*
G01Y-4280D01*
G02X655072I1000J0D01*
G01Y-6280D01*
G37*
G36*
G01X645230D02*
G02X643230I-1000J0D01*
G01Y-4280D01*
G02X645230I1000J0D01*
G01Y-6280D01*
G37*
G36*
G01X666923Y105520D02*
G02Y107520I0J1000D01*
G01X670923D01*
G02Y105520I0J-1000D01*
G01X666923D01*
G37*
G36*
G01X688537Y-6280D02*
G02X686537I-1000J0D01*
G01Y-4280D01*
G02X688537I1000J0D01*
G01Y-6280D01*
G37*
G36*
G01X675743D02*
G02X673743I-1000J0D01*
G01Y-4280D01*
G02X675743I1000J0D01*
G01Y-6280D01*
G37*
G36*
G01X678696D02*
G02X676696I-1000J0D01*
G01Y-4280D01*
G02X678696I1000J0D01*
G01Y-6280D01*
G37*
G36*
G01X725912Y-11544D02*
Y-10977D01*
X726675D01*
X726857Y-11055D01*
X726933Y-11131D01*
X726964Y-11226D01*
X726917Y-11390D01*
X726843Y-11514D01*
X726803Y-11544D01*
X725912D01*
G37*
G36*
G01X710412D02*
Y-10977D01*
X711175D01*
X711357Y-11055D01*
X711433Y-11131D01*
X711464Y-11226D01*
X711417Y-11390D01*
X711343Y-11514D01*
X711303Y-11544D01*
X710412D01*
G37*
G36*
G01X725912Y-12877D02*
Y-12144D01*
X726861D01*
X727038Y-12194D01*
X727178Y-12334D01*
X727216Y-12469D01*
X727169Y-12632D01*
X727068Y-12785D01*
X726907Y-12877D01*
X725912D01*
G37*
G36*
G01X710412D02*
Y-12144D01*
X711361D01*
X711538Y-12194D01*
X711678Y-12334D01*
X711716Y-12469D01*
X711669Y-12632D01*
X711568Y-12785D01*
X711407Y-12877D01*
X710412D01*
G37*
G36*
G01X770888Y-14912D02*
X770652Y-14882D01*
X770446Y-14765D01*
X770254Y-14572D01*
X770127Y-14351D01*
X770063Y-14094D01*
Y-13834D01*
X770127Y-13577D01*
X770254Y-13356D01*
X770446Y-13163D01*
X770652Y-13046D01*
X770888Y-13016D01*
X771124Y-13046D01*
X771330Y-13163D01*
X771522Y-13356D01*
X771649Y-13577D01*
X771713Y-13834D01*
Y-14094D01*
X771649Y-14351D01*
X771522Y-14572D01*
X771330Y-14765D01*
X771124Y-14882D01*
X770888Y-14912D01*
G37*
G36*
G01X779655Y-13706D02*
Y-13014D01*
X780342D01*
X780580Y-13103D01*
X780671Y-13177D01*
X780712Y-13339D01*
X780671Y-13505D01*
X780529Y-13623D01*
X780334Y-13706D01*
X779655D01*
G37*
G36*
G01X798917Y-13792D02*
Y-13100D01*
X799604D01*
X799842Y-13189D01*
X799933Y-13263D01*
X799974Y-13425D01*
X799933Y-13591D01*
X799791Y-13709D01*
X799596Y-13792D01*
X798917D01*
G37*
G36*
G01X792717Y-13958D02*
Y-13100D01*
X793363D01*
X793572Y-13179D01*
X793726Y-13358D01*
X793774Y-13550D01*
X793725Y-13744D01*
X793616Y-13875D01*
X793368Y-13958D01*
X792717D01*
G37*
G36*
G01X808133Y-15000D02*
Y-13100D01*
X808613D01*
X808862Y-13194D01*
X809047Y-13317D01*
X809211Y-13514D01*
X809333Y-13727D01*
X809365Y-14050D01*
X809333Y-14373D01*
X809211Y-14586D01*
X809047Y-14783D01*
X808862Y-14906D01*
X808613Y-15000D01*
X808133D01*
G37*
G36*
G01X874093Y-15627D02*
X873857Y-15597D01*
X873651Y-15480D01*
X873459Y-15287D01*
X873332Y-15066D01*
X873268Y-14809D01*
Y-14549D01*
X873332Y-14292D01*
X873459Y-14071D01*
X873651Y-13878D01*
X873857Y-13761D01*
X874093Y-13731D01*
X874329Y-13761D01*
X874535Y-13878D01*
X874727Y-14071D01*
X874854Y-14292D01*
X874918Y-14549D01*
Y-14809D01*
X874854Y-15066D01*
X874727Y-15287D01*
X874535Y-15480D01*
X874329Y-15597D01*
X874093Y-15627D01*
G37*
G36*
G01X873951Y-11041D02*
X873715Y-11011D01*
X873509Y-10894D01*
X873317Y-10701D01*
X873190Y-10480D01*
X873126Y-10223D01*
Y-9963D01*
X873190Y-9706D01*
X873317Y-9485D01*
X873509Y-9292D01*
X873715Y-9175D01*
X873951Y-9145D01*
X874187Y-9175D01*
X874393Y-9292D01*
X874585Y-9485D01*
X874712Y-9706D01*
X874776Y-9963D01*
Y-10223D01*
X874712Y-10480D01*
X874585Y-10701D01*
X874393Y-10894D01*
X874187Y-11011D01*
X873951Y-11041D01*
G37*
G36*
G01X857824Y-14918D02*
Y-14385D01*
X858659D01*
X858798Y-14424D01*
X858901Y-14527D01*
X858924Y-14610D01*
X858890Y-14731D01*
X858810Y-14851D01*
X858692Y-14918D01*
X857824D01*
G37*
G36*
G01Y-13585D02*
Y-13218D01*
X858467D01*
X858612Y-13280D01*
X858657Y-13326D01*
X858671Y-13369D01*
X858637Y-13491D01*
X858580Y-13585D01*
X857824D01*
G37*
G36*
G01X885835Y-14296D02*
Y-13729D01*
X886598D01*
X886780Y-13807D01*
X886856Y-13883D01*
X886887Y-13978D01*
X886840Y-14142D01*
X886766Y-14266D01*
X886726Y-14296D01*
X885835D01*
G37*
G36*
G01Y-15629D02*
Y-14896D01*
X886784D01*
X886961Y-14946D01*
X887101Y-15086D01*
X887139Y-15221D01*
X887092Y-15384D01*
X886991Y-15537D01*
X886830Y-15629D01*
X885835D01*
G37*
G36*
G01X876724Y-6011D02*
X876951Y-5466D01*
X877178Y-6011D01*
X876724D01*
G37*
G36*
G01X879518Y-5678D02*
Y-4986D01*
X880205D01*
X880443Y-5075D01*
X880534Y-5149D01*
X880575Y-5311D01*
X880534Y-5477D01*
X880392Y-5595D01*
X880197Y-5678D01*
X879518D01*
G37*
G36*
G01X894934Y-6886D02*
Y-4986D01*
X895414D01*
X895663Y-5080D01*
X895848Y-5203D01*
X896012Y-5400D01*
X896134Y-5613D01*
X896166Y-5936D01*
X896134Y-6259D01*
X896012Y-6472D01*
X895848Y-6669D01*
X895663Y-6792D01*
X895414Y-6886D01*
X894934D01*
G37*
G36*
G01X1142278Y-6280D02*
G02X1140278I-1000J0D01*
G01Y-4280D01*
G02X1142278I1000J0D01*
G01Y-6280D01*
G37*
G36*
G01X1139325D02*
G02X1137325I-1000J0D01*
G01Y-4280D01*
G02X1139325I1000J0D01*
G01Y-6280D01*
G37*
G36*
G01X1136372D02*
G02X1134372I-1000J0D01*
G01Y-4280D01*
G02X1136372I1000J0D01*
G01Y-6280D01*
G37*
G36*
G01X1133419D02*
G02X1131419I-1000J0D01*
G01Y-4280D01*
G02X1133419I1000J0D01*
G01Y-6280D01*
G37*
G36*
G01X1130466D02*
G02X1128466I-1000J0D01*
G01Y-4280D01*
G02X1130466I1000J0D01*
G01Y-6280D01*
G37*
G36*
G01X1127513D02*
G02X1125513I-1000J0D01*
G01Y-4280D01*
G02X1127513I1000J0D01*
G01Y-6280D01*
G37*
G36*
G01X1117671D02*
G02X1115671I-1000J0D01*
G01Y-4280D01*
G02X1117671I1000J0D01*
G01Y-6280D01*
G37*
G36*
G01X1139285Y105520D02*
G02Y107520I0J1000D01*
G01X1143285D01*
G02Y105520I0J-1000D01*
G01X1139285D01*
G37*
G36*
G01X1173773Y-6280D02*
G02X1171773I-1000J0D01*
G01Y-4280D01*
G02X1173773I1000J0D01*
G01Y-6280D01*
G37*
G36*
G01X1176726D02*
G02X1174726I-1000J0D01*
G01Y-4280D01*
G02X1176726I1000J0D01*
G01Y-6280D01*
G37*
G36*
G01X1170820D02*
G02X1168820I-1000J0D01*
G01Y-4280D01*
G02X1170820I1000J0D01*
G01Y-6280D01*
G37*
G36*
G01X1160978D02*
G02X1158978I-1000J0D01*
G01Y-4280D01*
G02X1160978I1000J0D01*
G01Y-6280D01*
G37*
G36*
G01X1151137D02*
G02X1149137I-1000J0D01*
G01Y-4280D01*
G02X1151137I1000J0D01*
G01Y-6280D01*
G37*
G36*
G01X1148184D02*
G02X1146184I-1000J0D01*
G01Y-4280D01*
G02X1148184I1000J0D01*
G01Y-6280D01*
G37*
G36*
G01X1145231D02*
G02X1143231I-1000J0D01*
G01Y-4280D01*
G02X1145231I1000J0D01*
G01Y-6280D01*
G37*
G36*
G01X1204285D02*
G02X1202285I-1000J0D01*
G01Y-4280D01*
G02X1204285I1000J0D01*
G01Y-6280D01*
G37*
G36*
G01X1179679D02*
G02X1177679I-1000J0D01*
G01Y-4280D01*
G02X1179679I1000J0D01*
G01Y-6280D01*
G37*
G36*
G01X1182632D02*
G02X1180632I-1000J0D01*
G01Y-4280D01*
G02X1182632I1000J0D01*
G01Y-6280D01*
G37*
G36*
G01X1188538D02*
G02X1186538I-1000J0D01*
G01Y-4280D01*
G02X1188538I1000J0D01*
G01Y-6280D01*
G37*
G36*
G01X1185585D02*
G02X1183585I-1000J0D01*
G01Y-4280D01*
G02X1185585I1000J0D01*
G01Y-6280D01*
G37*
G36*
G01X1191491D02*
G02X1189491I-1000J0D01*
G01Y-4280D01*
G02X1191491I1000J0D01*
G01Y-6280D01*
G37*
G36*
G01X1194444D02*
G02X1192444I-1000J0D01*
G01Y-4280D01*
G02X1194444I1000J0D01*
G01Y-6280D01*
G37*
G36*
G01X1182285Y105520D02*
G02Y107520I0J1000D01*
G01X1186285D01*
G02Y105520I0J-1000D01*
G01X1182285D01*
G37*
G36*
G01X1217080Y-6280D02*
G02X1215080I-1000J0D01*
G01Y-4280D01*
G02X1217080I1000J0D01*
G01Y-6280D01*
G37*
G36*
G01X1220033D02*
G02X1218033I-1000J0D01*
G01Y-4280D01*
G02X1220033I1000J0D01*
G01Y-6280D01*
G37*
G36*
G01X1222986D02*
G02X1220986I-1000J0D01*
G01Y-4280D01*
G02X1222986I1000J0D01*
G01Y-6280D01*
G37*
G36*
G01X1225939D02*
G02X1223939I-1000J0D01*
G01Y-4280D01*
G02X1225939I1000J0D01*
G01Y-6280D01*
G37*
G36*
G01X1231845D02*
G02X1229845I-1000J0D01*
G01Y-4280D01*
G02X1231845I1000J0D01*
G01Y-6280D01*
G37*
G36*
G01X1228892D02*
G02X1226892I-1000J0D01*
G01Y-4280D01*
G02X1228892I1000J0D01*
G01Y-6280D01*
G37*
G36*
G01X1234798D02*
G02X1232798I-1000J0D01*
G01Y-4280D01*
G02X1234798I1000J0D01*
G01Y-6280D01*
G37*
G36*
G01X1237751D02*
G02X1235751I-1000J0D01*
G01Y-4280D01*
G02X1237751I1000J0D01*
G01Y-6280D01*
G37*
G36*
G01X1214127D02*
G02X1212127I-1000J0D01*
G01Y-4280D01*
G02X1214127I1000J0D01*
G01Y-6280D01*
G37*
G36*
G01X1226285Y105520D02*
G02Y107520I0J1000D01*
G01X1230285D01*
G02Y105520I0J-1000D01*
G01X1226285D01*
G37*
G36*
G01X1260387Y-6280D02*
G02X1258387I-1000J0D01*
G01Y-4280D01*
G02X1260387I1000J0D01*
G01Y-6280D01*
G37*
G36*
G01X1263340D02*
G02X1261340I-1000J0D01*
G01Y-4280D01*
G02X1263340I1000J0D01*
G01Y-6280D01*
G37*
G36*
G01X1266293D02*
G02X1264293I-1000J0D01*
G01Y-4280D01*
G02X1266293I1000J0D01*
G01Y-6280D01*
G37*
G36*
G01X1269246D02*
G02X1267246I-1000J0D01*
G01Y-4280D01*
G02X1269246I1000J0D01*
G01Y-6280D01*
G37*
G36*
G01X1275152D02*
G02X1273152I-1000J0D01*
G01Y-4280D01*
G02X1275152I1000J0D01*
G01Y-6280D01*
G37*
G36*
G01X1272199D02*
G02X1270199I-1000J0D01*
G01Y-4280D01*
G02X1272199I1000J0D01*
G01Y-6280D01*
G37*
G36*
G01X1278105D02*
G02X1276105I-1000J0D01*
G01Y-4280D01*
G02X1278105I1000J0D01*
G01Y-6280D01*
G37*
G36*
G01X1257434D02*
G02X1255434I-1000J0D01*
G01Y-4280D01*
G02X1257434I1000J0D01*
G01Y-6280D01*
G37*
G36*
G01X1247592D02*
G02X1245592I-1000J0D01*
G01Y-4280D01*
G02X1247592I1000J0D01*
G01Y-6280D01*
G37*
G36*
G01X1269285Y105520D02*
G02Y107520I0J1000D01*
G01X1273285D01*
G02Y105520I0J-1000D01*
G01X1269285D01*
G37*
G36*
G01X1290899Y-6280D02*
G02X1288899I-1000J0D01*
G01Y-4280D01*
G02X1290899I1000J0D01*
G01Y-6280D01*
G37*
G36*
G01X1281058D02*
G02X1279058I-1000J0D01*
G01Y-4280D01*
G02X1281058I1000J0D01*
G01Y-6280D01*
G37*
G36*
G01X1356513Y162366D02*
Y163058D01*
X1357200D01*
X1357438Y162969D01*
X1357529Y162895D01*
X1357570Y162733D01*
X1357529Y162567D01*
X1357387Y162449D01*
X1357192Y162366D01*
X1356513D01*
G37*
G36*
G01X1356388Y157691D02*
Y158258D01*
X1357151D01*
X1357333Y158180D01*
X1357409Y158104D01*
X1357440Y158009D01*
X1357393Y157845D01*
X1357319Y157721D01*
X1357279Y157691D01*
X1356388D01*
G37*
G36*
G01Y156358D02*
Y157091D01*
X1357337D01*
X1357514Y157041D01*
X1357654Y156901D01*
X1357692Y156766D01*
X1357645Y156603D01*
X1357544Y156450D01*
X1357383Y156358D01*
X1356388D01*
G37*
G54D10*
G01X29000Y438000D02*
X34000D01*
G01X33500Y420000D02*
X28500D01*
G01X21400Y524062D02*
Y530062D01*
G01X62550Y354433D02*
X56550D01*
G01X51000Y437000D02*
Y442000D01*
G01X39800Y708400D02*
X34800D01*
G01X127746Y-260199D02*
X95746D01*
G01X69500Y433000D02*
Y428000D01*
G01Y441000D02*
Y436000D01*
G01X75500Y628100D02*
X81500D01*
G01X67000D02*
X73000D01*
G01X127746Y-276199D02*
Y-356199D01*
G01D02*
X1310146D01*
G01X127746Y-311699D02*
X1310146D01*
G01X123746Y-260199D02*
G02I-12000J0D01*
G01X118596D02*
G02I-6850J0D01*
G01X111746Y-276199D02*
Y-244199D01*
G01X127746Y-276199D02*
X1310146D01*
G01X124500Y201000D02*
Y206000D01*
G01Y193000D02*
Y198000D01*
G01Y209000D02*
Y214000D01*
G01X123500Y274900D02*
Y279900D01*
G01X121551Y650936D02*
X126551D01*
G01X116900Y822450D02*
Y831550D01*
G01X133500Y212800D02*
Y196200D01*
G01X157130Y178131D02*
Y185131D01*
G01X132850Y295100D02*
Y302100D01*
G01X150921Y305358D02*
X155921D01*
G01X158900Y305400D02*
X163900D01*
G01X162000Y622284D02*
X168300D01*
Y615984D01*
G01X132100Y771500D02*
Y765500D01*
G01X188721Y481318D02*
Y475018D01*
X182421D01*
G01X233000Y175000D02*
Y180000D01*
G01Y166500D02*
Y171500D01*
G01X210518Y243606D02*
Y235006D01*
G01X213768Y247856D02*
Y239956D01*
G01X217300Y583500D02*
X225000D01*
G01X252500Y174422D02*
Y169422D01*
G01Y182222D02*
Y177222D01*
G01Y190222D02*
Y185222D01*
G01X257800Y608900D02*
Y603900D01*
G01Y616900D02*
Y611900D01*
G01Y624900D02*
Y619900D01*
G01X275031Y276980D02*
Y287080D01*
G01X284131Y288780D02*
Y278680D01*
G01X278800Y625400D02*
X273800D01*
G01Y647900D02*
X278800D01*
G01X312200Y159000D02*
X328800D01*
G01X332500Y183500D02*
X337500D01*
G01X308439Y328701D02*
Y323701D01*
G01X340500Y183500D02*
X345500D01*
G01X341634Y276911D02*
Y287011D01*
G01X350734Y288711D02*
Y278611D01*
G01X458900Y80700D02*
Y88700D01*
G01X500588Y5524D02*
Y10174D01*
G01Y29146D02*
Y33796D01*
G01Y52768D02*
Y57418D01*
G01Y76390D02*
Y81040D01*
G01X522646Y-276199D02*
Y-356199D01*
G01X511776Y242411D02*
Y250311D01*
G01X515026Y246761D02*
Y255361D01*
G01X514477Y296240D02*
Y291240D01*
G01X554531Y372580D02*
Y377580D01*
G01X573863Y243108D02*
Y248108D01*
G01X598863Y266608D02*
Y261608D01*
G01X573863Y251108D02*
Y256108D01*
G01X587000Y352500D02*
X592000D01*
G01X571500D02*
X576500D01*
G01X579200D02*
X584200D01*
G01X573000Y377500D02*
Y372500D01*
G01X575062Y600254D02*
X625104D01*
Y572841D01*
X575062D01*
Y600254D01*
G01X660146Y-276199D02*
Y-356199D01*
G01X662763Y232608D02*
X657763D01*
G01X683063Y258108D02*
X666463D01*
G01X666537Y260192D02*
X683137D01*
G01X645056Y685234D02*
Y614234D01*
X836971D01*
Y658269D01*
X903054D01*
Y685234D01*
X645056D01*
G01X704924Y71248D02*
Y66598D01*
G01X702200Y282000D02*
X707200D01*
G01X726863Y-6000D02*
Y-1350D01*
G01X724609Y71248D02*
Y66598D01*
G01X735100Y242500D02*
X730100D01*
G01X727100D02*
X722100D01*
G01X719100D02*
X714100D01*
G01X711100D02*
X706100D01*
G01X709800Y282000D02*
X714800D01*
G01X717400D02*
X722400D01*
G01X725000D02*
X730000D01*
G01X732600D02*
X737600D01*
G01X744294Y71248D02*
Y66598D01*
G01X769738Y100600D02*
X777738D01*
G01X772638Y132000D02*
X780638D01*
G01X750737Y202192D02*
X745737D01*
G01X775146Y-276199D02*
Y-356199D01*
G01X775379Y4400D02*
X779229D01*
Y-4400D01*
X775579D01*
G01X842834Y535D02*
Y-4115D01*
G01X877000Y9700D02*
X869000D01*
G01X851102Y46000D02*
Y55600D01*
G01X885550Y26050D02*
Y19950D01*
G01X888500Y322300D02*
Y314600D01*
G01X921400Y51600D02*
X926400D01*
G01X942646Y-276199D02*
Y-356199D01*
G01X973900Y35600D02*
X968900D01*
G01X963086Y17943D02*
Y10443D01*
G01X955586Y17943D02*
X963086D01*
G01X968900Y52600D02*
X973900D01*
G01X981900Y35600D02*
X976900D01*
G01Y52600D02*
X981900D01*
G01X1017003Y30207D02*
Y37007D01*
G01X1071454Y66548D02*
Y71198D01*
G01X1051769Y66548D02*
Y71198D01*
G01X1091139Y66548D02*
Y71198D01*
G01X1112646Y-276199D02*
Y-356199D01*
G01X1179500Y224800D02*
X1174500D01*
G01X1170500D02*
X1165500D01*
G01X1174500Y271000D02*
X1179500D01*
G01X1165500D02*
X1170500D01*
G01X1215500Y224800D02*
X1210500D01*
G01X1206500D02*
X1201500D01*
G01X1197500D02*
X1192500D01*
G01X1188500D02*
X1183500D01*
G01X1210000Y271000D02*
X1215000D01*
G01X1192500D02*
X1197500D01*
G01X1201500D02*
X1206500D01*
G01X1183500D02*
X1188500D01*
G01X1242800Y233000D02*
X1226200D01*
G01Y254000D02*
X1242800D01*
G01X1263300Y233000D02*
X1246700D01*
G01Y254000D02*
X1263300D01*
G01X1310146Y-276199D02*
Y-356199D01*
G01X1342146Y-260199D02*
X1310146D01*
G01X1293506Y10224D02*
Y5574D01*
G01Y33846D02*
Y29196D01*
G01Y57468D02*
Y52818D01*
G01Y81090D02*
Y76440D01*
G01X1338146Y-260199D02*
G02I-12000J0D01*
G01X1332996D02*
G02I-6850J0D01*
G01X1326146Y-276199D02*
Y-244199D01*
G01X1342500Y237500D02*
Y242500D01*
G01X1363481Y243009D02*
Y238009D01*
G01X1363540Y250621D02*
Y245621D01*
G54D20*
G01X560170Y656590D02*
X559510D01*
G01X559610Y656680D02*
X560270D01*
G01X560360Y656790D02*
X559710D01*
G01X559810Y656880D02*
X560460D01*
G01X560560Y656990D02*
X559900D01*
G01X560000Y657090D02*
X560650D01*
G01X560750Y657180D02*
X560100D01*
G01X560190Y657290D02*
X560850D01*
G01X560940Y657380D02*
X560290D01*
G01X560380Y657490D02*
X561040D01*
G01X561140Y657590D02*
X560480D01*
G01X560580Y657680D02*
X561230D01*
G01X561330Y657790D02*
X560685D01*
G01X560680D02*
X560730D01*
G01X560770Y657880D02*
X560810D01*
G01X560770D02*
X561420D01*
G01X561520Y657990D02*
X560870D01*
G01X560970Y658090D02*
X561620D01*
G01X561720Y658180D02*
X561060D01*
G01X561160Y658290D02*
X561810D01*
G01X561910Y658380D02*
X561250D01*
G01X561350Y658490D02*
X562010D01*
G01X562100Y658590D02*
X561450D01*
G01X561550Y658680D02*
X562200D01*
G01X562290Y658790D02*
X561640D01*
G01X561740Y658880D02*
X562390D01*
G01X562490Y658990D02*
X561830D01*
G01X561930Y659090D02*
X562590D01*
G01X562680Y659180D02*
X562030D01*
G01X562120Y659290D02*
X562780D01*
G01X562970Y659490D02*
X562320D01*
G01X562510Y659680D02*
X563160D01*
G01X557870Y674100D02*
X557900Y674120D01*
G01X557870Y673560D02*
Y674100D01*
G01X557880Y673540D02*
X557870Y673560D01*
G01X557930Y673430D02*
X557880Y673540D01*
G01X557940Y673420D02*
X557930Y673430D01*
G01X563120Y667830D02*
X557940Y673420D01*
G01X557870Y674090D02*
X557930D01*
G01X557870Y673990D02*
X558020D01*
G01X558110Y673880D02*
X557870D01*
G01Y673790D02*
X558210D01*
G01X558300Y673680D02*
X557870D01*
G01Y673590D02*
X558390D01*
G01X558490Y673490D02*
X557900D01*
G01X557970Y673380D02*
X558580D01*
G01X558670Y673290D02*
X558060D01*
G01X558150Y673180D02*
X558760D01*
G01X558860Y673090D02*
X558250D01*
G01X558340Y672990D02*
X558950D01*
G01X559040Y672880D02*
X558430D01*
G01X558520Y672790D02*
X559140D01*
G01X559230Y672680D02*
X558620D01*
G01X558710Y672590D02*
X559320D01*
G01X559420Y672490D02*
X558800D01*
G01X558900Y672380D02*
X559510D01*
G01X559600Y672290D02*
X558990D01*
G01X559080Y672180D02*
X559700D01*
G01X559790Y672090D02*
X559180D01*
G01X559270Y671990D02*
X559880D01*
G01X559980Y671880D02*
X559360D01*
G01X559450Y671790D02*
X560070D01*
G01X560160Y671680D02*
X559550D01*
G01X559640Y671590D02*
X560250D01*
G01X560350Y671490D02*
X559730D01*
G01X559830Y671380D02*
X560440D01*
G01X560530Y671290D02*
X559920D01*
G01X560010Y671180D02*
X560620D01*
G01X560720Y671090D02*
X560110D01*
G01X560200Y670990D02*
X560810D01*
G01X560900Y670880D02*
X560290D01*
G01X560380Y670790D02*
X561000D01*
G01X561090Y670680D02*
X560480D01*
G01X560570Y670590D02*
X561180D01*
G01X561280Y670490D02*
X560660D01*
G01X560750Y670380D02*
X561370D01*
G01X561460Y670290D02*
X560850D01*
G01X560940Y670180D02*
X561560D01*
G01X561650Y670090D02*
X561030D01*
G01X561120Y669990D02*
X561740D01*
G01X561840Y669880D02*
X561220D01*
G01X561310Y669790D02*
X561930D01*
G01X562020Y669680D02*
X561400D01*
G01X561490Y669590D02*
X562120D01*
G01X562210Y669490D02*
X561590D01*
G01X561680Y669380D02*
X562300D01*
G01X562390Y669290D02*
X561770D01*
G01X561870Y669180D02*
X562490D01*
G01X562580Y669090D02*
X561960D01*
G01X562050Y668990D02*
X562670D01*
G01X562770Y668880D02*
X562150D01*
G01X562330Y668680D02*
X563570D01*
G01X563580Y668490D02*
X562520D01*
G01X562270Y670780D02*
X562780D01*
G01X562230Y670740D02*
X562270Y670780D01*
G01X562230Y670280D02*
Y670740D01*
G01X562270Y670240D02*
X562230Y670280D01*
G01Y670680D02*
X572480D01*
G01X572410Y670490D02*
X562230D01*
G01Y670290D02*
X572250D01*
G01X564880Y671590D02*
X563450D01*
G01X562870Y670850D02*
X562780Y670780D01*
G01X562890Y670900D02*
X562870Y670850D01*
G01X562890Y670910D02*
Y670900D01*
G01X563010Y671160D02*
X562890Y670910D01*
G01X563030Y671170D02*
X563010Y671160D01*
G01X563460Y671590D02*
X563030Y671170D01*
G01X562790Y670790D02*
X563520D01*
G01X563630Y671120D02*
X563740Y671190D01*
G01X563460Y670950D02*
X563630Y671120D01*
G01X563440Y670840D02*
X563460Y670950D01*
G01X563530Y670780D02*
X563440Y670840D01*
G01X563600Y671090D02*
X562980D01*
G01X562930Y670990D02*
X563500D01*
G01X563450Y670880D02*
X562880D01*
G01X563140Y671290D02*
X564820D01*
G01Y671490D02*
X563350D01*
G01X563700Y667890D02*
X566930Y664410D01*
G01X563690Y667890D02*
X563700D01*
G01X563650Y667940D02*
X563690Y667890D01*
G01X563620Y668000D02*
X563650Y667940D01*
G01X563440Y670130D02*
X563620Y668000D01*
G01X563540Y670240D02*
X563440Y670130D01*
G01X563960Y664090D02*
X563490D01*
G01X563480Y664290D02*
X563940D01*
G01X563920Y664490D02*
X563460D01*
G01X563440Y664680D02*
X563910D01*
G01X563890Y664880D02*
X563420D01*
G01X563400Y665090D02*
X563870D01*
G01X563860Y665290D02*
X563390D01*
G01X563370Y665490D02*
X563840D01*
G01X563820Y665680D02*
X563350D01*
G01X563340Y665880D02*
X563810D01*
G01X563790Y666090D02*
X563320D01*
G01X563300Y666290D02*
X563770D01*
G01X563750Y666490D02*
X563290D01*
G01X563270Y666680D02*
X563740D01*
G01X563720Y666880D02*
X563250D01*
G01X563240Y666990D02*
X563750D01*
G01X564250Y667290D02*
X563220D01*
G01X563200Y667490D02*
X564070D01*
G01X563140Y667800D02*
X563120Y667830D01*
G01X563180Y667700D02*
X563140Y667800D01*
G01X563180Y667690D02*
Y667700D01*
G01Y667680D02*
Y667690D01*
G01X563880Y667680D02*
X563180D01*
G01X563080Y667880D02*
X563700D01*
G01X563630Y667990D02*
X562980D01*
G01X562890Y668090D02*
X563620D01*
G01X563610Y668180D02*
X562800D01*
G01X562700Y668290D02*
X563600D01*
G01X563590Y668380D02*
X562610D01*
G01X562420Y668590D02*
X563570D01*
G01X563560Y668790D02*
X563080D01*
G01X562870Y670240D02*
X562270D01*
G01X562970Y670150D02*
X562870Y670240D01*
G01X563090Y668800D02*
X562970Y670150D01*
G01X562930Y670180D02*
X563490D01*
G01X563440Y670090D02*
X562980D01*
G01X562990Y669990D02*
X563460D01*
G01Y669880D02*
X562990D01*
G01X563000Y669790D02*
X563470D01*
G01X563480Y669680D02*
X563010D01*
G01X563020Y669590D02*
X563490D01*
G01X563500Y669490D02*
X563030D01*
G01X563040Y669380D02*
X563510D01*
G01Y669290D02*
X563050D01*
G01Y669180D02*
X563520D01*
G01X563530Y669090D02*
X563070D01*
G01Y668990D02*
X563540D01*
G01X563550Y668880D02*
X563080D01*
G01X562920Y668730D02*
X557900Y674120D01*
G01X563030Y668700D02*
X562920Y668730D01*
G01X563090Y668800D02*
X563030Y668700D01*
G01X562240Y668790D02*
X562860D01*
G01X563180Y667680D02*
X563620Y662530D01*
G01X563630Y662490D02*
X564100D01*
G01X564110Y662290D02*
X563640D01*
G01X563660Y662090D02*
X564130D01*
G01X564150Y661880D02*
X563680D01*
G01X563700Y661680D02*
X564170D01*
G01X564210Y661590D02*
X563710D01*
G01X563720Y660940D02*
X563620Y660830D01*
G01X563750Y661010D02*
X563720Y660940D01*
G01X563570Y660790D02*
X564260D01*
G01Y660590D02*
X563380D01*
G01X563190Y660380D02*
X564280D01*
G01X563640Y660180D02*
X562990D01*
G01X562900Y660090D02*
X563550D01*
G01X563450Y659990D02*
X562800D01*
G01X562700Y659880D02*
X563360D01*
G01X563260Y659790D02*
X562610D01*
G01X562420Y659590D02*
X563070D01*
G01X562870Y659380D02*
X562220D01*
G01X563600Y662790D02*
X564070D01*
G01X564050Y662990D02*
X563590D01*
G01X563570Y663180D02*
X564040D01*
G01X564020Y663380D02*
X563550D01*
G01X563530Y663590D02*
X564000D01*
G01X563990Y663790D02*
X563520D01*
G01X563510Y663880D02*
X563980D01*
G01X563970Y663990D02*
X563500D01*
G01X563480Y664180D02*
X563950D01*
G01X563940Y664380D02*
X563470D01*
G01X563450Y664590D02*
X563920D01*
G01X563900Y664790D02*
X563430D01*
G01X563420Y664990D02*
X563880D01*
G01X563860Y665180D02*
X563400D01*
G01X563380Y665380D02*
X563850D01*
G01X563830Y665590D02*
X563360D01*
G01X563350Y665790D02*
X563810D01*
G01X563800Y665990D02*
X563330D01*
G01X563310Y666180D02*
X563780D01*
G01X563760Y666380D02*
X563290D01*
G01X563280Y666590D02*
X563740D01*
G01X563730Y666790D02*
X563260D01*
G01X563890Y667010D02*
X566620Y664070D01*
G01X563770Y667030D02*
X563890Y667010D01*
G01X563720Y666930D02*
X563770Y667030D01*
G01X563990Y663680D02*
X563530D01*
G01X563540Y663490D02*
X564010D01*
G01X564030Y663290D02*
X563560D01*
G01X563580Y663090D02*
X564050D01*
G01X564060Y662880D02*
X563590D01*
G01X563610Y662680D02*
X564080D01*
G01X564090Y662590D02*
X563620D01*
G01X563750Y661070D02*
Y661010D01*
G01X563620Y662530D02*
X563750Y661070D01*
G01X563740Y660990D02*
X564420D01*
G01X564270Y660810D02*
X564250Y660740D01*
G01X564320Y660890D02*
X564270Y660810D01*
G01X564250Y660680D02*
X563480D01*
G01X563290Y660490D02*
X564270D01*
G01X564290Y660180D02*
X563790D01*
G01X563760Y660220D02*
X563660Y660200D01*
G01X564030Y657780D02*
X564140D01*
G01X564030Y657790D02*
Y657780D01*
G01X563830Y660140D02*
X564030Y657790D01*
G01X563760Y660220D02*
X563830Y660140D01*
G01X564130Y657880D02*
X564020D01*
G01X564025D02*
X569620D01*
G01X569685Y657790D02*
X564030D01*
G01X564270Y656740D02*
X565160D01*
G01X564230Y656780D02*
X564270Y656740D01*
G01X564230Y657460D02*
Y656780D01*
G01X564200Y657530D02*
X564230Y657460D01*
G01X564050Y657690D02*
X564200Y657530D01*
G01X564040Y657710D02*
X564050Y657690D01*
G01X564030Y657770D02*
X564040Y657710D01*
G01X565200Y656790D02*
X564230D01*
G01Y656990D02*
X565200D01*
G01Y657180D02*
X564230D01*
G01Y657380D02*
X565200D01*
G01X564480Y658090D02*
X564010D01*
G01X563990Y658180D02*
X564460D01*
G01X564450Y658380D02*
X563980D01*
G01X563960Y658590D02*
X564430D01*
G01X564410Y658790D02*
X563940D01*
G01X563930Y658990D02*
X564400D01*
G01X564380Y659180D02*
X563910D01*
G01X563890Y659380D02*
X564360D01*
G01X564350Y659590D02*
X563880D01*
G01X563860Y659790D02*
X564330D01*
G01X564310Y659990D02*
X563850D01*
G01X563740Y661180D02*
X564610D01*
G01X564800Y661380D02*
X563720D01*
G01X563690Y661790D02*
X564160D01*
G01X564170Y661640D02*
X563720Y666930D01*
G01X563910Y666990D02*
X564530D01*
G01X564720Y666790D02*
X564100D01*
G01X564280Y666590D02*
X564900D01*
G01X564160Y667380D02*
X563210D01*
G01X563190Y667590D02*
X563980D01*
G01X563790Y667790D02*
X563150D01*
G01X563850Y671200D02*
X563740Y671190D01*
G01X563900Y671110D02*
X563850Y671200D01*
G01X563900Y670880D02*
Y671110D01*
G01X563800Y670780D02*
X563900Y670880D01*
G01X563530Y670780D02*
X563800D01*
G01X563730Y671180D02*
X563040D01*
G01X563910Y672170D02*
X563940Y672190D01*
G01X563900Y672140D02*
X563910Y672170D01*
G01X563900Y671940D02*
Y672140D01*
G01X563890Y671900D02*
X563900Y671940D01*
G01X563870Y671850D02*
X563890Y671900D01*
G01X563820Y671790D02*
X563870Y671850D01*
G01X563730Y671750D02*
X563820Y671790D01*
G01X563460Y671590D02*
X563730Y671750D01*
G01X563940Y672180D02*
X564770D01*
G01X563900Y671990D02*
X566790D01*
G01X566780Y671790D02*
X563800D01*
G01X563850Y671180D02*
X564820D01*
G01Y670990D02*
X563900D01*
G01X563810Y670790D02*
X564920D01*
G01X564110Y662380D02*
X563640D01*
G01X563650Y662180D02*
X564120D01*
G01X564140Y661990D02*
X563670D01*
G01X564240Y661550D02*
X564340Y661580D01*
G01X564170Y661640D02*
X564240Y661550D01*
G01X564150Y657590D02*
X569930D01*
G01X564470Y658160D02*
X564250Y660740D01*
G01X564470Y658090D02*
Y658160D01*
G01X564570Y658000D02*
X564470Y658090D01*
G01X568670Y658000D02*
X564570D01*
G01X564320Y660880D02*
X563670D01*
G01X563750Y661090D02*
X564510D01*
G01X564330Y660890D02*
X564320D01*
G01X564330Y660900D02*
Y660890D01*
G01Y660900D02*
X566920Y663590D01*
G01X566730Y663380D02*
X566090D01*
G01X565890Y663180D02*
X566540D01*
G01X566350Y662990D02*
X565700D01*
G01X565510Y662790D02*
X566150D01*
G01X566060Y662680D02*
X565410D01*
G01X565460Y662740D02*
X564340Y661580D01*
G01X564350Y661590D02*
X564990D01*
G01X564900Y661490D02*
X563720D01*
G01X563730Y661290D02*
X564710D01*
G01X564450Y661680D02*
X565090D01*
G01X565190Y661790D02*
X564550D01*
G01X564640Y661880D02*
X565290D01*
G01X565380Y661990D02*
X564740D01*
G01X564830Y662090D02*
X565480D01*
G01X565570Y662180D02*
X564930D01*
G01X565030Y662290D02*
X565670D01*
G01X565770Y662380D02*
X565120D01*
G01X565220Y662490D02*
X565860D01*
G01X565960Y662590D02*
X565310D01*
G01X566140Y664590D02*
X566770D01*
G01X566580Y664790D02*
X565960D01*
G01X565770Y664990D02*
X566390D01*
G01X566210Y665180D02*
X565580D01*
G01X565490Y665290D02*
X566110D01*
G01X566020Y665380D02*
X565400D01*
G01X565310Y665490D02*
X565930D01*
G01X565830Y665590D02*
X565210D01*
G01X565120Y665680D02*
X565740D01*
G01X565650Y665790D02*
X565030D01*
G01X564930Y665880D02*
X565560D01*
G01X565460Y665990D02*
X564840D01*
G01X564750Y666090D02*
X565370D01*
G01X565280Y666180D02*
X564650D01*
G01X564560Y666290D02*
X565180D01*
G01X565090Y666380D02*
X564470D01*
G01X564380Y666490D02*
X565000D01*
G01X564810Y666680D02*
X564190D01*
G01X564000Y666880D02*
X564620D01*
G01X564440Y667090D02*
X563240D01*
G01X563230Y667180D02*
X564350D01*
G01X566200Y666460D02*
X566240Y666420D01*
G01X564820Y670880D02*
X563900D01*
G01X564920Y670780D02*
X564820Y670880D01*
G01X563900Y671090D02*
X564820D01*
G01X566150Y671790D02*
X566260Y671680D01*
G01X565880Y671760D02*
X566150Y671790D01*
G01X565600Y671730D02*
X565880Y671760D01*
G01X565480Y671720D02*
X565600Y671730D01*
G01X565380Y671700D02*
X565480Y671720D01*
G01X565130Y671660D02*
X565380Y671700D01*
G01X565120Y671660D02*
X565130D01*
G01X565030Y671640D02*
X565120Y671660D01*
G01X565020Y671640D02*
X565030D01*
G01X564900Y671620D02*
X565020Y671640D01*
G01X564820Y671520D02*
X564900Y671620D01*
G01X564820Y670880D02*
Y671520D01*
G01X564760Y672190D02*
X563940D01*
G01X564780Y672180D02*
X564760Y672190D01*
G01X564810Y672170D02*
X564780Y672180D01*
G01X564840Y672150D02*
X564810Y672170D01*
G01X564920Y672130D02*
X564840Y672150D01*
G01X564940Y672140D02*
X564920Y672130D01*
G01X565180Y672180D02*
X564940Y672140D01*
G01X565680Y672250D02*
X565180Y672180D01*
G01X565800Y672260D02*
X565680Y672250D01*
G01X565860Y672260D02*
X565800D01*
G01X566020Y672280D02*
X565860Y672260D01*
G01X566160Y672290D02*
X566020Y672280D01*
G01X563620Y671680D02*
X565270D01*
G01X564820Y671380D02*
X563250D01*
G01X564920Y670780D02*
X570760D01*
G01X568830Y672290D02*
X566140D01*
G01X566160D02*
X566260Y672390D01*
G01X564290Y660290D02*
X563090D01*
G01X563830Y660090D02*
X564300D01*
G01X564320Y659880D02*
X563850D01*
G01X563870Y659680D02*
X564340D01*
G01X564350Y659490D02*
X563880D01*
G01X563900Y659290D02*
X564370D01*
G01X564390Y659090D02*
X563920D01*
G01X563940Y658880D02*
X564400D01*
G01X564420Y658680D02*
X563960D01*
G01X563970Y658490D02*
X564440D01*
G01X564460Y658290D02*
X563990D01*
G01X564220Y657490D02*
X565270D01*
G01X565200Y656780D02*
X565160Y656740D01*
G01X565200Y657420D02*
Y656780D01*
G01X565300Y657520D02*
X565200Y657420D01*
G01Y656880D02*
X564230D01*
G01Y657090D02*
X565200D01*
G01Y657290D02*
X564230D01*
G01X568770Y658470D02*
Y658480D01*
G01X568760Y658400D02*
X568770Y658470D01*
G01X568760Y658140D02*
Y658400D01*
G01X568770Y658120D02*
X568760Y658140D01*
G01X568670Y658000D02*
X568770Y658120D01*
G01Y658490D02*
X569540D01*
G01X569500Y658290D02*
X568760D01*
G01X568740Y658090D02*
X569540D01*
G01X567380Y663920D02*
Y664060D01*
G01X570080Y661020D02*
X567380Y663920D01*
G01X567400Y664090D02*
X566610D01*
G01X566620Y663930D02*
X565460Y662740D01*
G01X566620Y664070D02*
Y663930D01*
G01X565610Y662880D02*
X566250D01*
G01X566440Y663090D02*
X565800D01*
G01X565990Y663290D02*
X566640D01*
G01X566830Y663490D02*
X566180D01*
G01X567070Y663590D02*
X568750Y661770D01*
G01X566920Y663590D02*
X567070D01*
G01X566280D02*
X566920D01*
G01X568740Y661790D02*
X569370D01*
G01X569180Y661990D02*
X568550D01*
G01X568370Y662180D02*
X569000D01*
G01X568810Y662380D02*
X568180D01*
G01X568090Y662490D02*
X568720D01*
G01X568620Y662590D02*
X567990D01*
G01X567900Y662680D02*
X568530D01*
G01X568440Y662790D02*
X567810D01*
G01X567720Y662880D02*
X568350D01*
G01X568250Y662990D02*
X567620D01*
G01X567530Y663090D02*
X568160D01*
G01X568070Y663180D02*
X567440D01*
G01X567350Y663290D02*
X567980D01*
G01X567880Y663380D02*
X567250D01*
G01X567160Y663490D02*
X567790D01*
G01X567700Y663590D02*
X567050D01*
G01X567420Y663880D02*
X566570D01*
G01X566620Y663990D02*
X567380D01*
G01X567500Y664180D02*
X566510D01*
G01X566420Y664290D02*
X567600D01*
G01X567700Y664380D02*
X566330D01*
G01X566240Y664490D02*
X566860D01*
G01X567070Y664410D02*
X568500Y665880D01*
G01X566930Y664410D02*
X567070D01*
G01X568400Y665790D02*
X569040D01*
G01X568850Y665590D02*
X568210D01*
G01X568120Y665490D02*
X568750D01*
G01X568660Y665380D02*
X568020D01*
G01X567920Y665290D02*
X568560D01*
G01X568470Y665180D02*
X567830D01*
G01X567730Y665090D02*
X568370D01*
G01X568270Y664990D02*
X567630D01*
G01X567540Y664880D02*
X568180D01*
G01X568080Y664790D02*
X567440D01*
G01X567350Y664680D02*
X567980D01*
G01X567890Y664590D02*
X567250D01*
G01X567150Y664490D02*
X567790D01*
G01X567510Y663790D02*
X566480D01*
G01X566380Y663680D02*
X567600D01*
G01X566670Y664680D02*
X566050D01*
G01X565860Y664880D02*
X566490D01*
G01X566300Y665090D02*
X565680D01*
G01X566290Y666420D02*
X568780D01*
G01X566240D02*
X566290D01*
G01X568790Y666180D02*
X569430D01*
G01X569240Y665990D02*
X568600D01*
G01X569720Y666490D02*
X566200D01*
G01X566240Y667450D02*
X566290D01*
G01X566200Y667410D02*
X566240Y667450D01*
G01X566200Y666460D02*
Y667410D01*
G01Y667290D02*
X569460D01*
G01X569490Y667090D02*
X566200D01*
G01Y666880D02*
X570110D01*
G01X569910Y666680D02*
X566200D01*
G01X566260Y671340D02*
Y671680D01*
G01X566300Y671290D02*
X566260Y671340D01*
G01X566250Y671680D02*
X568880D01*
G01X568750Y671290D02*
X566300D01*
G01X568800Y671340D02*
X568750Y671290D01*
G01X568800Y671620D02*
Y671340D01*
G01X566260Y671380D02*
X568800D01*
G01Y671490D02*
X566260D01*
G01Y671590D02*
X568800D01*
G01X568350Y671900D02*
Y671860D01*
G01X568250Y672000D02*
X568350Y671900D01*
G01X566810Y672000D02*
X568250D01*
G01X566710Y671900D02*
X566810Y672000D01*
G01X566710Y671860D02*
Y671900D01*
G01X566810Y671750D02*
X566710Y671860D01*
G01X568250Y671750D02*
X566810D01*
G01X568350Y671860D02*
X568250Y671750D01*
G01X568350Y671880D02*
X570320D01*
G01X570030Y671990D02*
X568260D01*
G01X566260Y672420D02*
Y672390D01*
G01X566300Y672460D02*
X566260Y672420D01*
G01X568750Y672460D02*
X566300D01*
G01X568800Y672420D02*
X568750Y672460D01*
G01X568800Y672320D02*
Y672420D01*
G01X566250Y672380D02*
X568800D01*
G01X566710Y671880D02*
X563880D01*
G01X563900Y672090D02*
X569660D01*
G01X568880Y672220D02*
X568800Y672320D01*
G01X568930Y672220D02*
X568880D01*
G01X569490Y672130D02*
X568930Y672220D01*
G01X569670Y672090D02*
X569490Y672130D01*
G01X569110Y672180D02*
X565240D01*
G01X569310Y671650D02*
X569720Y671560D01*
G01X569020Y671700D02*
X569310Y671650D01*
G01X568990Y671700D02*
X569020D01*
G01X568910Y671720D02*
X568990Y671700D01*
G01X568800Y671620D02*
X568910Y671720D01*
G01X569100Y671680D02*
X570690D01*
G01X569410Y667450D02*
X566290D01*
G01X566200Y667380D02*
X569460D01*
G01X569450Y667410D02*
X569410Y667450D01*
G01X569630Y667060D02*
X569830Y667260D01*
G01X569520Y667030D02*
X569630Y667060D01*
G01X569460Y667130D02*
X569520Y667030D01*
G01X569460Y667310D02*
Y667130D01*
G01Y667320D02*
Y667310D01*
G01X569450Y667410D02*
X569460Y667320D01*
G01X569660Y667090D02*
X570300D01*
G01X569460Y667180D02*
X566200D01*
G01X568310Y665680D02*
X568950D01*
G01X568870Y666360D02*
X568780Y666420D01*
G01X568850Y666250D02*
X568870Y666360D01*
G01X568500Y665880D02*
X568850Y666250D01*
G01X569140Y665880D02*
X568500D01*
G01X568830Y666380D02*
X569620D01*
G01X569530Y666290D02*
X568860D01*
G01X568700Y666090D02*
X569330D01*
G01X568900Y662290D02*
X568270D01*
G01X568460Y662090D02*
X569090D01*
G01X569270Y661880D02*
X568640D01*
G01X568830Y661680D02*
X569460D01*
G01X569550Y661590D02*
X568920D01*
G01X569010Y661490D02*
X569650D01*
G01X569740Y661380D02*
X569110D01*
G01X569200Y661290D02*
X569830D01*
G01X570020Y661090D02*
X569390D01*
G01X569570Y660880D02*
X570710D01*
G01X570700Y660790D02*
X569670D01*
G01X568810Y658660D02*
X568770Y658480D01*
G01X568810Y658670D02*
Y658660D01*
G01X568920Y658980D02*
X568810Y658670D01*
G01X568930Y658990D02*
X568920Y658980D01*
G01X569140Y659300D02*
X568930Y658990D01*
G01X569150Y659310D02*
X569140Y659300D01*
G01X569390Y659530D02*
X569150Y659310D01*
G01X569400Y659530D02*
X569390D01*
G01X569520Y659610D02*
X569400Y659530D01*
G01X569530Y659620D02*
X569520Y659610D01*
G01X569590Y659650D02*
X569530Y659620D01*
G01X569750Y659720D02*
X569590Y659650D01*
G01X568760Y658380D02*
X569520D01*
G01X569560Y657990D02*
X564010D01*
G01X569550Y658010D02*
X569560Y657990D01*
G01X569500Y658270D02*
X569550Y658010D01*
G01X569500Y658280D02*
Y658270D01*
G01Y658300D02*
Y658280D01*
G01X564050Y657680D02*
X569790D01*
G01X569710Y657750D02*
X569650Y657840D01*
G01X569720Y657740D02*
X569710Y657750D01*
G01X569730Y657730D02*
X569720Y657740D01*
G01X569570Y657980D02*
X569560Y657990D01*
G01X569650Y657850D02*
X569570Y657980D01*
G01X569520Y658180D02*
X568760D01*
G01X568790Y658590D02*
X569560D01*
G01X569550Y658560D02*
X569500Y658300D01*
G01X569560Y658580D02*
X569550Y658560D01*
G01X569730Y658840D02*
X569950Y659000D01*
G01X569720Y658830D02*
X569730Y658840D01*
G01X569710Y658810D02*
X569720Y658830D01*
G01X569570Y658600D02*
X569710Y658810D01*
G01X569560Y658580D02*
X569570Y658600D01*
G01X569790Y658880D02*
X568890D01*
G01X568850Y658790D02*
X569690D01*
G01X569620Y658680D02*
X568810D01*
G01X568990Y659090D02*
X570250D01*
G01X569660Y659680D02*
X571330D01*
G01X571420Y659590D02*
X569480D01*
G01X569240Y659380D02*
X571610D01*
G01X571790Y659180D02*
X569070D01*
G01X569650Y657790D02*
X569690D01*
G01X569730Y657730D02*
X569950Y657570D01*
G01X569520Y656990D02*
X571070D01*
G01X571230Y657090D02*
X569340D01*
G01X568900Y657520D02*
X565300D01*
G01X568980Y657490D02*
X568900Y657520D01*
G01X568990Y657480D02*
X568980Y657490D01*
G01X568990Y657470D02*
Y657480D01*
G01X569030Y657400D02*
X568990Y657470D01*
G01X569040Y657400D02*
X569030D01*
G01X569050Y657390D02*
X569040Y657400D01*
G01X569120Y657290D02*
X569050Y657390D01*
G01X569130Y657280D02*
X569120Y657290D01*
G01X569360Y657060D02*
X569130Y657280D01*
G01Y657290D02*
X571470D01*
G01X569380Y657050D02*
X569360Y657060D01*
G01X569380Y657050D02*
X569980Y656770D01*
G01X569930Y658990D02*
X568930D01*
G01X569840Y659750D02*
X569750Y659720D01*
G01X569850Y660590D02*
X568750Y661770D01*
G01X569290Y661180D02*
X569930D01*
G01X570200Y666990D02*
X566200D01*
G01Y666790D02*
X570010D01*
G01X569810Y666590D02*
X566200D01*
G01X570000Y671480D02*
X569720Y671560D01*
G01X569790Y672050D02*
X569670Y672090D01*
G01X569600Y671590D02*
X570850D01*
G01X570530Y671790D02*
X568280D01*
G01X570590Y667390D02*
X567380Y664060D01*
G01X570720Y660990D02*
X569480D01*
G01X570890Y670240D02*
X563540D01*
G01X569350Y659490D02*
X571510D01*
G01X571700Y659290D02*
X569130D01*
G01X568980Y657490D02*
X571610D01*
G01X571380Y657180D02*
X569230D01*
G01X569050Y657380D02*
X571540D01*
G01X572340Y670380D02*
X562230D01*
G01Y670590D02*
X572440D01*
G01X558200Y655220D02*
X563620Y660830D01*
G01X558170Y655190D02*
X558200Y655220D01*
G01X558180Y655170D02*
X558170Y655190D01*
G01X558490Y654900D02*
X558180Y655170D01*
G01X558520Y654890D02*
X558490Y654900D01*
G01X558540D02*
X558520Y654890D01*
G01X563660Y660200D02*
X558540Y654900D01*
G01X558620Y654990D02*
X558390D01*
G01X558270Y655090D02*
X558720D01*
G01X558820Y655180D02*
X558170D01*
G01X558260Y655290D02*
X558920D01*
G01X559010Y655380D02*
X558360D01*
G01X558450Y655490D02*
X559110D01*
G01X559200Y655590D02*
X558550D01*
G01X558640Y655680D02*
X559300D01*
G01X559400Y655790D02*
X558740D01*
G01X558840Y655880D02*
X559490D01*
G01X559590Y655990D02*
X558940D01*
G01X559030Y656090D02*
X559690D01*
G01X559780Y656180D02*
X559130D01*
G01X559230Y656290D02*
X559880D01*
G01X559980Y656380D02*
X559320D01*
G01X559420Y656490D02*
X560070D01*
G01X569780Y658310D02*
X569790Y658330D01*
G01X570180Y656750D02*
X570520Y656760D01*
G01X570170Y656750D02*
X570180D01*
G01X570160D02*
X570170D01*
G01X570000Y656770D02*
X570160Y656750D01*
G01X569980Y656770D02*
X570000D01*
G01X570630Y656790D02*
X569960D01*
G01Y657560D02*
X569950Y657570D01*
G01X569980Y657560D02*
X569960D01*
G01X570150Y657500D02*
X569980Y657560D01*
G01X570370Y657490D02*
X570390D01*
G01X570240D02*
X570370D01*
G01X570170Y657500D02*
X570240Y657490D01*
G01X570150Y657500D02*
X570170D01*
G01X569810Y658120D02*
X569780Y658310D01*
G01X569820Y658090D02*
X569810Y658120D01*
G01X569990Y657870D02*
X569820Y658090D01*
G01X570010Y657860D02*
X569990Y657870D01*
G01X570180Y657780D02*
X570010Y657860D01*
G01X570190Y657780D02*
X570180D01*
G01X570230Y657770D02*
X570190Y657780D01*
G01X570290Y657770D02*
X570230D01*
G01X570310D02*
X570290D01*
G01X570340Y658800D02*
X570350D01*
G01X570250D02*
X570340D01*
G01X570230Y658790D02*
X570250Y658800D01*
G01X569920Y658630D02*
X570230Y658790D01*
G01X569900Y658610D02*
X569920Y658630D01*
G01X569790Y658330D02*
X569900Y658610D01*
G01X569960Y659010D02*
X569950Y659000D01*
G01X569980Y659010D02*
X569960D01*
G01X570150Y659070D02*
X569980Y659010D01*
G01X570170Y659070D02*
X570150D01*
G01X570240Y659080D02*
X570170Y659070D01*
G01X570260Y659090D02*
X570240Y659080D01*
G01X570320Y659090D02*
X570260D01*
G01X570350Y659080D02*
X570320Y659090D01*
G01X569840Y658470D02*
X570780D01*
G01X570800Y658270D02*
X569790D01*
G01X569840Y658070D02*
X570750D01*
G01X570570Y657870D02*
X570000D01*
G01X570310Y657770D02*
X570440Y657790D01*
G01X570640Y658660D02*
X569990D01*
G01X570390Y659080D02*
X570590Y659030D01*
G01X570350Y659080D02*
X570390D01*
G01X569850Y659760D02*
X569840Y659750D01*
G01X569990Y659790D02*
X569850Y659760D01*
G01X570070Y659810D02*
X569990Y659790D01*
G01X570110Y660310D02*
X569850Y660590D01*
G01X570140Y660260D02*
X570110Y660310D01*
G01X570170Y660110D02*
X570140Y660260D01*
G01X570180Y660090D02*
X570170Y660110D01*
G01X570180Y660070D02*
Y660090D01*
G01X570160Y659900D02*
X570180Y660070D01*
G01X570160Y659890D02*
Y659900D01*
G01X570070Y659810D02*
X570160Y659890D01*
G01X570250Y661080D02*
X570760Y667310D01*
G01X570190Y661000D02*
X570250Y661080D01*
G01X570080Y661020D02*
X570190Y661000D01*
G01X569850Y667290D02*
X569830Y667260D01*
G01X570490Y667290D02*
X569850D01*
G01D02*
X570660Y668130D01*
G01X570240Y667680D02*
X572500D01*
G01Y667490D02*
X570050D01*
G01X569750Y667180D02*
X570390D01*
G01X570420Y663090D02*
X570880D01*
G01X570870Y662880D02*
X570400D01*
G01X570380Y662680D02*
X570850D01*
G01X570840Y662490D02*
X570370D01*
G01X570350Y662290D02*
X570820D01*
G01X570810Y662090D02*
X570340D01*
G01X570320Y661880D02*
X570790D01*
G01X570770Y661680D02*
X570310D01*
G01X570290Y661490D02*
X570750D01*
G01X570740Y661290D02*
X570270D01*
G01X570250Y661090D02*
X570720D01*
G01X570680Y660590D02*
X569850D01*
G01X570040Y660380D02*
X570680D01*
G01X570860Y660180D02*
X570160D01*
G01X570170Y659990D02*
X571050D01*
G01X570010Y671470D02*
X570000Y671480D01*
G01X570120Y671440D02*
X570010Y671470D01*
G01X570120Y671430D02*
Y671440D01*
G01X570230Y671390D02*
X570120Y671430D01*
G01X570240Y671380D02*
X570230Y671390D01*
G01X571100Y671380D02*
X570240D01*
G01X569960Y671490D02*
X570990D01*
G01X569900Y672030D02*
X569790Y672050D01*
G01X570140Y671950D02*
X569900Y672030D01*
G01X570250Y671910D02*
X570140Y671950D01*
G01X570310Y671890D02*
X570250Y671910D01*
G01X570850Y670830D02*
X570760Y670780D01*
G01X570840Y670930D02*
X570850Y670830D01*
G01X570770Y671040D02*
X570840Y670930D01*
G01X570750Y671060D02*
X570770Y671040D01*
G01X570450Y671280D02*
X570750Y671060D01*
G01X570440Y671290D02*
X570450Y671280D01*
G01X570430Y671290D02*
X570440D01*
G01X570240Y671380D02*
X570430Y671290D01*
G01X570770Y670790D02*
X572490D01*
G01X572470Y670990D02*
X570810D01*
G01X570580Y671180D02*
X572390D01*
G01X572500Y669180D02*
X570720D01*
G01X570690Y668160D02*
X570660Y668130D01*
G01X570720Y668220D02*
X570690Y668160D01*
G01X570720Y669240D02*
Y668220D01*
G01X570620Y668090D02*
X571290D01*
G01X571460Y668290D02*
X570720D01*
G01Y668490D02*
X571650D01*
G01X571840Y668680D02*
X570720D01*
G01Y668790D02*
X572500D01*
G01Y668990D02*
X570720D01*
G01X570830Y669320D02*
X570930Y669420D01*
G01X570760Y669320D02*
X570830D01*
G01X570720Y669280D02*
X570760Y669320D01*
G01X570720Y669240D02*
Y669280D01*
G01X570430Y667880D02*
X572500D01*
G01X571220Y667180D02*
X570750D01*
G01X570700Y667410D02*
X570590Y667390D01*
G01X570760Y667310D02*
X570700Y667410D01*
G01X570480Y663880D02*
X570950D01*
G01X570960Y663990D02*
X570490D01*
G01X570510Y664180D02*
X570980D01*
G01X570990Y664380D02*
X570530D01*
G01X570540Y664590D02*
X571010D01*
G01X571020Y664790D02*
X570560D01*
G01X570570Y664990D02*
X571040D01*
G01X571060Y665180D02*
X570590D01*
G01X570610Y665380D02*
X571070D01*
G01X571090Y665590D02*
X570620D01*
G01X570640Y665790D02*
X571110D01*
G01X571120Y665990D02*
X570660D01*
G01X570670Y666180D02*
X571140D01*
G01X571150Y666380D02*
X570690D01*
G01X570700Y666590D02*
X571170D01*
G01X571190Y666790D02*
X570720D01*
G01X570740Y666990D02*
X571200D01*
G01X570590Y667380D02*
X569950D01*
G01X570470Y663680D02*
X570940D01*
G01X570920Y663490D02*
X570450D01*
G01X570440Y663290D02*
X570900D01*
G01X570890Y663180D02*
X570430D01*
G01X570410Y662990D02*
X570880D01*
G01X570860Y662790D02*
X570390D01*
G01X570380Y662590D02*
X570850D01*
G01X570830Y662380D02*
X570360D01*
G01X570350Y662180D02*
X570810D01*
G01X570800Y661990D02*
X570330D01*
G01X570310Y661790D02*
X570780D01*
G01X570760Y661590D02*
X570300D01*
G01X570280Y661380D02*
X570750D01*
G01X570730Y661180D02*
X570260D01*
G01X569760Y660680D02*
X570690D01*
G01X570680Y660490D02*
X569950D01*
G01X570120Y660290D02*
X570760D01*
G01X570700Y660350D02*
X571660Y659330D01*
G01X571980Y658990D02*
X570650D01*
G01X570630Y659010D02*
X570590Y659030D01*
G01X570630Y659010D02*
X570940Y658750D01*
G01X570710Y658570D02*
X569880D01*
G01X569800Y658370D02*
X570790D01*
G01X570600Y658700D02*
X570350Y658800D01*
G01X570620Y658690D02*
X570600Y658700D01*
G01X570770Y658490D02*
X570620Y658690D01*
G01X570780Y658460D02*
X570770Y658490D01*
G01X570440Y658770D02*
X570170D01*
G01X570460Y657790D02*
X570440D01*
G01X570680Y657930D02*
X570460Y657790D01*
G01X570690Y657950D02*
X570680Y657930D01*
G01X570800Y658180D02*
X570690Y657950D01*
G01X570810Y658200D02*
X570800Y658180D01*
G01X570780Y658460D02*
X570810Y658200D01*
G01X570650Y657590D02*
X571670D01*
G01X570530Y656760D02*
X570520D01*
G01X570820Y656830D02*
X570530Y656760D01*
G01X570830Y656840D02*
X570820Y656830D01*
G01X571340Y657150D02*
X570830Y656840D01*
G01X570590Y657540D02*
X570630Y657560D01*
G01X570390Y657490D02*
X570590Y657540D01*
G01X570700Y657970D02*
X569920D01*
G01X569800Y658160D02*
X570800D01*
G01X570690Y660370D02*
X570670Y660440D01*
G01X570700Y660360D02*
X570690Y660370D01*
G01X570700Y660350D02*
Y660360D01*
G01X570460Y671830D02*
X570310Y671890D01*
G01X570470Y671820D02*
X570460Y671830D01*
G01X571720Y671540D02*
X571780Y671550D01*
G01X571710Y671540D02*
X571720D01*
G01X571600Y671510D02*
X571710Y671540D01*
G01X571590Y671510D02*
X571600D01*
G01X571460Y671460D02*
X571590Y671510D01*
G01X571460Y671450D02*
Y671460D01*
G01X571400Y671420D02*
X571460Y671450D01*
G01X571380Y671400D02*
X571400Y671420D01*
G01X571320Y671350D02*
X571380Y671400D01*
G01X571300Y671330D02*
X571320Y671350D01*
G01X571160Y671330D02*
X571300D01*
G01X570980Y671500D02*
X571160Y671330D01*
G01X570970Y671510D02*
X570980Y671500D01*
G01X570470Y671820D02*
X570970Y671510D01*
G01X571530Y671490D02*
X572050D01*
G01X572100Y670180D02*
X570940D01*
G01X570990Y670130D02*
X570930Y669420D01*
G01X570900Y669380D02*
X571450D01*
G01X571740Y670110D02*
X571770Y670100D01*
G01X571660Y670120D02*
X571740Y670110D01*
G01X571590Y670140D02*
X571660Y670120D01*
G01X571580Y670140D02*
X571590D01*
G01X571450Y670050D02*
X571580Y670140D01*
G01X571400Y669440D02*
X571450Y670050D01*
G01X571500Y669330D02*
X571400Y669440D01*
G01X571500Y670090D02*
X570990D01*
G01Y670130D02*
X570890Y670240D01*
G01X570530Y667990D02*
X571350D01*
G01X571320Y668140D02*
X571870Y668720D01*
G01X571290Y668090D02*
X571320Y668140D01*
G01X571290Y668050D02*
Y668090D01*
G01X571390Y667940D02*
X571290Y668050D01*
G01X571750Y668590D02*
X570720D01*
G01Y668380D02*
X571550D01*
G01X571360Y668180D02*
X570700D01*
G01X570720Y667380D02*
X571250D01*
G01X571240Y667370D02*
X570670Y660440D01*
G01X570950Y660090D02*
X570180D01*
G01X570150Y659880D02*
X571140D01*
G01X571230Y659790D02*
X569960D01*
G01X571430Y657240D02*
X571340Y657150D01*
G01X571490Y657310D02*
X571430Y657240D01*
G01X571620Y657500D02*
X571490Y657310D01*
G01X571740Y657750D02*
X571800Y657920D01*
G01X571700Y657650D02*
X571740Y657750D01*
G01X571700Y657640D02*
Y657650D01*
G01X571630Y657510D02*
X571700Y657640D01*
G01X571620Y657500D02*
X571630Y657510D01*
G01X571790Y657880D02*
X570975D01*
G01X570980D02*
X571040D01*
G01X570940Y657820D02*
X570630Y657560D01*
G01X570970Y657870D02*
X570940Y657820D01*
G01X570770Y657680D02*
X571720D01*
G01X571750Y657790D02*
X570960D01*
G01X571720D02*
X571750D01*
G01X570970Y658700D02*
X570940Y658750D01*
G01X571090Y658310D02*
X570970Y658700D01*
G01X571090Y658250D02*
Y658310D01*
G01X570970Y657870D02*
X571090Y658250D01*
G01X570900Y658790D02*
X572160D01*
G01X572350Y658590D02*
X571010D01*
G01X571070Y658380D02*
X572530D01*
G01X571830Y658180D02*
X571070D01*
G01X571010Y657990D02*
X571810D01*
G01X570900Y656880D02*
X569740D01*
G01X570440Y663380D02*
X570910D01*
G01X570930Y663590D02*
X570460D01*
G01X570480Y663790D02*
X570940D01*
G01X570970Y664090D02*
X570500D01*
G01X570510Y664290D02*
X570980D01*
G01X571000Y664490D02*
X570530D01*
G01X570550Y664680D02*
X571010D01*
G01X571030Y664880D02*
X570570D01*
G01X570580Y665090D02*
X571050D01*
G01X571070Y665290D02*
X570600D01*
G01X570610Y665490D02*
X571080D01*
G01X571100Y665680D02*
X570630D01*
G01X570650Y665880D02*
X571110D01*
G01X571130Y666090D02*
X570660D01*
G01X570680Y666290D02*
X571140D01*
G01X571160Y666490D02*
X570700D01*
G01X570710Y666680D02*
X571180D01*
G01X571200Y666880D02*
X570730D01*
G01X570740Y667090D02*
X571210D01*
G01X571230Y667290D02*
X570760D01*
G01X571240Y667370D02*
X571330Y667460D01*
G01X571660Y669320D02*
X571780D01*
G01X571500Y669330D02*
X571660Y669320D01*
G01X571410Y669490D02*
X570940D01*
G01X570950Y669590D02*
X571420D01*
G01Y669680D02*
X570960D01*
G01Y669790D02*
X571430D01*
G01X571440Y669880D02*
X570970D01*
G01X570980Y669990D02*
X571450D01*
G01X571850Y671550D02*
X571780D01*
G01X571860Y671540D02*
X571850Y671550D01*
G01X572120Y671470D02*
X571860Y671540D01*
G01X572130Y671460D02*
X572120Y671470D01*
G01X572330Y671290D02*
X572130Y671460D01*
G01X572340Y671280D02*
X572330Y671290D01*
G01X572460Y671050D02*
X572340Y671280D01*
G01X572470Y671030D02*
X572460Y671050D01*
G01X572490Y670750D02*
X572470Y671030D01*
G01X572490Y670740D02*
Y670750D01*
G01X572410Y670480D02*
X572490Y670740D01*
G01X572400Y670470D02*
X572410Y670480D01*
G01X572240Y670270D02*
X572400Y670470D01*
G01X572230Y670250D02*
X572240Y670270D01*
G01X572000Y670130D02*
X572230Y670250D01*
G01X571980Y670130D02*
X572000D01*
G01X571860Y670110D02*
X571980Y670130D01*
G01X571850Y670110D02*
X571860D01*
G01X571790Y670100D02*
X571850Y670110D01*
G01X571770Y670100D02*
X571790D01*
G01X571360Y671380D02*
X572220D01*
G01X572330Y671290D02*
X570440D01*
G01X570720Y671090D02*
X572440D01*
G01X572480Y670880D02*
X570850D01*
G01X572750Y670290D02*
X573380D01*
G01X573480Y670380D02*
X572850D01*
G01X572940Y670490D02*
X573580D01*
G01X573670Y670590D02*
X573040D01*
G01X573140Y670680D02*
X573770D01*
G01X573860Y670790D02*
X573240D01*
G01X573330Y670880D02*
X573960D01*
G01X574060Y670990D02*
X573430D01*
G01X573530Y671090D02*
X574160D01*
G01X574350Y671290D02*
X573720D01*
G01X573910Y671490D02*
X574540D01*
G01X573290Y670180D02*
X572660D01*
G01X572560Y670090D02*
X573190D01*
G01X573090Y669990D02*
X572460D01*
G01X572360Y669880D02*
X573000D01*
G01X572900Y669790D02*
X572270D01*
G01X572170Y669680D02*
X572810D01*
G01X572710Y669590D02*
X572080D01*
G01X571980Y669490D02*
X572610D01*
G01X572460Y667460D02*
X571330D01*
G01X572500Y667480D02*
X572460Y667460D01*
G01X572500Y667490D02*
Y667480D01*
G01Y669310D02*
Y667490D01*
G01Y669320D02*
Y669310D01*
G01X572530Y669400D02*
X572500Y669320D01*
G01X571980Y668740D02*
X571870Y668720D01*
G01X572040Y668640D02*
X571980Y668740D01*
G01X572040Y668040D02*
Y668640D01*
G01X571940Y667940D02*
X572040Y668040D01*
G01X571390Y667940D02*
X571940D01*
G01X572010Y668680D02*
X572500D01*
G01Y668590D02*
X572040D01*
G01Y668490D02*
X572500D01*
G01Y668380D02*
X572040D01*
G01Y668290D02*
X572500D01*
G01Y668180D02*
X572040D01*
G01Y668090D02*
X572500D01*
G01Y667990D02*
X571990D01*
G01X572500Y667790D02*
X570330D01*
G01X570140Y667590D02*
X572500D01*
G01Y668880D02*
X570720D01*
G01Y669090D02*
X572500D01*
G01Y669290D02*
X570720D01*
G01X571780Y669320D02*
X571850Y669350D01*
G01X571880Y669380D02*
X572520D01*
G01X571880Y659090D02*
X570330D01*
G01X570770Y658880D02*
X572070D01*
G01X572250Y658680D02*
X570980D01*
G01X571030Y658490D02*
X572440D01*
G01X572630Y658290D02*
X571940D01*
G01X571800Y657940D02*
Y657920D01*
G01X571840Y658210D02*
X571800Y657940D01*
G01X571900Y658290D02*
X571840Y658210D01*
G01X571820Y658090D02*
X571040D01*
G01X571900Y658290D02*
X572010Y658270D01*
G01X571090Y658290D02*
X571900D01*
G01X572090Y658180D02*
X572720D01*
G01X572810Y658090D02*
X572180D01*
G01X572270Y657990D02*
X572910D01*
G01X572960Y657880D02*
X573000D01*
G01X573010D02*
X572370D01*
G01X572460Y657790D02*
X573095D01*
G01X573090D02*
X573040D01*
G01X573195Y657680D02*
X572550D01*
G01X572640Y657590D02*
X573280D01*
G01X573370Y657490D02*
X572735D01*
G01X572835Y657380D02*
X573470D01*
G01X573560Y657290D02*
X572920D01*
G01X573025Y657180D02*
X573650D01*
G01X573750Y657090D02*
X573110D01*
G01X573200Y656990D02*
X573840D01*
G01X573930Y656880D02*
X573290D01*
G01X573380Y656790D02*
X574030D01*
G01X574210Y656590D02*
X573570D01*
G01X573480Y656680D02*
X574120D01*
G01X574300Y656490D02*
X573660D01*
G01X573760Y656380D02*
X574400D01*
G01X574490Y656290D02*
X573850D01*
G01X573940Y656180D02*
X574580D01*
G01X574680Y656090D02*
X574030D01*
G01X574130Y655990D02*
X574770D01*
G01X574860Y655880D02*
X574220D01*
G01X574310Y655790D02*
X574960D01*
G01X575050Y655680D02*
X574410D01*
G01X574500Y655590D02*
X575140D01*
G01X575330Y655380D02*
X574690D01*
G01X574870Y655180D02*
X575480D01*
G01X575470Y655240D02*
X571660Y659330D01*
G01X575140Y654900D02*
X575160Y654880D01*
G01X572010Y658270D02*
X575140Y654900D01*
G01X575060Y654990D02*
X575280D01*
G01X571850Y669350D02*
X576430Y674090D01*
G01X576460Y673480D02*
X572530Y669400D01*
G01X573620Y671180D02*
X574250D01*
G01X574440Y671380D02*
X573810D01*
G01X574010Y671590D02*
X574640D01*
G01X574740Y671680D02*
X574110D01*
G01X574200Y671790D02*
X574830D01*
G01X574930Y671880D02*
X574300D01*
G01X574400Y671990D02*
X575020D01*
G01X575120Y672090D02*
X574490D01*
G01X574680Y672290D02*
X575310D01*
G01X575510Y672490D02*
X574880D01*
G01X575070Y672680D02*
X575700D01*
G01X575600Y672590D02*
X574980D01*
G01X575170Y672790D02*
X575790D01*
G01X575890Y672880D02*
X575260D01*
G01X575360Y672990D02*
X575990D01*
G01X576090Y673090D02*
X575460D01*
G01X575550Y673180D02*
X576180D01*
G01X576280Y673290D02*
X575650D01*
G01X575750Y673380D02*
X576370D01*
G01X576480Y673590D02*
X575940D01*
G01X576470Y673510D02*
X576480Y673590D01*
G01X576460Y673480D02*
X576470Y673510D01*
G01X575850Y673490D02*
X576460D01*
G01X576480Y674080D02*
X576430Y674090D01*
G01X576480Y673590D02*
Y674080D01*
G01X576420Y674090D02*
X576460D01*
G01X576480Y673990D02*
X576330D01*
G01X576230Y673880D02*
X576480D01*
G01Y673790D02*
X576130D01*
G01X576040Y673680D02*
X576480D01*
G01X575410Y672380D02*
X574780D01*
G01X574590Y672180D02*
X575220D01*
G01X575240Y655490D02*
X574590D01*
G01X574780Y655290D02*
X575420D01*
G01X575190Y654900D02*
X575160Y654880D01*
G01X575480Y655190D02*
X575190Y654900D01*
G01X575490Y655210D02*
X575480Y655190D01*
G01Y655220D02*
X575490Y655210D01*
G01X575470Y655240D02*
X575480Y655220D01*
G01X574960Y655090D02*
X575380D01*
G54D11*
G01X586182Y581489D02*
Y591489D01*
X589382D01*
X590449Y590989D01*
X591249Y589822D01*
X591516Y588489D01*
X591249Y587156D01*
X590582Y586156D01*
X589382Y585655D01*
X586182D01*
G01X596516Y591489D02*
X599849Y581489D01*
X603182Y591489D01*
G01X610849D02*
Y581489D01*
G01X607782Y591489D02*
X613916D01*
G54D21*
G01X145579Y-328699D02*
Y-346199D01*
X154313D01*
G01X167446Y-334533D02*
Y-346199D01*
G01Y-329866D02*
X167009Y-329574D01*
Y-328991D01*
X167446Y-328699D01*
X167883Y-328991D01*
Y-329574D01*
X167446Y-329866D01*
G01X181889Y-350574D02*
X183418Y-351741D01*
X185164Y-352032D01*
X186692Y-351741D01*
X188003Y-350283D01*
X188876Y-348241D01*
Y-334533D01*
G01Y-336866D02*
X188003Y-335699D01*
X186692Y-334824D01*
X185164Y-334533D01*
X183418Y-335116D01*
X182326Y-336282D01*
X181452Y-338324D01*
X181016Y-340366D01*
X181234Y-342116D01*
X182108Y-344158D01*
X183418Y-345616D01*
X185164Y-346199D01*
X186474Y-345907D01*
X188003Y-344741D01*
X188876Y-343575D01*
G01X198734Y-346199D02*
Y-328699D01*
G01Y-337157D02*
X199826Y-335699D01*
X200918Y-334824D01*
X202664Y-334533D01*
X203974Y-334824D01*
X205503Y-335991D01*
X206158Y-337741D01*
Y-346199D01*
G01X219946Y-328699D02*
Y-346199D01*
G01X216889Y-334533D02*
X223003D01*
G01X233734Y-346199D02*
Y-334533D01*
G01Y-337449D02*
X234608Y-335991D01*
X235918Y-334824D01*
X237664Y-334533D01*
X239192Y-334824D01*
X240503Y-335991D01*
X241158Y-338032D01*
Y-346199D01*
G01X254946Y-334533D02*
Y-346199D01*
G01Y-329866D02*
X254509Y-329574D01*
Y-328991D01*
X254946Y-328699D01*
X255383Y-328991D01*
Y-329574D01*
X254946Y-329866D01*
G01X268734Y-346199D02*
Y-334533D01*
G01Y-337449D02*
X269608Y-335991D01*
X270918Y-334824D01*
X272664Y-334533D01*
X274192Y-334824D01*
X275503Y-335991D01*
X276158Y-338032D01*
Y-346199D01*
G01X286889Y-350574D02*
X288418Y-351741D01*
X290164Y-352032D01*
X291692Y-351741D01*
X293003Y-350283D01*
X293876Y-348241D01*
Y-334533D01*
G01Y-336866D02*
X293003Y-335699D01*
X291692Y-334824D01*
X290164Y-334533D01*
X288418Y-335116D01*
X287326Y-336282D01*
X286452Y-338324D01*
X286016Y-340366D01*
X286234Y-342116D01*
X287108Y-344158D01*
X288418Y-345616D01*
X290164Y-346199D01*
X291474Y-345907D01*
X293003Y-344741D01*
X293876Y-343575D01*
G01X320579Y-346199D02*
Y-328699D01*
X325819D01*
X327566Y-329574D01*
X328876Y-331616D01*
X329313Y-333949D01*
X328876Y-336282D01*
X327784Y-338032D01*
X325819Y-338908D01*
X320579D01*
G01X346813Y-346199D02*
X338079D01*
Y-328699D01*
X346813D01*
G01X343319Y-337157D02*
X338079D01*
G01X361692Y-336866D02*
X362566Y-335991D01*
X363221Y-334533D01*
X363658Y-332490D01*
X363221Y-330741D01*
X362348Y-329574D01*
X360819Y-328699D01*
X354924D01*
Y-346199D01*
X362129D01*
X363658Y-345033D01*
X364531Y-343282D01*
X364968Y-341241D01*
X364531Y-339199D01*
X363221Y-337449D01*
X361692Y-336866D01*
X354924D01*
G01X390579Y-346199D02*
Y-328699D01*
X395819D01*
X397566Y-329574D01*
X398876Y-331616D01*
X399313Y-333949D01*
X398876Y-336282D01*
X397784Y-338032D01*
X395819Y-338908D01*
X390579D01*
G01X406769Y-346199D02*
Y-328699D01*
X412446Y-343282D01*
X418123Y-328699D01*
Y-346199D01*
G01X434749Y-330158D02*
X433439Y-329282D01*
X431911Y-328699D01*
X430164D01*
X428199Y-329574D01*
X426671Y-331032D01*
X425579Y-332783D01*
X424706Y-335699D01*
X424487Y-338324D01*
X424924Y-340949D01*
X425579Y-342699D01*
X426889Y-344449D01*
X428418Y-345616D01*
X429946Y-346199D01*
X431474D01*
X433003Y-345616D01*
X434313Y-344741D01*
X435405Y-343575D01*
G01X460579Y-346199D02*
Y-328699D01*
X465819D01*
X467566Y-329574D01*
X468876Y-331616D01*
X469313Y-333949D01*
X468876Y-336282D01*
X467784Y-338032D01*
X465819Y-338908D01*
X460579D01*
G01X476987Y-328699D02*
X482446Y-346199D01*
X487905Y-328699D01*
G01X499946D02*
Y-346199D01*
G01X494924Y-328699D02*
X504968D01*
G01X284269Y-301199D02*
Y-283699D01*
X289946Y-298282D01*
X295623Y-283699D01*
Y-301199D01*
G01X307446D02*
X306136Y-300907D01*
X304826Y-299741D01*
X303952Y-297699D01*
X303516Y-295366D01*
X303952Y-293032D01*
X304826Y-290991D01*
X306136Y-289824D01*
X307446Y-289533D01*
X308756Y-289824D01*
X310066Y-290991D01*
X310939Y-293032D01*
X311158Y-295366D01*
X310939Y-297699D01*
X310066Y-299741D01*
X308756Y-300907D01*
X307446Y-301199D01*
G01X328876Y-283699D02*
Y-301199D01*
G01Y-298575D02*
X328003Y-300033D01*
X326692Y-300907D01*
X325164Y-301199D01*
X323418Y-300616D01*
X322108Y-299158D01*
X321234Y-297408D01*
X321016Y-295366D01*
X321234Y-293324D01*
X322108Y-291574D01*
X323418Y-290116D01*
X325164Y-289533D01*
X326692Y-289824D01*
X327784Y-290408D01*
X328876Y-291574D01*
G01X339171Y-293324D02*
X346158D01*
X345503Y-291282D01*
X344411Y-290116D01*
X342883Y-289533D01*
X341354Y-289824D01*
X340044Y-290699D01*
X339171Y-292741D01*
X338734Y-294491D01*
Y-296241D01*
X339171Y-297991D01*
X340263Y-299741D01*
X341573Y-300907D01*
X343101Y-301199D01*
X344629Y-300616D01*
X346158Y-298866D01*
G01X359946Y-301199D02*
Y-283699D01*
G01X556346Y-346199D02*
Y-328699D01*
X553726Y-332199D01*
G01Y-346199D02*
X558966D01*
G01X569043Y-343575D02*
X570352Y-345033D01*
X571881Y-345907D01*
X573846Y-346199D01*
X575811Y-345616D01*
X577339Y-344449D01*
X578431Y-342408D01*
X578649Y-340074D01*
X578213Y-337741D01*
X577121Y-336282D01*
X575592Y-335116D01*
X574064Y-334824D01*
X572536Y-335116D01*
X570571Y-336282D01*
X571226Y-328699D01*
X577121D01*
G01X591346Y-346199D02*
Y-328699D01*
X588726Y-332199D01*
G01Y-346199D02*
X593966D01*
G01X608846Y-328699D02*
X607099Y-329282D01*
X605789Y-330741D01*
X604916Y-332490D01*
X604261Y-334824D01*
X604043Y-337449D01*
X604261Y-340074D01*
X604916Y-342408D01*
X605789Y-344158D01*
X607099Y-345616D01*
X608846Y-346199D01*
X610592Y-345616D01*
X611903Y-344158D01*
X612776Y-342408D01*
X613431Y-340074D01*
X613649Y-337449D01*
X613431Y-334824D01*
X612776Y-332490D01*
X611903Y-330741D01*
X610592Y-329282D01*
X608846Y-328699D01*
G01X621543Y-343575D02*
X622852Y-345033D01*
X624381Y-345907D01*
X626346Y-346199D01*
X628311Y-345616D01*
X629839Y-344449D01*
X630931Y-342408D01*
X631149Y-340074D01*
X630713Y-337741D01*
X629621Y-336282D01*
X628092Y-335116D01*
X626564Y-334824D01*
X625036Y-335116D01*
X623071Y-336282D01*
X623726Y-328699D01*
X629621D01*
G01X543229Y-301199D02*
Y-283699D01*
X548469D01*
X550216Y-284574D01*
X551526Y-286616D01*
X551963Y-288949D01*
X551526Y-291282D01*
X550434Y-293032D01*
X548469Y-293908D01*
X543229D01*
G01X569899Y-285158D02*
X568589Y-284282D01*
X567061Y-283699D01*
X565314D01*
X563349Y-284574D01*
X561821Y-286032D01*
X560729Y-287783D01*
X559856Y-290699D01*
X559637Y-293324D01*
X560074Y-295949D01*
X560729Y-297699D01*
X562039Y-299449D01*
X563568Y-300616D01*
X565096Y-301199D01*
X566624D01*
X568153Y-300616D01*
X569463Y-299741D01*
X570555Y-298575D01*
G01X584342Y-291866D02*
X585216Y-290991D01*
X585871Y-289533D01*
X586308Y-287490D01*
X585871Y-285741D01*
X584998Y-284574D01*
X583469Y-283699D01*
X577574D01*
Y-301199D01*
X584779D01*
X586308Y-300033D01*
X587181Y-298282D01*
X587618Y-296241D01*
X587181Y-294199D01*
X585871Y-292449D01*
X584342Y-291866D01*
X577574D01*
G01X593546Y-307032D02*
X606646D01*
G01X612574Y-301199D02*
Y-283699D01*
X622618Y-301199D01*
Y-283699D01*
G01X635096Y-301199D02*
X633349Y-300907D01*
X631821Y-299741D01*
X630511Y-297991D01*
X629637Y-295949D01*
X629201Y-293616D01*
Y-291282D01*
X629637Y-288949D01*
X630511Y-286907D01*
X631821Y-285158D01*
X633349Y-283991D01*
X635096Y-283699D01*
X636842Y-283991D01*
X638371Y-285158D01*
X639681Y-286907D01*
X640555Y-288949D01*
X640991Y-291282D01*
Y-293616D01*
X640555Y-295949D01*
X639681Y-297991D01*
X638371Y-299741D01*
X636842Y-300907D01*
X635096Y-301199D01*
G01X685937Y-283699D02*
X691396Y-301199D01*
X696855Y-283699D01*
G01X713263Y-301199D02*
X704529D01*
Y-283699D01*
X713263D01*
G01X709769Y-292157D02*
X704529D01*
G01X722029Y-301199D02*
Y-283699D01*
X727488D01*
X729234Y-284574D01*
X730326Y-285741D01*
X730763Y-288074D01*
X730326Y-290408D01*
X729016Y-291866D01*
X727488Y-292741D01*
X722029D01*
G01X727488D02*
X730763Y-301199D01*
G01X743896Y-301782D02*
X743459Y-301491D01*
Y-300907D01*
X743896Y-300616D01*
X744333Y-300907D01*
Y-301491D01*
X743896Y-301782D01*
G01X717646Y-346199D02*
Y-328699D01*
X715026Y-332199D01*
G01Y-346199D02*
X720266D01*
G01X823846Y-328699D02*
Y-346199D01*
G01X818824Y-328699D02*
X828868D01*
G01X836761Y-343866D02*
X838508Y-345324D01*
X840473Y-346199D01*
X842219D01*
X843966Y-345324D01*
X845276Y-343866D01*
X845931Y-341824D01*
X845494Y-339783D01*
X844403Y-338032D01*
X842438Y-336866D01*
X839818Y-336282D01*
X838289Y-335116D01*
X837634Y-333074D01*
X838071Y-331032D01*
X839163Y-329574D01*
X840691Y-328699D01*
X842219D01*
X843748Y-329282D01*
X845058Y-330741D01*
G01X856226Y-328699D02*
X861466D01*
G01X858846D02*
Y-346199D01*
G01X856226D02*
X861466D01*
G01X871979Y-328699D02*
Y-346199D01*
X880713D01*
G01X889043D02*
Y-328699D01*
G01X897339D02*
X889043Y-339491D01*
G01X898649Y-346199D02*
X892754Y-334533D01*
G01X819479Y-283699D02*
Y-301199D01*
X828213D01*
G01X845276D02*
Y-289533D01*
G01Y-291574D02*
X844403Y-290408D01*
X843092Y-289824D01*
X841564Y-289533D01*
X840036Y-290116D01*
X838726Y-291282D01*
X837852Y-293032D01*
X837416Y-295366D01*
X837852Y-297699D01*
X838726Y-299449D01*
X840036Y-300616D01*
X841564Y-301199D01*
X843092Y-300907D01*
X844403Y-300033D01*
X845276Y-298866D01*
G01X854261Y-306449D02*
X855571Y-307032D01*
X857318Y-306449D01*
X858409Y-305283D01*
X859283Y-303824D01*
X860592Y-299158D01*
X863431Y-289533D01*
G01X856444D02*
X860592Y-299158D01*
G01X873071Y-293324D02*
X880058D01*
X879403Y-291282D01*
X878311Y-290116D01*
X876783Y-289533D01*
X875254Y-289824D01*
X873944Y-290699D01*
X873071Y-292741D01*
X872634Y-294491D01*
Y-296241D01*
X873071Y-297991D01*
X874163Y-299741D01*
X875473Y-300907D01*
X877001Y-301199D01*
X878529Y-300616D01*
X880058Y-298866D01*
G01X890789Y-301199D02*
Y-289533D01*
G01Y-291866D02*
X891881Y-290699D01*
X892973Y-289824D01*
X894501Y-289533D01*
X895592Y-289824D01*
X896903Y-290699D01*
G01X959846Y-328699D02*
X962902Y-346199D01*
X966396Y-328699D01*
X969889Y-346199D01*
X972946Y-328699D01*
G01X979529Y-346199D02*
Y-328699D01*
X984769D01*
X986516Y-329574D01*
X987826Y-331616D01*
X988263Y-333949D01*
X987826Y-336282D01*
X986734Y-338032D01*
X984769Y-338908D01*
X979529D01*
G01X996811Y-346199D02*
Y-328699D01*
G01X1005981D02*
Y-346199D01*
G01Y-337449D02*
X996811D01*
G01X1016058Y-340366D02*
X1021734D01*
G01X1031593Y-346199D02*
Y-328699D01*
G01X1039889D02*
X1031593Y-339491D01*
G01X1041199Y-346199D02*
X1035304Y-334533D01*
G01X1058263Y-346199D02*
X1049529D01*
Y-328699D01*
X1058263D01*
G01X1054769Y-337157D02*
X1049529D01*
G01X1066374Y-346199D02*
Y-328699D01*
X1076418Y-346199D01*
Y-328699D01*
G01X1083874Y-346199D02*
Y-328699D01*
X1093918Y-346199D01*
Y-328699D01*
G01X961593Y-301199D02*
Y-283699D01*
X965959D01*
X967706Y-284574D01*
X969016Y-285741D01*
X970108Y-287490D01*
X970981Y-289533D01*
X971199Y-292449D01*
X970981Y-295366D01*
X970108Y-297408D01*
X969016Y-299158D01*
X967706Y-300324D01*
X965959Y-301199D01*
X961593D01*
G01X980621Y-293324D02*
X987608D01*
X986953Y-291282D01*
X985861Y-290116D01*
X984333Y-289533D01*
X982804Y-289824D01*
X981494Y-290699D01*
X980621Y-292741D01*
X980184Y-294491D01*
Y-296241D01*
X980621Y-297991D01*
X981713Y-299741D01*
X983023Y-300907D01*
X984551Y-301199D01*
X986079Y-300616D01*
X987608Y-298866D01*
G01X998121Y-299158D02*
X999213Y-300324D01*
X1000741Y-301199D01*
X1002051D01*
X1003361Y-300616D01*
X1004234Y-299741D01*
X1004671Y-298575D01*
X1004453Y-296824D01*
X1003579Y-295949D01*
X999649Y-294199D01*
X998776Y-292157D01*
X999213Y-290699D01*
X1000086Y-289824D01*
X1001396Y-289533D01*
X1002706Y-289824D01*
X1004016Y-290699D01*
G01X1018896Y-289533D02*
Y-301199D01*
G01Y-284866D02*
X1018459Y-284574D01*
Y-283991D01*
X1018896Y-283699D01*
X1019333Y-283991D01*
Y-284574D01*
X1018896Y-284866D01*
G01X1033339Y-305574D02*
X1034868Y-306741D01*
X1036614Y-307032D01*
X1038142Y-306741D01*
X1039453Y-305283D01*
X1040326Y-303241D01*
Y-289533D01*
G01Y-291866D02*
X1039453Y-290699D01*
X1038142Y-289824D01*
X1036614Y-289533D01*
X1034868Y-290116D01*
X1033776Y-291282D01*
X1032902Y-293324D01*
X1032466Y-295366D01*
X1032684Y-297116D01*
X1033558Y-299158D01*
X1034868Y-300616D01*
X1036614Y-301199D01*
X1037924Y-300907D01*
X1039453Y-299741D01*
X1040326Y-298575D01*
G01X1050184Y-301199D02*
Y-289533D01*
G01Y-292449D02*
X1051058Y-290991D01*
X1052368Y-289824D01*
X1054114Y-289533D01*
X1055642Y-289824D01*
X1056953Y-290991D01*
X1057608Y-293032D01*
Y-301199D01*
G01X1068121Y-293324D02*
X1075108D01*
X1074453Y-291282D01*
X1073361Y-290116D01*
X1071833Y-289533D01*
X1070304Y-289824D01*
X1068994Y-290699D01*
X1068121Y-292741D01*
X1067684Y-294491D01*
Y-296241D01*
X1068121Y-297991D01*
X1069213Y-299741D01*
X1070523Y-300907D01*
X1072051Y-301199D01*
X1073579Y-300616D01*
X1075108Y-298866D01*
G01X1085839Y-301199D02*
Y-289533D01*
G01Y-291866D02*
X1086931Y-290699D01*
X1088023Y-289824D01*
X1089551Y-289533D01*
X1090642Y-289824D01*
X1091953Y-290699D01*
G01X1132596Y-346199D02*
Y-328699D01*
X1129976Y-332199D01*
G01Y-346199D02*
X1135216D01*
G01X1150096D02*
Y-328699D01*
X1147476Y-332199D01*
G01Y-346199D02*
X1152716D01*
G01X1163666Y-346782D02*
X1171526Y-328699D01*
G01X1185096Y-346199D02*
Y-328699D01*
X1182476Y-332199D01*
G01Y-346199D02*
X1187716D01*
G01X1198448Y-338908D02*
X1199976Y-336866D01*
X1201286Y-335699D01*
X1203033Y-335116D01*
X1204561Y-335699D01*
X1205653Y-336866D01*
X1206526Y-338616D01*
X1206744Y-340657D01*
X1206526Y-342408D01*
X1205653Y-344158D01*
X1204342Y-345616D01*
X1202814Y-346199D01*
X1201068Y-345616D01*
X1199539Y-343866D01*
X1198666Y-341241D01*
X1198448Y-338324D01*
X1198884Y-334533D01*
X1199539Y-332490D01*
X1200631Y-330449D01*
X1202159Y-328991D01*
X1203688Y-328699D01*
X1205216Y-329282D01*
X1206308Y-330741D01*
G01X1216166Y-346782D02*
X1224026Y-328699D01*
G01X1233448Y-331616D02*
X1234758Y-329866D01*
X1236286Y-328991D01*
X1238033Y-328699D01*
X1240216Y-329282D01*
X1241744Y-330741D01*
X1242181Y-332490D01*
X1241963Y-334241D01*
X1241089Y-335699D01*
X1236723Y-338616D01*
X1234758Y-340657D01*
X1233448Y-343575D01*
X1233011Y-346199D01*
X1242181D01*
G01X1255096Y-328699D02*
X1253349Y-329282D01*
X1252039Y-330741D01*
X1251166Y-332490D01*
X1250511Y-334824D01*
X1250293Y-337449D01*
X1250511Y-340074D01*
X1251166Y-342408D01*
X1252039Y-344158D01*
X1253349Y-345616D01*
X1255096Y-346199D01*
X1256842Y-345616D01*
X1258153Y-344158D01*
X1259026Y-342408D01*
X1259681Y-340074D01*
X1259899Y-337449D01*
X1259681Y-334824D01*
X1259026Y-332490D01*
X1258153Y-330741D01*
X1256842Y-329282D01*
X1255096Y-328699D01*
G01X1272596Y-346199D02*
Y-328699D01*
X1269976Y-332199D01*
G01Y-346199D02*
X1275216D01*
G01X1285948Y-338908D02*
X1287476Y-336866D01*
X1288786Y-335699D01*
X1290533Y-335116D01*
X1292061Y-335699D01*
X1293153Y-336866D01*
X1294026Y-338616D01*
X1294244Y-340657D01*
X1294026Y-342408D01*
X1293153Y-344158D01*
X1291842Y-345616D01*
X1290314Y-346199D01*
X1288568Y-345616D01*
X1287039Y-343866D01*
X1286166Y-341241D01*
X1285948Y-338324D01*
X1286384Y-334533D01*
X1287039Y-332490D01*
X1288131Y-330449D01*
X1289659Y-328991D01*
X1291188Y-328699D01*
X1292716Y-329282D01*
X1293808Y-330741D01*
G01X1180293Y-301199D02*
Y-283699D01*
X1184659D01*
X1186406Y-284574D01*
X1187716Y-285741D01*
X1188808Y-287490D01*
X1189681Y-289533D01*
X1189899Y-292449D01*
X1189681Y-295366D01*
X1188808Y-297408D01*
X1187716Y-299158D01*
X1186406Y-300324D01*
X1184659Y-301199D01*
X1180293D01*
G01X1206526D02*
Y-289533D01*
G01Y-291574D02*
X1205653Y-290408D01*
X1204342Y-289824D01*
X1202814Y-289533D01*
X1201286Y-290116D01*
X1199976Y-291282D01*
X1199102Y-293032D01*
X1198666Y-295366D01*
X1199102Y-297699D01*
X1199976Y-299449D01*
X1201286Y-300616D01*
X1202814Y-301199D01*
X1204342Y-300907D01*
X1205653Y-300033D01*
X1206526Y-298866D01*
G01X1220096Y-283699D02*
Y-301199D01*
G01X1217039Y-289533D02*
X1223153D01*
G01X1234321Y-293324D02*
X1241308D01*
X1240653Y-291282D01*
X1239561Y-290116D01*
X1238033Y-289533D01*
X1236504Y-289824D01*
X1235194Y-290699D01*
X1234321Y-292741D01*
X1233884Y-294491D01*
Y-296241D01*
X1234321Y-297991D01*
X1235413Y-299741D01*
X1236723Y-300907D01*
X1238251Y-301199D01*
X1239779Y-300616D01*
X1241308Y-298866D01*
G01X25583Y98614D02*
Y146714D01*
X22083D01*
Y156514D01*
X25583D01*
Y195614D01*
X97583D01*
Y156514D01*
X101083D01*
Y146714D01*
X97583D01*
Y98614D01*
X25583D01*
G01X16000Y138033D02*
X11000D01*
Y140117D01*
X11250Y140783D01*
X11583Y141200D01*
X12250Y141367D01*
X12917Y141200D01*
X13333Y140700D01*
X13583Y140117D01*
Y138033D01*
G01Y140117D02*
X16000Y141367D01*
G01X15000Y143633D02*
X15500Y144050D01*
X15833Y144550D01*
X16000Y145133D01*
X15833Y145800D01*
X15500Y146300D01*
X15000Y146800D01*
X14333Y146967D01*
X11000D01*
G01X16000Y151900D02*
X11000D01*
X14583Y148817D01*
Y152983D01*
G01X15250Y154667D02*
X15667Y155167D01*
X15917Y155750D01*
X16000Y156500D01*
X15833Y157250D01*
X15500Y157833D01*
X14917Y158250D01*
X14250Y158333D01*
X13583Y158167D01*
X13167Y157750D01*
X12833Y157167D01*
X12750Y156583D01*
X12833Y156000D01*
X13167Y155250D01*
X11000Y155500D01*
Y157750D01*
G01X9267Y174459D02*
X9017Y174584D01*
X8725Y174667D01*
X8392D01*
X8017Y174542D01*
X7725Y174334D01*
X7517Y174084D01*
X7350Y173667D01*
X7308Y173292D01*
X7392Y172917D01*
X7517Y172667D01*
X7767Y172417D01*
X8058Y172250D01*
X8350Y172167D01*
X8642D01*
X8933Y172250D01*
X9183Y172375D01*
X9392Y172542D01*
G01X10533Y172667D02*
X10783Y172375D01*
X11117Y172209D01*
X11492Y172167D01*
X11825Y172209D01*
X12158Y172417D01*
X12367Y172667D01*
X12408Y172917D01*
X12325Y173209D01*
X12033Y173417D01*
X11742Y173500D01*
X11367D01*
G01X11742D02*
X11992Y173625D01*
X12200Y173834D01*
X12283Y174084D01*
X12200Y174334D01*
X11992Y174542D01*
X11617Y174667D01*
X11242Y174625D01*
X10867Y174459D01*
G01X13633Y172667D02*
X13883Y172375D01*
X14217Y172209D01*
X14592Y172167D01*
X14925Y172209D01*
X15258Y172417D01*
X15467Y172667D01*
X15508Y172917D01*
X15425Y173209D01*
X15133Y173417D01*
X14842Y173500D01*
X14467D01*
G01X14842D02*
X15092Y173625D01*
X15300Y173834D01*
X15383Y174084D01*
X15300Y174334D01*
X15092Y174542D01*
X14717Y174667D01*
X14342Y174625D01*
X13967Y174459D01*
G01X17650Y174667D02*
X17317Y174584D01*
X17067Y174375D01*
X16900Y174125D01*
X16775Y173792D01*
X16733Y173417D01*
X16775Y173042D01*
X16900Y172709D01*
X17067Y172459D01*
X17317Y172250D01*
X17650Y172167D01*
X17983Y172250D01*
X18233Y172459D01*
X18400Y172709D01*
X18525Y173042D01*
X18567Y173417D01*
X18525Y173792D01*
X18400Y174125D01*
X18233Y174375D01*
X17983Y174584D01*
X17650Y174667D01*
G01X9067Y161166D02*
Y163666D01*
X10108D01*
X10442Y163541D01*
X10650Y163374D01*
X10733Y163041D01*
X10650Y162708D01*
X10400Y162499D01*
X10108Y162374D01*
X9067D01*
G01X10108D02*
X10733Y161166D01*
G01X12167Y161666D02*
X12375Y161416D01*
X12625Y161249D01*
X12917Y161166D01*
X13250Y161249D01*
X13500Y161416D01*
X13750Y161666D01*
X13833Y161999D01*
Y163666D01*
G01X16100Y161166D02*
Y163666D01*
X15600Y163166D01*
G01Y161166D02*
X16600D01*
G01X38400Y196800D02*
X28200D01*
Y210900D01*
X33000D01*
Y215100D01*
X37800D01*
G01X9267Y195459D02*
X9017Y195584D01*
X8725Y195667D01*
X8392D01*
X8017Y195542D01*
X7725Y195334D01*
X7517Y195084D01*
X7350Y194667D01*
X7308Y194292D01*
X7392Y193917D01*
X7517Y193667D01*
X7767Y193417D01*
X8058Y193250D01*
X8350Y193167D01*
X8642D01*
X8933Y193250D01*
X9183Y193375D01*
X9392Y193542D01*
G01X10533Y193667D02*
X10783Y193375D01*
X11117Y193209D01*
X11492Y193167D01*
X11825Y193209D01*
X12158Y193417D01*
X12367Y193667D01*
X12408Y193917D01*
X12325Y194209D01*
X12033Y194417D01*
X11742Y194500D01*
X11367D01*
G01X11742D02*
X11992Y194625D01*
X12200Y194834D01*
X12283Y195084D01*
X12200Y195334D01*
X11992Y195542D01*
X11617Y195667D01*
X11242Y195625D01*
X10867Y195459D01*
G01X13758Y195250D02*
X14008Y195500D01*
X14300Y195625D01*
X14633Y195667D01*
X15050Y195584D01*
X15342Y195375D01*
X15425Y195125D01*
X15383Y194875D01*
X15217Y194667D01*
X14383Y194250D01*
X14008Y193959D01*
X13758Y193542D01*
X13675Y193167D01*
X15425D01*
G01X16942Y193459D02*
X17233Y193250D01*
X17567Y193167D01*
X17900Y193250D01*
X18192Y193500D01*
X18400Y193875D01*
X18483Y194250D01*
Y194709D01*
X18400Y195084D01*
X18192Y195417D01*
X17942Y195584D01*
X17650Y195667D01*
X17317Y195584D01*
X17067Y195417D01*
X16900Y195167D01*
X16817Y194834D01*
X16900Y194542D01*
X17108Y194250D01*
X17358Y194084D01*
X17650Y194042D01*
X17983Y194125D01*
X18233Y194334D01*
X18483Y194709D01*
G01X9267Y183959D02*
X9017Y184084D01*
X8725Y184167D01*
X8392D01*
X8017Y184042D01*
X7725Y183834D01*
X7517Y183584D01*
X7350Y183167D01*
X7308Y182792D01*
X7392Y182417D01*
X7517Y182167D01*
X7767Y181917D01*
X8058Y181750D01*
X8350Y181667D01*
X8642D01*
X8933Y181750D01*
X9183Y181875D01*
X9392Y182042D01*
G01X10533Y182167D02*
X10783Y181875D01*
X11117Y181709D01*
X11492Y181667D01*
X11825Y181709D01*
X12158Y181917D01*
X12367Y182167D01*
X12408Y182417D01*
X12325Y182709D01*
X12033Y182917D01*
X11742Y183000D01*
X11367D01*
G01X11742D02*
X11992Y183125D01*
X12200Y183334D01*
X12283Y183584D01*
X12200Y183834D01*
X11992Y184042D01*
X11617Y184167D01*
X11242Y184125D01*
X10867Y183959D01*
G01X13633Y182167D02*
X13883Y181875D01*
X14217Y181709D01*
X14592Y181667D01*
X14925Y181709D01*
X15258Y181917D01*
X15467Y182167D01*
X15508Y182417D01*
X15425Y182709D01*
X15133Y182917D01*
X14842Y183000D01*
X14467D01*
G01X14842D02*
X15092Y183125D01*
X15300Y183334D01*
X15383Y183584D01*
X15300Y183834D01*
X15092Y184042D01*
X14717Y184167D01*
X14342Y184125D01*
X13967Y183959D01*
G01X16733Y182167D02*
X16983Y181875D01*
X17317Y181709D01*
X17692Y181667D01*
X18025Y181709D01*
X18358Y181917D01*
X18567Y182167D01*
X18608Y182417D01*
X18525Y182709D01*
X18233Y182917D01*
X17942Y183000D01*
X17567D01*
G01X17942D02*
X18192Y183125D01*
X18400Y183334D01*
X18483Y183584D01*
X18400Y183834D01*
X18192Y184042D01*
X17817Y184167D01*
X17442Y184125D01*
X17067Y183959D01*
G01X28800Y230717D02*
X26300D01*
Y231758D01*
X26425Y232092D01*
X26592Y232300D01*
X26925Y232383D01*
X27258Y232300D01*
X27467Y232050D01*
X27592Y231758D01*
Y230717D01*
G01Y231758D02*
X28800Y232383D01*
G01X28425Y233733D02*
X28633Y233983D01*
X28758Y234275D01*
X28800Y234650D01*
X28717Y235025D01*
X28550Y235317D01*
X28258Y235525D01*
X27925Y235567D01*
X27592Y235483D01*
X27383Y235275D01*
X27217Y234983D01*
X27175Y234692D01*
X27217Y234400D01*
X27383Y234025D01*
X26300Y234150D01*
Y235275D01*
G01X28800Y237750D02*
X26300D01*
X26800Y237250D01*
G01X28800D02*
Y238250D01*
G01Y240850D02*
X26300D01*
X26800Y240350D01*
G01X28800D02*
Y241350D01*
G01X22042Y228267D02*
X21917Y228017D01*
X21834Y227725D01*
Y227392D01*
X21959Y227017D01*
X22167Y226725D01*
X22417Y226517D01*
X22834Y226350D01*
X23209Y226308D01*
X23584Y226392D01*
X23834Y226517D01*
X24084Y226767D01*
X24251Y227058D01*
X24334Y227350D01*
Y227642D01*
X24251Y227933D01*
X24126Y228183D01*
X23959Y228392D01*
G01X24334Y230950D02*
X21834D01*
X23626Y229408D01*
Y231492D01*
G01X22251Y232758D02*
X22001Y233008D01*
X21876Y233300D01*
X21834Y233633D01*
X21917Y234050D01*
X22126Y234342D01*
X22376Y234425D01*
X22626Y234383D01*
X22834Y234217D01*
X23251Y233383D01*
X23542Y233008D01*
X23959Y232758D01*
X24334Y232675D01*
Y234425D01*
G01X22251Y235858D02*
X22001Y236108D01*
X21876Y236400D01*
X21834Y236733D01*
X21917Y237150D01*
X22126Y237442D01*
X22376Y237525D01*
X22626Y237483D01*
X22834Y237317D01*
X23251Y236483D01*
X23542Y236108D01*
X23959Y235858D01*
X24334Y235775D01*
Y237525D01*
G01X14367Y250650D02*
X9367Y254150D01*
G01Y250650D02*
X14367Y254150D01*
G01Y258000D02*
X9367D01*
X10367Y257000D01*
G01X14367D02*
Y259000D01*
G01Y263600D02*
X9367D01*
X10367Y262600D01*
G01X14367D02*
Y264600D01*
G01X14534Y269200D02*
X14450Y269033D01*
X14284D01*
X14200Y269200D01*
X14284Y269367D01*
X14450D01*
X14534Y269200D01*
G01X12284D02*
X12200Y269033D01*
X12034D01*
X11950Y269200D01*
X12034Y269367D01*
X12200D01*
X12284Y269200D01*
G01X10200Y273217D02*
X9700Y273717D01*
X9450Y274300D01*
X9367Y274967D01*
X9534Y275800D01*
X9950Y276383D01*
X10450Y276550D01*
X10950Y276467D01*
X11367Y276133D01*
X12200Y274467D01*
X12784Y273717D01*
X13617Y273217D01*
X14367Y273050D01*
Y276550D01*
G01X13617Y278567D02*
X14034Y279067D01*
X14284Y279650D01*
X14367Y280400D01*
X14200Y281150D01*
X13867Y281733D01*
X13284Y282150D01*
X12617Y282233D01*
X11950Y282067D01*
X11534Y281650D01*
X11200Y281067D01*
X11117Y280483D01*
X11200Y279900D01*
X11534Y279150D01*
X9367Y279400D01*
Y281650D01*
G01X14367Y283833D02*
X9367D01*
X13534Y286000D01*
X9367Y288167D01*
X14367D01*
G01Y289850D02*
X9367D01*
G01Y293350D02*
X14367D01*
G01X11867D02*
Y289850D01*
G01X9367Y295617D02*
Y298783D01*
X14367Y295617D01*
Y298783D01*
G01X17925Y259900D02*
X19675Y262400D01*
G01X17925D02*
X19675Y259900D01*
G01X21900D02*
Y262400D01*
X21400Y261900D01*
G01Y259900D02*
X22400D01*
G01X25000D02*
Y262400D01*
X24500Y261900D01*
G01Y259900D02*
X25500D01*
G01X35700Y265100D02*
X21100D01*
G01D02*
Y293700D01*
G01X27338Y249628D02*
Y252128D01*
X28338D01*
X28671Y252003D01*
X28921Y251711D01*
X29004Y251378D01*
X28921Y251045D01*
X28713Y250795D01*
X28338Y250670D01*
X27338D01*
G01X30229Y249628D02*
X31271Y252128D01*
X32313Y249628D01*
G01X31938Y250503D02*
X30604D01*
G01X33454Y249628D02*
Y252128D01*
X34288D01*
X34621Y252003D01*
X34871Y251836D01*
X35079Y251586D01*
X35246Y251295D01*
X35288Y250878D01*
X35246Y250461D01*
X35079Y250170D01*
X34871Y249920D01*
X34621Y249753D01*
X34288Y249628D01*
X33454D01*
G01X36554Y250003D02*
X36804Y249795D01*
X37096Y249670D01*
X37471Y249628D01*
X37846Y249711D01*
X38138Y249878D01*
X38346Y250170D01*
X38388Y250503D01*
X38304Y250836D01*
X38096Y251045D01*
X37804Y251211D01*
X37513Y251253D01*
X37221Y251211D01*
X36846Y251045D01*
X36971Y252128D01*
X38096D01*
G01X108400Y268200D02*
X102200D01*
Y263660D01*
X82610D01*
Y256470D01*
X36620D01*
Y299200D01*
X21300D01*
Y323600D01*
X38900D01*
G01X26148Y312872D02*
Y308872D01*
X33548D01*
G01X26212Y308674D02*
Y304674D01*
X33612D01*
G01X21100Y293700D02*
X35700D01*
G01X15467Y317350D02*
X10467Y320850D01*
G01Y317350D02*
X15467Y320850D01*
G01Y324700D02*
X10467D01*
X11467Y323700D01*
G01X15467D02*
Y325700D01*
G01X15634Y330300D02*
X15550Y330133D01*
X15384D01*
X15300Y330300D01*
X15384Y330467D01*
X15550D01*
X15634Y330300D01*
G01X13384D02*
X13300Y330133D01*
X13134D01*
X13050Y330300D01*
X13134Y330467D01*
X13300D01*
X13384Y330300D01*
G01X14717Y334067D02*
X15134Y334567D01*
X15384Y335150D01*
X15467Y335900D01*
X15300Y336650D01*
X14967Y337233D01*
X14384Y337650D01*
X13717Y337733D01*
X13050Y337567D01*
X12634Y337150D01*
X12300Y336567D01*
X12217Y335983D01*
X12300Y335400D01*
X12634Y334650D01*
X10467Y334900D01*
Y337150D01*
G01Y341500D02*
X10634Y340833D01*
X11050Y340333D01*
X11550Y340000D01*
X12217Y339750D01*
X12967Y339667D01*
X13717Y339750D01*
X14384Y340000D01*
X14884Y340333D01*
X15300Y340833D01*
X15467Y341500D01*
X15300Y342167D01*
X14884Y342667D01*
X14384Y343000D01*
X13717Y343250D01*
X12967Y343333D01*
X12217Y343250D01*
X11550Y343000D01*
X11050Y342667D01*
X10634Y342167D01*
X10467Y341500D01*
G01X15467Y344933D02*
X10467D01*
X14634Y347100D01*
X10467Y349267D01*
X15467D01*
G01Y350950D02*
X10467D01*
G01Y354450D02*
X15467D01*
G01X12967D02*
Y350950D01*
G01X10467Y356717D02*
Y359883D01*
X15467Y356717D01*
Y359883D01*
G01X48016Y324957D02*
X22716D01*
Y355657D01*
X48016D01*
Y324957D01*
G01X21358Y374015D02*
X21233Y373765D01*
X21150Y373473D01*
Y373140D01*
X21275Y372765D01*
X21483Y372473D01*
X21733Y372265D01*
X22150Y372098D01*
X22525Y372056D01*
X22900Y372140D01*
X23150Y372265D01*
X23400Y372515D01*
X23567Y372806D01*
X23650Y373098D01*
Y373390D01*
X23567Y373681D01*
X23442Y373931D01*
X23275Y374140D01*
G01X23650Y376698D02*
X21150D01*
X22942Y375156D01*
Y377240D01*
G01X23650Y379298D02*
X21150D01*
X21650Y378798D01*
G01X23650D02*
Y379798D01*
G01X28989Y370358D02*
X26489D01*
Y371399D01*
X26614Y371733D01*
X26781Y371941D01*
X27114Y372024D01*
X27447Y371941D01*
X27656Y371691D01*
X27781Y371399D01*
Y370358D01*
G01Y371399D02*
X28989Y372024D01*
G01X26906Y373499D02*
X26656Y373749D01*
X26531Y374041D01*
X26489Y374374D01*
X26572Y374791D01*
X26781Y375083D01*
X27031Y375166D01*
X27281Y375124D01*
X27489Y374958D01*
X27906Y374124D01*
X28197Y373749D01*
X28614Y373499D01*
X28989Y373416D01*
Y375166D01*
G01X28697Y376683D02*
X28906Y376974D01*
X28989Y377308D01*
X28906Y377641D01*
X28656Y377933D01*
X28281Y378141D01*
X27906Y378224D01*
X27447D01*
X27072Y378141D01*
X26739Y377933D01*
X26572Y377683D01*
X26489Y377391D01*
X26572Y377058D01*
X26739Y376808D01*
X26989Y376641D01*
X27322Y376558D01*
X27614Y376641D01*
X27906Y376849D01*
X28072Y377099D01*
X28114Y377391D01*
X28031Y377724D01*
X27822Y377974D01*
X27447Y378224D01*
G01X28489Y379574D02*
X28781Y379824D01*
X28947Y380158D01*
X28989Y380533D01*
X28947Y380866D01*
X28739Y381199D01*
X28489Y381408D01*
X28239Y381449D01*
X27947Y381366D01*
X27739Y381074D01*
X27656Y380783D01*
Y380408D01*
G01Y380783D02*
X27531Y381033D01*
X27322Y381241D01*
X27072Y381324D01*
X26822Y381241D01*
X26614Y381033D01*
X26489Y380658D01*
X26531Y380283D01*
X26697Y379908D01*
G01X28697Y382883D02*
X28906Y383174D01*
X28989Y383508D01*
X28906Y383841D01*
X28656Y384133D01*
X28281Y384341D01*
X27906Y384424D01*
X27447D01*
X27072Y384341D01*
X26739Y384133D01*
X26572Y383883D01*
X26489Y383591D01*
X26572Y383258D01*
X26739Y383008D01*
X26989Y382841D01*
X27322Y382758D01*
X27614Y382841D01*
X27906Y383049D01*
X28072Y383299D01*
X28114Y383591D01*
X28031Y383924D01*
X27822Y384174D01*
X27447Y384424D01*
G01X18543Y366462D02*
Y368962D01*
X19584D01*
X19918Y368837D01*
X20126Y368670D01*
X20209Y368337D01*
X20126Y368004D01*
X19876Y367795D01*
X19584Y367670D01*
X18543D01*
G01X19584D02*
X20209Y366462D01*
G01X21559Y366962D02*
X21809Y366670D01*
X22143Y366504D01*
X22518Y366462D01*
X22851Y366504D01*
X23184Y366712D01*
X23393Y366962D01*
X23434Y367212D01*
X23351Y367504D01*
X23059Y367712D01*
X22768Y367795D01*
X22393D01*
G01X22768D02*
X23018Y367920D01*
X23226Y368129D01*
X23309Y368379D01*
X23226Y368629D01*
X23018Y368837D01*
X22643Y368962D01*
X22268Y368920D01*
X21893Y368754D01*
G01X24868Y366754D02*
X25159Y366545D01*
X25493Y366462D01*
X25826Y366545D01*
X26118Y366795D01*
X26326Y367170D01*
X26409Y367545D01*
Y368004D01*
X26326Y368379D01*
X26118Y368712D01*
X25868Y368879D01*
X25576Y368962D01*
X25243Y368879D01*
X24993Y368712D01*
X24826Y368462D01*
X24743Y368129D01*
X24826Y367837D01*
X25034Y367545D01*
X25284Y367379D01*
X25576Y367337D01*
X25909Y367420D01*
X26159Y367629D01*
X26409Y368004D01*
G01X28676Y368962D02*
X28343Y368879D01*
X28093Y368670D01*
X27926Y368420D01*
X27801Y368087D01*
X27759Y367712D01*
X27801Y367337D01*
X27926Y367004D01*
X28093Y366754D01*
X28343Y366545D01*
X28676Y366462D01*
X29009Y366545D01*
X29259Y366754D01*
X29426Y367004D01*
X29551Y367337D01*
X29593Y367712D01*
X29551Y368087D01*
X29426Y368420D01*
X29259Y368670D01*
X29009Y368879D01*
X28676Y368962D01*
G01X7883Y362989D02*
X5383D01*
Y364030D01*
X5508Y364364D01*
X5675Y364572D01*
X6008Y364655D01*
X6341Y364572D01*
X6550Y364322D01*
X6675Y364030D01*
Y362989D01*
G01Y364030D02*
X7883Y364655D01*
G01X7508Y366005D02*
X7716Y366255D01*
X7841Y366547D01*
X7883Y366922D01*
X7800Y367297D01*
X7633Y367589D01*
X7341Y367797D01*
X7008Y367839D01*
X6675Y367755D01*
X6466Y367547D01*
X6300Y367255D01*
X6258Y366964D01*
X6300Y366672D01*
X6466Y366297D01*
X5383Y366422D01*
Y367547D01*
G01X5800Y369230D02*
X5550Y369480D01*
X5425Y369772D01*
X5383Y370105D01*
X5466Y370522D01*
X5675Y370814D01*
X5925Y370897D01*
X6175Y370855D01*
X6383Y370689D01*
X6800Y369855D01*
X7091Y369480D01*
X7508Y369230D01*
X7883Y369147D01*
Y370897D01*
G01Y373122D02*
X7841Y373414D01*
X7716Y373747D01*
X7508Y373955D01*
X7216Y374039D01*
X6925Y373955D01*
X6675Y373705D01*
X6550Y373330D01*
Y372914D01*
X6466Y372664D01*
X6258Y372455D01*
X5966Y372372D01*
X5675Y372497D01*
X5466Y372789D01*
X5383Y373122D01*
X5466Y373455D01*
X5675Y373747D01*
X5966Y373872D01*
X6258Y373789D01*
X6466Y373580D01*
X6550Y373330D01*
Y372914D01*
X6675Y372539D01*
X6925Y372289D01*
X7216Y372205D01*
X7508Y372289D01*
X7716Y372497D01*
X7841Y372830D01*
X7883Y373122D01*
G01X25000Y357300D02*
X29000D01*
Y364700D01*
G01X12280Y362926D02*
X9780D01*
Y363967D01*
X9905Y364301D01*
X10072Y364509D01*
X10405Y364592D01*
X10738Y364509D01*
X10947Y364259D01*
X11072Y363967D01*
Y362926D01*
G01Y363967D02*
X12280Y364592D01*
G01Y367359D02*
X9780D01*
X11572Y365817D01*
Y367901D01*
G01X12280Y369876D02*
X11738Y369959D01*
X11280Y370084D01*
X10863Y370251D01*
X10405Y370459D01*
X9780Y370792D01*
Y369126D01*
G01X11238Y372267D02*
X10947Y372559D01*
X10780Y372809D01*
X10697Y373142D01*
X10780Y373434D01*
X10947Y373642D01*
X11197Y373809D01*
X11488Y373851D01*
X11738Y373809D01*
X11988Y373642D01*
X12197Y373392D01*
X12280Y373101D01*
X12197Y372767D01*
X11947Y372476D01*
X11572Y372309D01*
X11155Y372267D01*
X10613Y372351D01*
X10322Y372476D01*
X10030Y372684D01*
X9822Y372976D01*
X9780Y373267D01*
X9863Y373559D01*
X10072Y373767D01*
G01X17652Y374287D02*
X17527Y374037D01*
X17444Y373745D01*
Y373412D01*
X17569Y373037D01*
X17777Y372745D01*
X18027Y372537D01*
X18444Y372370D01*
X18819Y372328D01*
X19194Y372412D01*
X19444Y372537D01*
X19694Y372787D01*
X19861Y373078D01*
X19944Y373370D01*
Y373662D01*
X19861Y373953D01*
X19736Y374203D01*
X19569Y374412D01*
G01X19944Y376470D02*
X17444D01*
X17944Y375970D01*
G01X19944D02*
Y376970D01*
G01X19569Y378653D02*
X19777Y378903D01*
X19902Y379195D01*
X19944Y379570D01*
X19861Y379945D01*
X19694Y380237D01*
X19402Y380445D01*
X19069Y380487D01*
X18736Y380403D01*
X18527Y380195D01*
X18361Y379903D01*
X18319Y379612D01*
X18361Y379320D01*
X18527Y378945D01*
X17444Y379070D01*
Y380195D01*
G01X19569Y381753D02*
X19777Y382003D01*
X19902Y382295D01*
X19944Y382670D01*
X19861Y383045D01*
X19694Y383337D01*
X19402Y383545D01*
X19069Y383587D01*
X18736Y383503D01*
X18527Y383295D01*
X18361Y383003D01*
X18319Y382712D01*
X18361Y382420D01*
X18527Y382045D01*
X17444Y382170D01*
Y383295D01*
G01X6890Y376829D02*
X8682D01*
X9057Y376996D01*
X9307Y377329D01*
X9390Y377746D01*
X9307Y378163D01*
X9057Y378496D01*
X8682Y378663D01*
X6890D01*
G01X7307Y380054D02*
X7057Y380304D01*
X6932Y380596D01*
X6890Y380929D01*
X6973Y381346D01*
X7182Y381638D01*
X7432Y381721D01*
X7682Y381679D01*
X7890Y381513D01*
X8307Y380679D01*
X8598Y380304D01*
X9015Y380054D01*
X9390Y379971D01*
Y381721D01*
G01Y383946D02*
X6890D01*
X7390Y383446D01*
G01X9390D02*
Y384446D01*
G01X15986Y362737D02*
X13486D01*
Y363571D01*
X13611Y363904D01*
X13778Y364154D01*
X14028Y364362D01*
X14319Y364529D01*
X14736Y364571D01*
X15153Y364529D01*
X15444Y364362D01*
X15694Y364154D01*
X15861Y363904D01*
X15986Y363571D01*
Y362737D01*
G01Y366754D02*
X13486D01*
X13986Y366254D01*
G01X15986D02*
Y367254D01*
G01Y370354D02*
X13486D01*
X15278Y368812D01*
Y370896D01*
G01X13486Y372954D02*
X13569Y372621D01*
X13778Y372371D01*
X14028Y372204D01*
X14361Y372079D01*
X14736Y372037D01*
X15111Y372079D01*
X15444Y372204D01*
X15694Y372371D01*
X15903Y372621D01*
X15986Y372954D01*
X15903Y373287D01*
X15694Y373537D01*
X15444Y373704D01*
X15111Y373829D01*
X14736Y373871D01*
X14361Y373829D01*
X14028Y373704D01*
X13778Y373537D01*
X13569Y373287D01*
X13486Y372954D01*
G01X15986Y376554D02*
X13486D01*
X15278Y375012D01*
Y377096D01*
G01X18834Y409017D02*
X16334D01*
Y410017D01*
X16459Y410350D01*
X16751Y410600D01*
X17084Y410683D01*
X17417Y410600D01*
X17667Y410392D01*
X17792Y410017D01*
Y409017D01*
G01X16542Y413867D02*
X16417Y413617D01*
X16334Y413325D01*
Y412992D01*
X16459Y412617D01*
X16667Y412325D01*
X16917Y412117D01*
X17334Y411950D01*
X17709Y411908D01*
X18084Y411992D01*
X18334Y412117D01*
X18584Y412367D01*
X18751Y412658D01*
X18834Y412950D01*
Y413242D01*
X18751Y413533D01*
X18626Y413783D01*
X18459Y413992D01*
G01X18834Y416050D02*
X18792Y416342D01*
X18667Y416675D01*
X18459Y416883D01*
X18167Y416967D01*
X17876Y416883D01*
X17626Y416633D01*
X17501Y416258D01*
Y415842D01*
X17417Y415592D01*
X17209Y415383D01*
X16917Y415300D01*
X16626Y415425D01*
X16417Y415717D01*
X16334Y416050D01*
X16417Y416383D01*
X16626Y416675D01*
X16917Y416800D01*
X17209Y416717D01*
X17417Y416508D01*
X17501Y416258D01*
Y415842D01*
X17626Y415467D01*
X17876Y415217D01*
X18167Y415133D01*
X18459Y415217D01*
X18667Y415425D01*
X18792Y415758D01*
X18834Y416050D01*
G01X16334Y419150D02*
X16417Y418817D01*
X16626Y418567D01*
X16876Y418400D01*
X17209Y418275D01*
X17584Y418233D01*
X17959Y418275D01*
X18292Y418400D01*
X18542Y418567D01*
X18751Y418817D01*
X18834Y419150D01*
X18751Y419483D01*
X18542Y419733D01*
X18292Y419900D01*
X17959Y420025D01*
X17584Y420067D01*
X17209Y420025D01*
X16876Y419900D01*
X16626Y419733D01*
X16417Y419483D01*
X16334Y419150D01*
G01X13611Y379357D02*
X16111D01*
G01X13611Y378399D02*
Y380315D01*
G01X16111Y381624D02*
X13611D01*
Y382624D01*
X13736Y382957D01*
X14028Y383207D01*
X14361Y383290D01*
X14694Y383207D01*
X14944Y382999D01*
X15069Y382624D01*
Y381624D01*
G01X16111Y385557D02*
X13611D01*
X14111Y385057D01*
G01X16111D02*
Y386057D01*
G01X15611Y387740D02*
X15903Y387990D01*
X16069Y388324D01*
X16111Y388699D01*
X16069Y389032D01*
X15861Y389365D01*
X15611Y389574D01*
X15361Y389615D01*
X15069Y389532D01*
X14861Y389240D01*
X14778Y388949D01*
Y388574D01*
G01Y388949D02*
X14653Y389199D01*
X14444Y389407D01*
X14194Y389490D01*
X13944Y389407D01*
X13736Y389199D01*
X13611Y388824D01*
X13653Y388449D01*
X13819Y388074D01*
G01X16111Y392257D02*
X13611D01*
X15403Y390715D01*
Y392799D01*
G01X29177Y385685D02*
X26677D01*
Y386726D01*
X26802Y387060D01*
X26969Y387268D01*
X27302Y387351D01*
X27635Y387268D01*
X27844Y387018D01*
X27969Y386726D01*
Y385685D01*
G01Y386726D02*
X29177Y387351D01*
G01X27094Y388826D02*
X26844Y389076D01*
X26719Y389368D01*
X26677Y389701D01*
X26760Y390118D01*
X26969Y390410D01*
X27219Y390493D01*
X27469Y390451D01*
X27677Y390285D01*
X28094Y389451D01*
X28385Y389076D01*
X28802Y388826D01*
X29177Y388743D01*
Y390493D01*
G01X28885Y392010D02*
X29094Y392301D01*
X29177Y392635D01*
X29094Y392968D01*
X28844Y393260D01*
X28469Y393468D01*
X28094Y393551D01*
X27635D01*
X27260Y393468D01*
X26927Y393260D01*
X26760Y393010D01*
X26677Y392718D01*
X26760Y392385D01*
X26927Y392135D01*
X27177Y391968D01*
X27510Y391885D01*
X27802Y391968D01*
X28094Y392176D01*
X28260Y392426D01*
X28302Y392718D01*
X28219Y393051D01*
X28010Y393301D01*
X27635Y393551D01*
G01X29177Y396318D02*
X26677D01*
X28469Y394776D01*
Y396860D01*
G01X26677Y398918D02*
X26760Y398585D01*
X26969Y398335D01*
X27219Y398168D01*
X27552Y398043D01*
X27927Y398001D01*
X28302Y398043D01*
X28635Y398168D01*
X28885Y398335D01*
X29094Y398585D01*
X29177Y398918D01*
X29094Y399251D01*
X28885Y399501D01*
X28635Y399668D01*
X28302Y399793D01*
X27927Y399835D01*
X27552Y399793D01*
X27219Y399668D01*
X26969Y399501D01*
X26760Y399251D01*
X26677Y398918D01*
G01X23819Y401889D02*
Y404389D01*
X24860D01*
X25194Y404264D01*
X25402Y404097D01*
X25485Y403764D01*
X25402Y403431D01*
X25152Y403222D01*
X24860Y403097D01*
X23819D01*
G01X24860D02*
X25485Y401889D01*
G01X28252D02*
Y404389D01*
X26710Y402597D01*
X28794D01*
G01X30852Y404389D02*
X30519Y404306D01*
X30269Y404097D01*
X30102Y403847D01*
X29977Y403514D01*
X29935Y403139D01*
X29977Y402764D01*
X30102Y402431D01*
X30269Y402181D01*
X30519Y401972D01*
X30852Y401889D01*
X31185Y401972D01*
X31435Y402181D01*
X31602Y402431D01*
X31727Y402764D01*
X31769Y403139D01*
X31727Y403514D01*
X31602Y403847D01*
X31435Y404097D01*
X31185Y404306D01*
X30852Y404389D01*
G01X33952D02*
X33619Y404306D01*
X33369Y404097D01*
X33202Y403847D01*
X33077Y403514D01*
X33035Y403139D01*
X33077Y402764D01*
X33202Y402431D01*
X33369Y402181D01*
X33619Y401972D01*
X33952Y401889D01*
X34285Y401972D01*
X34535Y402181D01*
X34702Y402431D01*
X34827Y402764D01*
X34869Y403139D01*
X34827Y403514D01*
X34702Y403847D01*
X34535Y404097D01*
X34285Y404306D01*
X33952Y404389D01*
G01X30500Y445517D02*
X28000D01*
Y446517D01*
X28125Y446850D01*
X28417Y447100D01*
X28750Y447183D01*
X29083Y447100D01*
X29333Y446892D01*
X29458Y446517D01*
Y445517D01*
G01X28208Y450367D02*
X28083Y450117D01*
X28000Y449825D01*
Y449492D01*
X28125Y449117D01*
X28333Y448825D01*
X28583Y448617D01*
X29000Y448450D01*
X29375Y448408D01*
X29750Y448492D01*
X30000Y448617D01*
X30250Y448867D01*
X30417Y449158D01*
X30500Y449450D01*
Y449742D01*
X30417Y450033D01*
X30292Y450283D01*
X30125Y450492D01*
G01X30500Y452550D02*
X30458Y452842D01*
X30333Y453175D01*
X30125Y453383D01*
X29833Y453467D01*
X29542Y453383D01*
X29292Y453133D01*
X29167Y452758D01*
Y452342D01*
X29083Y452092D01*
X28875Y451883D01*
X28583Y451800D01*
X28292Y451925D01*
X28083Y452217D01*
X28000Y452550D01*
X28083Y452883D01*
X28292Y453175D01*
X28583Y453300D01*
X28875Y453217D01*
X29083Y453008D01*
X29167Y452758D01*
Y452342D01*
X29292Y451967D01*
X29542Y451717D01*
X29833Y451633D01*
X30125Y451717D01*
X30333Y451925D01*
X30458Y452258D01*
X30500Y452550D01*
G01X28417Y454858D02*
X28167Y455108D01*
X28042Y455400D01*
X28000Y455733D01*
X28083Y456150D01*
X28292Y456442D01*
X28542Y456525D01*
X28792Y456483D01*
X29000Y456317D01*
X29417Y455483D01*
X29708Y455108D01*
X30125Y454858D01*
X30500Y454775D01*
Y456525D01*
G01X25808Y439440D02*
X23308D01*
Y440440D01*
X23433Y440773D01*
X23725Y441023D01*
X24058Y441106D01*
X24391Y441023D01*
X24641Y440815D01*
X24766Y440440D01*
Y439440D01*
G01X25808Y442540D02*
X23308D01*
Y443581D01*
X23433Y443915D01*
X23600Y444123D01*
X23933Y444206D01*
X24266Y444123D01*
X24475Y443873D01*
X24600Y443581D01*
Y442540D01*
G01Y443581D02*
X25808Y444206D01*
G01X24766Y445681D02*
X24475Y445973D01*
X24308Y446223D01*
X24225Y446556D01*
X24308Y446848D01*
X24475Y447056D01*
X24725Y447223D01*
X25016Y447265D01*
X25266Y447223D01*
X25516Y447056D01*
X25725Y446806D01*
X25808Y446515D01*
X25725Y446181D01*
X25475Y445890D01*
X25100Y445723D01*
X24683Y445681D01*
X24141Y445765D01*
X23850Y445890D01*
X23558Y446098D01*
X23350Y446390D01*
X23308Y446681D01*
X23391Y446973D01*
X23600Y447181D01*
G01X25516Y448865D02*
X25725Y449156D01*
X25808Y449490D01*
X25725Y449823D01*
X25475Y450115D01*
X25100Y450323D01*
X24725Y450406D01*
X24266D01*
X23891Y450323D01*
X23558Y450115D01*
X23391Y449865D01*
X23308Y449573D01*
X23391Y449240D01*
X23558Y448990D01*
X23808Y448823D01*
X24141Y448740D01*
X24433Y448823D01*
X24725Y449031D01*
X24891Y449281D01*
X24933Y449573D01*
X24850Y449906D01*
X24641Y450156D01*
X24266Y450406D01*
G01X8017Y422500D02*
Y425000D01*
X9017D01*
X9350Y424875D01*
X9600Y424583D01*
X9683Y424250D01*
X9600Y423917D01*
X9392Y423667D01*
X9017Y423542D01*
X8017D01*
G01X11117Y422500D02*
Y425000D01*
X12158D01*
X12492Y424875D01*
X12700Y424708D01*
X12783Y424375D01*
X12700Y424042D01*
X12450Y423833D01*
X12158Y423708D01*
X11117D01*
G01X12158D02*
X12783Y422500D01*
G01X14967D02*
X15050Y423042D01*
X15175Y423500D01*
X15342Y423917D01*
X15550Y424375D01*
X15883Y425000D01*
X14217D01*
G01X18150Y422500D02*
Y425000D01*
X17650Y424500D01*
G01Y422500D02*
X18650D01*
G01X19800Y426000D02*
Y422000D01*
X27200D01*
G01X7915Y426713D02*
Y429213D01*
X8915D01*
X9248Y429088D01*
X9498Y428796D01*
X9581Y428463D01*
X9498Y428130D01*
X9290Y427880D01*
X8915Y427755D01*
X7915D01*
G01X11015Y426713D02*
Y429213D01*
X12056D01*
X12390Y429088D01*
X12598Y428921D01*
X12681Y428588D01*
X12598Y428255D01*
X12348Y428046D01*
X12056Y427921D01*
X11015D01*
G01X12056D02*
X12681Y426713D01*
G01X14865D02*
X14948Y427255D01*
X15073Y427713D01*
X15240Y428130D01*
X15448Y428588D01*
X15781Y429213D01*
X14115D01*
G01X17131Y427213D02*
X17381Y426921D01*
X17715Y426755D01*
X18090Y426713D01*
X18423Y426755D01*
X18756Y426963D01*
X18965Y427213D01*
X19006Y427463D01*
X18923Y427755D01*
X18631Y427963D01*
X18340Y428046D01*
X17965D01*
G01X18340D02*
X18590Y428171D01*
X18798Y428380D01*
X18881Y428630D01*
X18798Y428880D01*
X18590Y429088D01*
X18215Y429213D01*
X17840Y429171D01*
X17465Y429005D01*
G01X27300Y431000D02*
Y427000D01*
X34700D01*
G01X16900Y472733D02*
X18692D01*
X19067Y472900D01*
X19317Y473233D01*
X19400Y473650D01*
X19317Y474067D01*
X19067Y474400D01*
X18692Y474567D01*
X16900D01*
G01X19400Y476750D02*
X19358Y477042D01*
X19233Y477375D01*
X19025Y477583D01*
X18733Y477667D01*
X18442Y477583D01*
X18192Y477333D01*
X18067Y476958D01*
Y476542D01*
X17983Y476292D01*
X17775Y476083D01*
X17483Y476000D01*
X17192Y476125D01*
X16983Y476417D01*
X16900Y476750D01*
X16983Y477083D01*
X17192Y477375D01*
X17483Y477500D01*
X17775Y477417D01*
X17983Y477208D01*
X18067Y476958D01*
Y476542D01*
X18192Y476167D01*
X18442Y475917D01*
X18733Y475833D01*
X19025Y475917D01*
X19233Y476125D01*
X19358Y476458D01*
X19400Y476750D01*
G01X10900Y471267D02*
X8400D01*
Y472308D01*
X8525Y472642D01*
X8692Y472850D01*
X9025Y472933D01*
X9358Y472850D01*
X9567Y472600D01*
X9692Y472308D01*
Y471267D01*
G01Y472308D02*
X10900Y472933D01*
G01Y475200D02*
X8400D01*
X8900Y474700D01*
G01X10900D02*
Y475700D01*
G01X10525Y477383D02*
X10733Y477633D01*
X10858Y477925D01*
X10900Y478300D01*
X10817Y478675D01*
X10650Y478967D01*
X10358Y479175D01*
X10025Y479217D01*
X9692Y479133D01*
X9483Y478925D01*
X9317Y478633D01*
X9275Y478342D01*
X9317Y478050D01*
X9483Y477675D01*
X8400Y477800D01*
Y478925D01*
G01X34000Y478700D02*
X30000D01*
Y471300D01*
G01X27900Y471267D02*
X25400D01*
Y472308D01*
X25525Y472642D01*
X25692Y472850D01*
X26025Y472933D01*
X26358Y472850D01*
X26567Y472600D01*
X26692Y472308D01*
Y471267D01*
G01Y472308D02*
X27900Y472933D01*
G01Y475200D02*
X25400D01*
X25900Y474700D01*
G01X27900D02*
Y475700D01*
G01X26858Y477508D02*
X26567Y477800D01*
X26400Y478050D01*
X26317Y478383D01*
X26400Y478675D01*
X26567Y478883D01*
X26817Y479050D01*
X27108Y479092D01*
X27358Y479050D01*
X27608Y478883D01*
X27817Y478633D01*
X27900Y478342D01*
X27817Y478008D01*
X27567Y477717D01*
X27192Y477550D01*
X26775Y477508D01*
X26233Y477592D01*
X25942Y477717D01*
X25650Y477925D01*
X25442Y478217D01*
X25400Y478508D01*
X25483Y478800D01*
X25692Y479008D01*
G01X12617Y465300D02*
Y467800D01*
X13658D01*
X13992Y467675D01*
X14200Y467508D01*
X14283Y467175D01*
X14200Y466842D01*
X13950Y466633D01*
X13658Y466508D01*
X12617D01*
G01X13658D02*
X14283Y465300D01*
G01X15758Y467383D02*
X16008Y467633D01*
X16300Y467758D01*
X16633Y467800D01*
X17050Y467717D01*
X17342Y467508D01*
X17425Y467258D01*
X17383Y467008D01*
X17217Y466800D01*
X16383Y466383D01*
X16008Y466092D01*
X15758Y465675D01*
X15675Y465300D01*
X17425D01*
G01X18942Y465592D02*
X19233Y465383D01*
X19567Y465300D01*
X19900Y465383D01*
X20192Y465633D01*
X20400Y466008D01*
X20483Y466383D01*
Y466842D01*
X20400Y467217D01*
X20192Y467550D01*
X19942Y467717D01*
X19650Y467800D01*
X19317Y467717D01*
X19067Y467550D01*
X18900Y467300D01*
X18817Y466967D01*
X18900Y466675D01*
X19108Y466383D01*
X19358Y466217D01*
X19650Y466175D01*
X19983Y466258D01*
X20233Y466467D01*
X20483Y466842D01*
G01X23250Y465300D02*
Y467800D01*
X21708Y466008D01*
X23792D01*
G01X26900Y493383D02*
X28692D01*
X29067Y493550D01*
X29317Y493883D01*
X29400Y494300D01*
X29317Y494717D01*
X29067Y495050D01*
X28692Y495217D01*
X26900D01*
G01X29400Y497400D02*
X26900D01*
X27400Y496900D01*
G01X29400D02*
Y497900D01*
G01X27317Y499708D02*
X27067Y499958D01*
X26942Y500250D01*
X26900Y500583D01*
X26983Y501000D01*
X27192Y501292D01*
X27442Y501375D01*
X27692Y501333D01*
X27900Y501167D01*
X28317Y500333D01*
X28608Y499958D01*
X29025Y499708D01*
X29400Y499625D01*
Y501375D01*
G01X25700Y493367D02*
X23200D01*
Y494408D01*
X23325Y494742D01*
X23492Y494950D01*
X23825Y495033D01*
X24158Y494950D01*
X24367Y494700D01*
X24492Y494408D01*
Y493367D01*
G01Y494408D02*
X25700Y495033D01*
G01Y497300D02*
X23200D01*
X23700Y496800D01*
G01X25700D02*
Y497800D01*
G01Y500400D02*
X25658Y500692D01*
X25533Y501025D01*
X25325Y501233D01*
X25033Y501317D01*
X24742Y501233D01*
X24492Y500983D01*
X24367Y500608D01*
Y500192D01*
X24283Y499942D01*
X24075Y499733D01*
X23783Y499650D01*
X23492Y499775D01*
X23283Y500067D01*
X23200Y500400D01*
X23283Y500733D01*
X23492Y501025D01*
X23783Y501150D01*
X24075Y501067D01*
X24283Y500858D01*
X24367Y500608D01*
Y500192D01*
X24492Y499817D01*
X24742Y499567D01*
X25033Y499483D01*
X25325Y499567D01*
X25533Y499775D01*
X25658Y500108D01*
X25700Y500400D01*
G01X12417Y484700D02*
Y487200D01*
X13458D01*
X13792Y487075D01*
X14000Y486908D01*
X14083Y486575D01*
X14000Y486242D01*
X13750Y486033D01*
X13458Y485908D01*
X12417D01*
G01X13458D02*
X14083Y484700D01*
G01X15558Y486783D02*
X15808Y487033D01*
X16100Y487158D01*
X16433Y487200D01*
X16850Y487117D01*
X17142Y486908D01*
X17225Y486658D01*
X17183Y486408D01*
X17017Y486200D01*
X16183Y485783D01*
X15808Y485492D01*
X15558Y485075D01*
X15475Y484700D01*
X17225D01*
G01X18742Y484992D02*
X19033Y484783D01*
X19367Y484700D01*
X19700Y484783D01*
X19992Y485033D01*
X20200Y485408D01*
X20283Y485783D01*
Y486242D01*
X20200Y486617D01*
X19992Y486950D01*
X19742Y487117D01*
X19450Y487200D01*
X19117Y487117D01*
X18867Y486950D01*
X18700Y486700D01*
X18617Y486367D01*
X18700Y486075D01*
X18908Y485783D01*
X19158Y485617D01*
X19450Y485575D01*
X19783Y485658D01*
X20033Y485867D01*
X20283Y486242D01*
G01X21633Y485200D02*
X21883Y484908D01*
X22217Y484742D01*
X22592Y484700D01*
X22925Y484742D01*
X23258Y484950D01*
X23467Y485200D01*
X23508Y485450D01*
X23425Y485742D01*
X23133Y485950D01*
X22842Y486033D01*
X22467D01*
G01X22842D02*
X23092Y486158D01*
X23300Y486367D01*
X23383Y486617D01*
X23300Y486867D01*
X23092Y487075D01*
X22717Y487200D01*
X22342Y487158D01*
X21967Y486992D01*
G01X22117Y489200D02*
Y491700D01*
X23158D01*
X23492Y491575D01*
X23700Y491408D01*
X23783Y491075D01*
X23700Y490742D01*
X23450Y490533D01*
X23158Y490408D01*
X22117D01*
G01X23158D02*
X23783Y489200D01*
G01X25258Y491283D02*
X25508Y491533D01*
X25800Y491658D01*
X26133Y491700D01*
X26550Y491617D01*
X26842Y491408D01*
X26925Y491158D01*
X26883Y490908D01*
X26717Y490700D01*
X25883Y490283D01*
X25508Y489992D01*
X25258Y489575D01*
X25175Y489200D01*
X26925D01*
G01X28442Y489492D02*
X28733Y489283D01*
X29067Y489200D01*
X29400Y489283D01*
X29692Y489533D01*
X29900Y489908D01*
X29983Y490283D01*
Y490742D01*
X29900Y491117D01*
X29692Y491450D01*
X29442Y491617D01*
X29150Y491700D01*
X28817Y491617D01*
X28567Y491450D01*
X28400Y491200D01*
X28317Y490867D01*
X28400Y490575D01*
X28608Y490283D01*
X28858Y490117D01*
X29150Y490075D01*
X29483Y490158D01*
X29733Y490367D01*
X29983Y490742D01*
G01X31333Y489575D02*
X31583Y489367D01*
X31875Y489242D01*
X32250Y489200D01*
X32625Y489283D01*
X32917Y489450D01*
X33125Y489742D01*
X33167Y490075D01*
X33083Y490408D01*
X32875Y490617D01*
X32583Y490783D01*
X32292Y490825D01*
X32000Y490783D01*
X31625Y490617D01*
X31750Y491700D01*
X32875D01*
G01X22130Y543394D02*
Y545894D01*
X23171D01*
X23505Y545769D01*
X23713Y545602D01*
X23796Y545269D01*
X23713Y544936D01*
X23463Y544727D01*
X23171Y544602D01*
X22130D01*
G01X23171D02*
X23796Y543394D01*
G01X25271Y544436D02*
X25563Y544727D01*
X25813Y544894D01*
X26146Y544977D01*
X26438Y544894D01*
X26646Y544727D01*
X26813Y544477D01*
X26855Y544186D01*
X26813Y543936D01*
X26646Y543686D01*
X26396Y543477D01*
X26105Y543394D01*
X25771Y543477D01*
X25480Y543727D01*
X25313Y544102D01*
X25271Y544519D01*
X25355Y545061D01*
X25480Y545352D01*
X25688Y545644D01*
X25980Y545852D01*
X26271Y545894D01*
X26563Y545811D01*
X26771Y545602D01*
G01X29163Y543394D02*
X29455Y543436D01*
X29788Y543561D01*
X29996Y543769D01*
X30080Y544061D01*
X29996Y544352D01*
X29746Y544602D01*
X29371Y544727D01*
X28955D01*
X28705Y544811D01*
X28496Y545019D01*
X28413Y545311D01*
X28538Y545602D01*
X28830Y545811D01*
X29163Y545894D01*
X29496Y545811D01*
X29788Y545602D01*
X29913Y545311D01*
X29830Y545019D01*
X29621Y544811D01*
X29371Y544727D01*
X28955D01*
X28580Y544602D01*
X28330Y544352D01*
X28246Y544061D01*
X28330Y543769D01*
X28538Y543561D01*
X28871Y543436D01*
X29163Y543394D01*
G01X31346Y543769D02*
X31596Y543561D01*
X31888Y543436D01*
X32263Y543394D01*
X32638Y543477D01*
X32930Y543644D01*
X33138Y543936D01*
X33180Y544269D01*
X33096Y544602D01*
X32888Y544811D01*
X32596Y544977D01*
X32305Y545019D01*
X32013Y544977D01*
X31638Y544811D01*
X31763Y545894D01*
X32888D01*
G01X16417Y532417D02*
Y534917D01*
X17458D01*
X17792Y534792D01*
X18000Y534625D01*
X18083Y534292D01*
X18000Y533959D01*
X17750Y533750D01*
X17458Y533625D01*
X16417D01*
G01X17458D02*
X18083Y532417D01*
G01X19558Y533459D02*
X19850Y533750D01*
X20100Y533917D01*
X20433Y534000D01*
X20725Y533917D01*
X20933Y533750D01*
X21100Y533500D01*
X21142Y533209D01*
X21100Y532959D01*
X20933Y532709D01*
X20683Y532500D01*
X20392Y532417D01*
X20058Y532500D01*
X19767Y532750D01*
X19600Y533125D01*
X19558Y533542D01*
X19642Y534084D01*
X19767Y534375D01*
X19975Y534667D01*
X20267Y534875D01*
X20558Y534917D01*
X20850Y534834D01*
X21058Y534625D01*
G01X23450Y532417D02*
X23742Y532459D01*
X24075Y532584D01*
X24283Y532792D01*
X24367Y533084D01*
X24283Y533375D01*
X24033Y533625D01*
X23658Y533750D01*
X23242D01*
X22992Y533834D01*
X22783Y534042D01*
X22700Y534334D01*
X22825Y534625D01*
X23117Y534834D01*
X23450Y534917D01*
X23783Y534834D01*
X24075Y534625D01*
X24200Y534334D01*
X24117Y534042D01*
X23908Y533834D01*
X23658Y533750D01*
X23242D01*
X22867Y533625D01*
X22617Y533375D01*
X22533Y533084D01*
X22617Y532792D01*
X22825Y532584D01*
X23158Y532459D01*
X23450Y532417D01*
G01X26467D02*
X26550Y532959D01*
X26675Y533417D01*
X26842Y533834D01*
X27050Y534292D01*
X27383Y534917D01*
X25717D01*
G01X28600Y535500D02*
Y531500D01*
X36000D01*
G01X15783Y520000D02*
Y522500D01*
X16617D01*
X16950Y522375D01*
X17200Y522208D01*
X17408Y521958D01*
X17575Y521667D01*
X17617Y521250D01*
X17575Y520833D01*
X17408Y520542D01*
X17200Y520292D01*
X16950Y520125D01*
X16617Y520000D01*
X15783D01*
G01X19800D02*
Y522500D01*
X19300Y522000D01*
G01Y520000D02*
X20300D01*
G01X23400D02*
Y522500D01*
X21858Y520708D01*
X23942D01*
G01X26000Y522500D02*
X25667Y522417D01*
X25417Y522208D01*
X25250Y521958D01*
X25125Y521625D01*
X25083Y521250D01*
X25125Y520875D01*
X25250Y520542D01*
X25417Y520292D01*
X25667Y520083D01*
X26000Y520000D01*
X26333Y520083D01*
X26583Y520292D01*
X26750Y520542D01*
X26875Y520875D01*
X26917Y521250D01*
X26875Y521625D01*
X26750Y521958D01*
X26583Y522208D01*
X26333Y522417D01*
X26000Y522500D01*
G01X28183Y520500D02*
X28433Y520208D01*
X28767Y520042D01*
X29142Y520000D01*
X29475Y520042D01*
X29808Y520250D01*
X30017Y520500D01*
X30058Y520750D01*
X29975Y521042D01*
X29683Y521250D01*
X29392Y521333D01*
X29017D01*
G01X29392D02*
X29642Y521458D01*
X29850Y521667D01*
X29933Y521917D01*
X29850Y522167D01*
X29642Y522375D01*
X29267Y522500D01*
X28892Y522458D01*
X28517Y522292D01*
G01X21000Y530562D02*
X37100D01*
G01X21000Y523562D02*
Y530562D01*
G01X37100Y523562D02*
X21000D01*
G01X22200Y574100D02*
Y571600D01*
G01X21242Y574100D02*
X23158D01*
G01X24467Y571600D02*
Y574100D01*
X25467D01*
X25800Y573975D01*
X26050Y573683D01*
X26133Y573350D01*
X26050Y573017D01*
X25842Y572767D01*
X25467Y572642D01*
X24467D01*
G01X28400Y571600D02*
Y574100D01*
X27900Y573600D01*
G01Y571600D02*
X28900D01*
G01X31500D02*
X31792Y571642D01*
X32125Y571767D01*
X32333Y571975D01*
X32417Y572267D01*
X32333Y572558D01*
X32083Y572808D01*
X31708Y572933D01*
X31292D01*
X31042Y573017D01*
X30833Y573225D01*
X30750Y573517D01*
X30875Y573808D01*
X31167Y574017D01*
X31500Y574100D01*
X31833Y574017D01*
X32125Y573808D01*
X32250Y573517D01*
X32167Y573225D01*
X31958Y573017D01*
X31708Y572933D01*
X31292D01*
X30917Y572808D01*
X30667Y572558D01*
X30583Y572267D01*
X30667Y571975D01*
X30875Y571767D01*
X31208Y571642D01*
X31500Y571600D01*
G01X34600D02*
Y574100D01*
X34100Y573600D01*
G01Y571600D02*
X35100D01*
G01X21997Y552069D02*
Y554569D01*
X23038D01*
X23372Y554444D01*
X23580Y554277D01*
X23663Y553944D01*
X23580Y553611D01*
X23330Y553402D01*
X23038Y553277D01*
X21997D01*
G01X23038D02*
X23663Y552069D01*
G01X25013Y552569D02*
X25263Y552277D01*
X25597Y552111D01*
X25972Y552069D01*
X26305Y552111D01*
X26638Y552319D01*
X26847Y552569D01*
X26888Y552819D01*
X26805Y553111D01*
X26513Y553319D01*
X26222Y553402D01*
X25847D01*
G01X26222D02*
X26472Y553527D01*
X26680Y553736D01*
X26763Y553986D01*
X26680Y554236D01*
X26472Y554444D01*
X26097Y554569D01*
X25722Y554527D01*
X25347Y554361D01*
G01X29530Y552069D02*
Y554569D01*
X27988Y552777D01*
X30072D01*
G01X31338Y553111D02*
X31630Y553402D01*
X31880Y553569D01*
X32213Y553652D01*
X32505Y553569D01*
X32713Y553402D01*
X32880Y553152D01*
X32922Y552861D01*
X32880Y552611D01*
X32713Y552361D01*
X32463Y552152D01*
X32172Y552069D01*
X31838Y552152D01*
X31547Y552402D01*
X31380Y552777D01*
X31338Y553194D01*
X31422Y553736D01*
X31547Y554027D01*
X31755Y554319D01*
X32047Y554527D01*
X32338Y554569D01*
X32630Y554486D01*
X32838Y554277D01*
G01X22197Y547969D02*
Y550469D01*
X23238D01*
X23572Y550344D01*
X23780Y550177D01*
X23863Y549844D01*
X23780Y549511D01*
X23530Y549302D01*
X23238Y549177D01*
X22197D01*
G01X23238D02*
X23863Y547969D01*
G01X25213Y548469D02*
X25463Y548177D01*
X25797Y548011D01*
X26172Y547969D01*
X26505Y548011D01*
X26838Y548219D01*
X27047Y548469D01*
X27088Y548719D01*
X27005Y549011D01*
X26713Y549219D01*
X26422Y549302D01*
X26047D01*
G01X26422D02*
X26672Y549427D01*
X26880Y549636D01*
X26963Y549886D01*
X26880Y550136D01*
X26672Y550344D01*
X26297Y550469D01*
X25922Y550427D01*
X25547Y550261D01*
G01X29730Y547969D02*
Y550469D01*
X28188Y548677D01*
X30272D01*
G01X31538Y550052D02*
X31788Y550302D01*
X32080Y550427D01*
X32413Y550469D01*
X32830Y550386D01*
X33122Y550177D01*
X33205Y549927D01*
X33163Y549677D01*
X32997Y549469D01*
X32163Y549052D01*
X31788Y548761D01*
X31538Y548344D01*
X31455Y547969D01*
X33205D01*
G01X21243Y593912D02*
Y591412D01*
X22909D01*
G01X24259Y591787D02*
X24509Y591579D01*
X24801Y591454D01*
X25176Y591412D01*
X25551Y591495D01*
X25843Y591662D01*
X26051Y591954D01*
X26093Y592287D01*
X26009Y592620D01*
X25801Y592829D01*
X25509Y592995D01*
X25218Y593037D01*
X24926Y592995D01*
X24551Y592829D01*
X24676Y593912D01*
X25801D01*
G01X21243Y589912D02*
Y587412D01*
X22909D01*
G01X24384Y588454D02*
X24676Y588745D01*
X24926Y588912D01*
X25259Y588995D01*
X25551Y588912D01*
X25759Y588745D01*
X25926Y588495D01*
X25968Y588204D01*
X25926Y587954D01*
X25759Y587704D01*
X25509Y587495D01*
X25218Y587412D01*
X24884Y587495D01*
X24593Y587745D01*
X24426Y588120D01*
X24384Y588537D01*
X24468Y589079D01*
X24593Y589370D01*
X24801Y589662D01*
X25093Y589870D01*
X25384Y589912D01*
X25676Y589829D01*
X25884Y589620D01*
G01X27717Y606700D02*
Y609200D01*
X28758D01*
X29092Y609075D01*
X29300Y608908D01*
X29383Y608575D01*
X29300Y608242D01*
X29050Y608033D01*
X28758Y607908D01*
X27717D01*
G01X28758D02*
X29383Y606700D01*
G01X30733Y607200D02*
X30983Y606908D01*
X31317Y606742D01*
X31692Y606700D01*
X32025Y606742D01*
X32358Y606950D01*
X32567Y607200D01*
X32608Y607450D01*
X32525Y607742D01*
X32233Y607950D01*
X31942Y608033D01*
X31567D01*
G01X31942D02*
X32192Y608158D01*
X32400Y608367D01*
X32483Y608617D01*
X32400Y608867D01*
X32192Y609075D01*
X31817Y609200D01*
X31442Y609158D01*
X31067Y608992D01*
G01X33833Y607200D02*
X34083Y606908D01*
X34417Y606742D01*
X34792Y606700D01*
X35125Y606742D01*
X35458Y606950D01*
X35667Y607200D01*
X35708Y607450D01*
X35625Y607742D01*
X35333Y607950D01*
X35042Y608033D01*
X34667D01*
G01X35042D02*
X35292Y608158D01*
X35500Y608367D01*
X35583Y608617D01*
X35500Y608867D01*
X35292Y609075D01*
X34917Y609200D01*
X34542Y609158D01*
X34167Y608992D01*
G01X36933Y607200D02*
X37183Y606908D01*
X37517Y606742D01*
X37892Y606700D01*
X38225Y606742D01*
X38558Y606950D01*
X38767Y607200D01*
X38808Y607450D01*
X38725Y607742D01*
X38433Y607950D01*
X38142Y608033D01*
X37767D01*
G01X38142D02*
X38392Y608158D01*
X38600Y608367D01*
X38683Y608617D01*
X38600Y608867D01*
X38392Y609075D01*
X38017Y609200D01*
X37642Y609158D01*
X37267Y608992D01*
G01X27717Y601200D02*
Y603700D01*
X28758D01*
X29092Y603575D01*
X29300Y603408D01*
X29383Y603075D01*
X29300Y602742D01*
X29050Y602533D01*
X28758Y602408D01*
X27717D01*
G01X28758D02*
X29383Y601200D01*
G01X30733Y601700D02*
X30983Y601408D01*
X31317Y601242D01*
X31692Y601200D01*
X32025Y601242D01*
X32358Y601450D01*
X32567Y601700D01*
X32608Y601950D01*
X32525Y602242D01*
X32233Y602450D01*
X31942Y602533D01*
X31567D01*
G01X31942D02*
X32192Y602658D01*
X32400Y602867D01*
X32483Y603117D01*
X32400Y603367D01*
X32192Y603575D01*
X31817Y603700D01*
X31442Y603658D01*
X31067Y603492D01*
G01X33833Y601700D02*
X34083Y601408D01*
X34417Y601242D01*
X34792Y601200D01*
X35125Y601242D01*
X35458Y601450D01*
X35667Y601700D01*
X35708Y601950D01*
X35625Y602242D01*
X35333Y602450D01*
X35042Y602533D01*
X34667D01*
G01X35042D02*
X35292Y602658D01*
X35500Y602867D01*
X35583Y603117D01*
X35500Y603367D01*
X35292Y603575D01*
X34917Y603700D01*
X34542Y603658D01*
X34167Y603492D01*
G01X38350Y601200D02*
Y603700D01*
X36808Y601908D01*
X38892D01*
G01X30150Y589825D02*
X29900Y589950D01*
X29608Y590033D01*
X29275D01*
X28900Y589908D01*
X28608Y589700D01*
X28400Y589450D01*
X28233Y589033D01*
X28191Y588658D01*
X28275Y588283D01*
X28400Y588033D01*
X28650Y587783D01*
X28941Y587616D01*
X29233Y587533D01*
X29525D01*
X29816Y587616D01*
X30066Y587741D01*
X30275Y587908D01*
G01X31541Y589616D02*
X31791Y589866D01*
X32083Y589991D01*
X32416Y590033D01*
X32833Y589950D01*
X33125Y589741D01*
X33208Y589491D01*
X33166Y589241D01*
X33000Y589033D01*
X32166Y588616D01*
X31791Y588325D01*
X31541Y587908D01*
X31458Y587533D01*
X33208D01*
G01X35433Y590033D02*
X35100Y589950D01*
X34850Y589741D01*
X34683Y589491D01*
X34558Y589158D01*
X34516Y588783D01*
X34558Y588408D01*
X34683Y588075D01*
X34850Y587825D01*
X35100Y587616D01*
X35433Y587533D01*
X35766Y587616D01*
X36016Y587825D01*
X36183Y588075D01*
X36308Y588408D01*
X36350Y588783D01*
X36308Y589158D01*
X36183Y589491D01*
X36016Y589741D01*
X35766Y589950D01*
X35433Y590033D01*
G01X38533Y587533D02*
Y590033D01*
X38033Y589533D01*
G01Y587533D02*
X39033D01*
G01X30150Y593825D02*
X29900Y593950D01*
X29608Y594033D01*
X29275D01*
X28900Y593908D01*
X28608Y593700D01*
X28400Y593450D01*
X28233Y593033D01*
X28191Y592658D01*
X28275Y592283D01*
X28400Y592033D01*
X28650Y591783D01*
X28941Y591616D01*
X29233Y591533D01*
X29525D01*
X29816Y591616D01*
X30066Y591741D01*
X30275Y591908D01*
G01X32333Y591533D02*
Y594033D01*
X31833Y593533D01*
G01Y591533D02*
X32833D01*
G01X34725Y591825D02*
X35016Y591616D01*
X35350Y591533D01*
X35683Y591616D01*
X35975Y591866D01*
X36183Y592241D01*
X36266Y592616D01*
Y593075D01*
X36183Y593450D01*
X35975Y593783D01*
X35725Y593950D01*
X35433Y594033D01*
X35100Y593950D01*
X34850Y593783D01*
X34683Y593533D01*
X34600Y593200D01*
X34683Y592908D01*
X34891Y592616D01*
X35141Y592450D01*
X35433Y592408D01*
X35766Y592491D01*
X36016Y592700D01*
X36266Y593075D01*
G01X39033Y591533D02*
Y594033D01*
X37491Y592241D01*
X39575D01*
G01X12800Y636333D02*
X12133Y636416D01*
X11550Y636750D01*
X11050Y637250D01*
X10717Y637833D01*
X10550Y638500D01*
Y639166D01*
X10717Y639833D01*
X11050Y640416D01*
X11550Y640916D01*
X12133Y641250D01*
X12800Y641333D01*
X13467Y641250D01*
X14050Y640916D01*
X14550Y640416D01*
X14883Y639833D01*
X15050Y639166D01*
Y638500D01*
X14883Y637833D01*
X14550Y637250D01*
X14050Y636750D01*
X13467Y636416D01*
X12800Y636333D01*
G01X16650Y637000D02*
X17317Y636583D01*
X18067Y636333D01*
X18733D01*
X19400Y636583D01*
X19900Y637000D01*
X20150Y637583D01*
X19983Y638166D01*
X19567Y638666D01*
X18817Y639000D01*
X17817Y639166D01*
X17233Y639500D01*
X16983Y640083D01*
X17150Y640666D01*
X17567Y641083D01*
X18150Y641333D01*
X18733D01*
X19317Y641166D01*
X19817Y640750D01*
G01X25833Y640916D02*
X25333Y641166D01*
X24750Y641333D01*
X24083D01*
X23333Y641083D01*
X22750Y640666D01*
X22333Y640166D01*
X22000Y639333D01*
X21917Y638583D01*
X22083Y637833D01*
X22333Y637333D01*
X22833Y636833D01*
X23417Y636500D01*
X24000Y636333D01*
X24583D01*
X25167Y636500D01*
X25667Y636750D01*
X26083Y637083D01*
G01X29600Y636333D02*
Y641333D01*
X28600Y640333D01*
G01Y636333D02*
X30600D01*
G01X35200Y636166D02*
X35033Y636250D01*
Y636416D01*
X35200Y636500D01*
X35367Y636416D01*
Y636250D01*
X35200Y636166D01*
G01Y638416D02*
X35033Y638500D01*
Y638666D01*
X35200Y638750D01*
X35367Y638666D01*
Y638500D01*
X35200Y638416D01*
G01X41800Y636333D02*
Y641333D01*
X38717Y637750D01*
X42883D01*
G01X46400Y636333D02*
X46983Y636416D01*
X47650Y636666D01*
X48067Y637083D01*
X48233Y637666D01*
X48067Y638250D01*
X47567Y638750D01*
X46817Y639000D01*
X45983D01*
X45483Y639166D01*
X45067Y639583D01*
X44900Y640166D01*
X45150Y640750D01*
X45733Y641166D01*
X46400Y641333D01*
X47067Y641166D01*
X47650Y640750D01*
X47900Y640166D01*
X47733Y639583D01*
X47317Y639166D01*
X46817Y639000D01*
X45983D01*
X45233Y638750D01*
X44733Y638250D01*
X44567Y637666D01*
X44733Y637083D01*
X45150Y636666D01*
X45817Y636416D01*
X46400Y636333D01*
G01X49833D02*
Y641333D01*
X52000Y637166D01*
X54167Y641333D01*
Y636333D01*
G01X55850D02*
Y641333D01*
G01X59350D02*
Y636333D01*
G01Y638833D02*
X55850D01*
G01X61617Y641333D02*
X64783D01*
X61617Y636333D01*
X64783D01*
G01X21453Y679880D02*
X21120Y679922D01*
X20828Y680088D01*
X20578Y680338D01*
X20411Y680630D01*
X20328Y680963D01*
Y681297D01*
X20411Y681630D01*
X20578Y681922D01*
X20828Y682172D01*
X21120Y682338D01*
X21453Y682380D01*
X21786Y682338D01*
X22078Y682172D01*
X22328Y681922D01*
X22495Y681630D01*
X22578Y681297D01*
Y680963D01*
X22495Y680630D01*
X22328Y680338D01*
X22078Y680088D01*
X21786Y679922D01*
X21453Y679880D01*
G01X21786Y680547D02*
X22286Y679880D01*
G01X23845Y680172D02*
X24136Y679963D01*
X24470Y679880D01*
X24803Y679963D01*
X25095Y680213D01*
X25303Y680588D01*
X25386Y680963D01*
Y681422D01*
X25303Y681797D01*
X25095Y682130D01*
X24845Y682297D01*
X24553Y682380D01*
X24220Y682297D01*
X23970Y682130D01*
X23803Y681880D01*
X23720Y681547D01*
X23803Y681255D01*
X24011Y680963D01*
X24261Y680797D01*
X24553Y680755D01*
X24886Y680838D01*
X25136Y681047D01*
X25386Y681422D01*
G01X26736Y680255D02*
X26986Y680047D01*
X27278Y679922D01*
X27653Y679880D01*
X28028Y679963D01*
X28320Y680130D01*
X28528Y680422D01*
X28570Y680755D01*
X28486Y681088D01*
X28278Y681297D01*
X27986Y681463D01*
X27695Y681505D01*
X27403Y681463D01*
X27028Y681297D01*
X27153Y682380D01*
X28278D01*
G01X13475Y703435D02*
X13350Y703185D01*
X13267Y702893D01*
Y702560D01*
X13392Y702185D01*
X13600Y701893D01*
X13850Y701685D01*
X14267Y701518D01*
X14642Y701476D01*
X15017Y701560D01*
X15267Y701685D01*
X15517Y701935D01*
X15684Y702226D01*
X15767Y702518D01*
Y702810D01*
X15684Y703101D01*
X15559Y703351D01*
X15392Y703560D01*
G01X15767Y704576D02*
X13267Y705618D01*
X15767Y706660D01*
G01X14892Y706285D02*
Y704951D01*
G01X15767Y708718D02*
X13267D01*
X13767Y708218D01*
G01X15767D02*
Y709218D01*
G01X27970Y701570D02*
X25470D01*
Y702611D01*
X25595Y702945D01*
X25762Y703153D01*
X26095Y703236D01*
X26428Y703153D01*
X26637Y702903D01*
X26762Y702611D01*
Y701570D01*
G01Y702611D02*
X27970Y703236D01*
G01X25887Y704711D02*
X25637Y704961D01*
X25512Y705253D01*
X25470Y705586D01*
X25553Y706003D01*
X25762Y706295D01*
X26012Y706378D01*
X26262Y706336D01*
X26470Y706170D01*
X26887Y705336D01*
X27178Y704961D01*
X27595Y704711D01*
X27970Y704628D01*
Y706378D01*
G01Y708603D02*
X25470D01*
X25970Y708103D01*
G01X27970D02*
Y709103D01*
G01Y711703D02*
X25470D01*
X25970Y711203D01*
G01X27970D02*
Y712203D01*
G01X25470Y714803D02*
X25553Y714470D01*
X25762Y714220D01*
X26012Y714053D01*
X26345Y713928D01*
X26720Y713886D01*
X27095Y713928D01*
X27428Y714053D01*
X27678Y714220D01*
X27887Y714470D01*
X27970Y714803D01*
X27887Y715136D01*
X27678Y715386D01*
X27428Y715553D01*
X27095Y715678D01*
X26720Y715720D01*
X26345Y715678D01*
X26012Y715553D01*
X25762Y715386D01*
X25553Y715136D01*
X25470Y714803D01*
G01X19970Y701570D02*
X17470D01*
Y702611D01*
X17595Y702945D01*
X17762Y703153D01*
X18095Y703236D01*
X18428Y703153D01*
X18637Y702903D01*
X18762Y702611D01*
Y701570D01*
G01Y702611D02*
X19970Y703236D01*
G01X17887Y704711D02*
X17637Y704961D01*
X17512Y705253D01*
X17470Y705586D01*
X17553Y706003D01*
X17762Y706295D01*
X18012Y706378D01*
X18262Y706336D01*
X18470Y706170D01*
X18887Y705336D01*
X19178Y704961D01*
X19595Y704711D01*
X19970Y704628D01*
Y706378D01*
G01Y708603D02*
X17470D01*
X17970Y708103D01*
G01X19970D02*
Y709103D01*
G01X17470Y711703D02*
X17553Y711370D01*
X17762Y711120D01*
X18012Y710953D01*
X18345Y710828D01*
X18720Y710786D01*
X19095Y710828D01*
X19428Y710953D01*
X19678Y711120D01*
X19887Y711370D01*
X19970Y711703D01*
X19887Y712036D01*
X19678Y712286D01*
X19428Y712453D01*
X19095Y712578D01*
X18720Y712620D01*
X18345Y712578D01*
X18012Y712453D01*
X17762Y712286D01*
X17553Y712036D01*
X17470Y711703D01*
G01X17887Y714011D02*
X17637Y714261D01*
X17512Y714553D01*
X17470Y714886D01*
X17553Y715303D01*
X17762Y715595D01*
X18012Y715678D01*
X18262Y715636D01*
X18470Y715470D01*
X18887Y714636D01*
X19178Y714261D01*
X19595Y714011D01*
X19970Y713928D01*
Y715678D01*
G01X11267Y701585D02*
X8767D01*
Y702626D01*
X8892Y702960D01*
X9059Y703168D01*
X9392Y703251D01*
X9725Y703168D01*
X9934Y702918D01*
X10059Y702626D01*
Y701585D01*
G01Y702626D02*
X11267Y703251D01*
G01X9184Y704726D02*
X8934Y704976D01*
X8809Y705268D01*
X8767Y705601D01*
X8850Y706018D01*
X9059Y706310D01*
X9309Y706393D01*
X9559Y706351D01*
X9767Y706185D01*
X10184Y705351D01*
X10475Y704976D01*
X10892Y704726D01*
X11267Y704643D01*
Y706393D01*
G01X8767Y708618D02*
X8850Y708285D01*
X9059Y708035D01*
X9309Y707868D01*
X9642Y707743D01*
X10017Y707701D01*
X10392Y707743D01*
X10725Y707868D01*
X10975Y708035D01*
X11184Y708285D01*
X11267Y708618D01*
X11184Y708951D01*
X10975Y709201D01*
X10725Y709368D01*
X10392Y709493D01*
X10017Y709535D01*
X9642Y709493D01*
X9309Y709368D01*
X9059Y709201D01*
X8850Y708951D01*
X8767Y708618D01*
G01X10975Y711010D02*
X11184Y711301D01*
X11267Y711635D01*
X11184Y711968D01*
X10934Y712260D01*
X10559Y712468D01*
X10184Y712551D01*
X9725D01*
X9350Y712468D01*
X9017Y712260D01*
X8850Y712010D01*
X8767Y711718D01*
X8850Y711385D01*
X9017Y711135D01*
X9267Y710968D01*
X9600Y710885D01*
X9892Y710968D01*
X10184Y711176D01*
X10350Y711426D01*
X10392Y711718D01*
X10309Y712051D01*
X10100Y712301D01*
X9725Y712551D01*
G01X10975Y714110D02*
X11184Y714401D01*
X11267Y714735D01*
X11184Y715068D01*
X10934Y715360D01*
X10559Y715568D01*
X10184Y715651D01*
X9725D01*
X9350Y715568D01*
X9017Y715360D01*
X8850Y715110D01*
X8767Y714818D01*
X8850Y714485D01*
X9017Y714235D01*
X9267Y714068D01*
X9600Y713985D01*
X9892Y714068D01*
X10184Y714276D01*
X10350Y714526D01*
X10392Y714818D01*
X10309Y715151D01*
X10100Y715401D01*
X9725Y715651D01*
G01X29200Y707200D02*
X33200D01*
Y714600D01*
G01X21678Y703320D02*
X21553Y703070D01*
X21470Y702778D01*
Y702445D01*
X21595Y702070D01*
X21803Y701778D01*
X22053Y701570D01*
X22470Y701403D01*
X22845Y701361D01*
X23220Y701445D01*
X23470Y701570D01*
X23720Y701820D01*
X23887Y702111D01*
X23970Y702403D01*
Y702695D01*
X23887Y702986D01*
X23762Y703236D01*
X23595Y703445D01*
G01X23970Y705420D02*
X23428Y705503D01*
X22970Y705628D01*
X22553Y705795D01*
X22095Y706003D01*
X21470Y706336D01*
Y704670D01*
G01X21887Y707811D02*
X21637Y708061D01*
X21512Y708353D01*
X21470Y708686D01*
X21553Y709103D01*
X21762Y709395D01*
X22012Y709478D01*
X22262Y709436D01*
X22470Y709270D01*
X22887Y708436D01*
X23178Y708061D01*
X23595Y707811D01*
X23970Y707728D01*
Y709478D01*
G01Y711620D02*
X23428Y711703D01*
X22970Y711828D01*
X22553Y711995D01*
X22095Y712203D01*
X21470Y712536D01*
Y710870D01*
G01X21887Y714011D02*
X21637Y714261D01*
X21512Y714553D01*
X21470Y714886D01*
X21553Y715303D01*
X21762Y715595D01*
X22012Y715678D01*
X22262Y715636D01*
X22470Y715470D01*
X22887Y714636D01*
X23178Y714261D01*
X23595Y714011D01*
X23970Y713928D01*
Y715678D01*
G01X20800Y684900D02*
X34800D01*
G01X20800Y697900D02*
Y684900D01*
G01X34800Y697900D02*
X20800D01*
G01X8017Y724167D02*
Y726667D01*
X9058D01*
X9392Y726542D01*
X9600Y726375D01*
X9683Y726042D01*
X9600Y725709D01*
X9350Y725500D01*
X9058Y725375D01*
X8017D01*
G01X9058D02*
X9683Y724167D01*
G01X11158Y725209D02*
X11450Y725500D01*
X11700Y725667D01*
X12033Y725750D01*
X12325Y725667D01*
X12533Y725500D01*
X12700Y725250D01*
X12742Y724959D01*
X12700Y724709D01*
X12533Y724459D01*
X12283Y724250D01*
X11992Y724167D01*
X11658Y724250D01*
X11367Y724500D01*
X11200Y724875D01*
X11158Y725292D01*
X11242Y725834D01*
X11367Y726125D01*
X11575Y726417D01*
X11867Y726625D01*
X12158Y726667D01*
X12450Y726584D01*
X12658Y726375D01*
G01X15050Y724167D02*
X15342Y724209D01*
X15675Y724334D01*
X15883Y724542D01*
X15967Y724834D01*
X15883Y725125D01*
X15633Y725375D01*
X15258Y725500D01*
X14842D01*
X14592Y725584D01*
X14383Y725792D01*
X14300Y726084D01*
X14425Y726375D01*
X14717Y726584D01*
X15050Y726667D01*
X15383Y726584D01*
X15675Y726375D01*
X15800Y726084D01*
X15717Y725792D01*
X15508Y725584D01*
X15258Y725500D01*
X14842D01*
X14467Y725375D01*
X14217Y725125D01*
X14133Y724834D01*
X14217Y724542D01*
X14425Y724334D01*
X14758Y724209D01*
X15050Y724167D01*
G01X18150D02*
X18442Y724209D01*
X18775Y724334D01*
X18983Y724542D01*
X19067Y724834D01*
X18983Y725125D01*
X18733Y725375D01*
X18358Y725500D01*
X17942D01*
X17692Y725584D01*
X17483Y725792D01*
X17400Y726084D01*
X17525Y726375D01*
X17817Y726584D01*
X18150Y726667D01*
X18483Y726584D01*
X18775Y726375D01*
X18900Y726084D01*
X18817Y725792D01*
X18608Y725584D01*
X18358Y725500D01*
X17942D01*
X17567Y725375D01*
X17317Y725125D01*
X17233Y724834D01*
X17317Y724542D01*
X17525Y724334D01*
X17858Y724209D01*
X18150Y724167D01*
G01X23100Y722400D02*
Y718400D01*
X30500D01*
G01Y744900D02*
Y748900D01*
X23100D01*
G01X12834Y738917D02*
X10334D01*
Y739917D01*
X10459Y740250D01*
X10751Y740500D01*
X11084Y740583D01*
X11417Y740500D01*
X11667Y740292D01*
X11792Y739917D01*
Y738917D01*
G01X12834Y742017D02*
X10334D01*
Y743058D01*
X10459Y743392D01*
X10626Y743600D01*
X10959Y743683D01*
X11292Y743600D01*
X11501Y743350D01*
X11626Y743058D01*
Y742017D01*
G01Y743058D02*
X12834Y743683D01*
G01X12542Y745242D02*
X12751Y745533D01*
X12834Y745867D01*
X12751Y746200D01*
X12501Y746492D01*
X12126Y746700D01*
X11751Y746783D01*
X11292D01*
X10917Y746700D01*
X10584Y746492D01*
X10417Y746242D01*
X10334Y745950D01*
X10417Y745617D01*
X10584Y745367D01*
X10834Y745200D01*
X11167Y745117D01*
X11459Y745200D01*
X11751Y745408D01*
X11917Y745658D01*
X11959Y745950D01*
X11876Y746283D01*
X11667Y746533D01*
X11292Y746783D01*
G01X10334Y749050D02*
X10417Y748717D01*
X10626Y748467D01*
X10876Y748300D01*
X11209Y748175D01*
X11584Y748133D01*
X11959Y748175D01*
X12292Y748300D01*
X12542Y748467D01*
X12751Y748717D01*
X12834Y749050D01*
X12751Y749383D01*
X12542Y749633D01*
X12292Y749800D01*
X11959Y749925D01*
X11584Y749967D01*
X11209Y749925D01*
X10876Y749800D01*
X10626Y749633D01*
X10417Y749383D01*
X10334Y749050D01*
G01Y752150D02*
X10417Y751817D01*
X10626Y751567D01*
X10876Y751400D01*
X11209Y751275D01*
X11584Y751233D01*
X11959Y751275D01*
X12292Y751400D01*
X12542Y751567D01*
X12751Y751817D01*
X12834Y752150D01*
X12751Y752483D01*
X12542Y752733D01*
X12292Y752900D01*
X11959Y753025D01*
X11584Y753067D01*
X11209Y753025D01*
X10876Y752900D01*
X10626Y752733D01*
X10417Y752483D01*
X10334Y752150D01*
G01X12834Y755167D02*
X12292Y755250D01*
X11834Y755375D01*
X11417Y755542D01*
X10959Y755750D01*
X10334Y756083D01*
Y754417D01*
G01X27300Y744600D02*
X23300D01*
Y737200D01*
G01X3217Y733400D02*
Y735900D01*
X4217D01*
X4550Y735775D01*
X4800Y735483D01*
X4883Y735150D01*
X4800Y734817D01*
X4592Y734567D01*
X4217Y734442D01*
X3217D01*
G01X6317Y733400D02*
Y735900D01*
X7358D01*
X7692Y735775D01*
X7900Y735608D01*
X7983Y735275D01*
X7900Y734942D01*
X7650Y734733D01*
X7358Y734608D01*
X6317D01*
G01X7358D02*
X7983Y733400D01*
G01X9542Y733692D02*
X9833Y733483D01*
X10167Y733400D01*
X10500Y733483D01*
X10792Y733733D01*
X11000Y734108D01*
X11083Y734483D01*
Y734942D01*
X11000Y735317D01*
X10792Y735650D01*
X10542Y735817D01*
X10250Y735900D01*
X9917Y735817D01*
X9667Y735650D01*
X9500Y735400D01*
X9417Y735067D01*
X9500Y734775D01*
X9708Y734483D01*
X9958Y734317D01*
X10250Y734275D01*
X10583Y734358D01*
X10833Y734567D01*
X11083Y734942D01*
G01X13350Y735900D02*
X13017Y735817D01*
X12767Y735608D01*
X12600Y735358D01*
X12475Y735025D01*
X12433Y734650D01*
X12475Y734275D01*
X12600Y733942D01*
X12767Y733692D01*
X13017Y733483D01*
X13350Y733400D01*
X13683Y733483D01*
X13933Y733692D01*
X14100Y733942D01*
X14225Y734275D01*
X14267Y734650D01*
X14225Y735025D01*
X14100Y735358D01*
X13933Y735608D01*
X13683Y735817D01*
X13350Y735900D01*
G01X16450D02*
X16117Y735817D01*
X15867Y735608D01*
X15700Y735358D01*
X15575Y735025D01*
X15533Y734650D01*
X15575Y734275D01*
X15700Y733942D01*
X15867Y733692D01*
X16117Y733483D01*
X16450Y733400D01*
X16783Y733483D01*
X17033Y733692D01*
X17200Y733942D01*
X17325Y734275D01*
X17367Y734650D01*
X17325Y735025D01*
X17200Y735358D01*
X17033Y735608D01*
X16783Y735817D01*
X16450Y735900D01*
G01X18758Y734442D02*
X19050Y734733D01*
X19300Y734900D01*
X19633Y734983D01*
X19925Y734900D01*
X20133Y734733D01*
X20300Y734483D01*
X20342Y734192D01*
X20300Y733942D01*
X20133Y733692D01*
X19883Y733483D01*
X19592Y733400D01*
X19258Y733483D01*
X18967Y733733D01*
X18800Y734108D01*
X18758Y734525D01*
X18842Y735067D01*
X18967Y735358D01*
X19175Y735650D01*
X19467Y735858D01*
X19758Y735900D01*
X20050Y735817D01*
X20258Y735608D01*
G01X30500Y731400D02*
Y735400D01*
X23100D01*
G01X3217Y729400D02*
Y731900D01*
X4217D01*
X4550Y731775D01*
X4800Y731483D01*
X4883Y731150D01*
X4800Y730817D01*
X4592Y730567D01*
X4217Y730442D01*
X3217D01*
G01X6317Y729400D02*
Y731900D01*
X7358D01*
X7692Y731775D01*
X7900Y731608D01*
X7983Y731275D01*
X7900Y730942D01*
X7650Y730733D01*
X7358Y730608D01*
X6317D01*
G01X7358D02*
X7983Y729400D01*
G01X9542Y729692D02*
X9833Y729483D01*
X10167Y729400D01*
X10500Y729483D01*
X10792Y729733D01*
X11000Y730108D01*
X11083Y730483D01*
Y730942D01*
X11000Y731317D01*
X10792Y731650D01*
X10542Y731817D01*
X10250Y731900D01*
X9917Y731817D01*
X9667Y731650D01*
X9500Y731400D01*
X9417Y731067D01*
X9500Y730775D01*
X9708Y730483D01*
X9958Y730317D01*
X10250Y730275D01*
X10583Y730358D01*
X10833Y730567D01*
X11083Y730942D01*
G01X13350Y731900D02*
X13017Y731817D01*
X12767Y731608D01*
X12600Y731358D01*
X12475Y731025D01*
X12433Y730650D01*
X12475Y730275D01*
X12600Y729942D01*
X12767Y729692D01*
X13017Y729483D01*
X13350Y729400D01*
X13683Y729483D01*
X13933Y729692D01*
X14100Y729942D01*
X14225Y730275D01*
X14267Y730650D01*
X14225Y731025D01*
X14100Y731358D01*
X13933Y731608D01*
X13683Y731817D01*
X13350Y731900D01*
G01X16450D02*
X16117Y731817D01*
X15867Y731608D01*
X15700Y731358D01*
X15575Y731025D01*
X15533Y730650D01*
X15575Y730275D01*
X15700Y729942D01*
X15867Y729692D01*
X16117Y729483D01*
X16450Y729400D01*
X16783Y729483D01*
X17033Y729692D01*
X17200Y729942D01*
X17325Y730275D01*
X17367Y730650D01*
X17325Y731025D01*
X17200Y731358D01*
X17033Y731608D01*
X16783Y731817D01*
X16450Y731900D01*
G01X20050Y729400D02*
Y731900D01*
X18508Y730108D01*
X20592D01*
G01X30500Y727400D02*
Y731400D01*
X23100D01*
G01X31334Y762967D02*
X28834D01*
Y764008D01*
X28959Y764342D01*
X29126Y764550D01*
X29459Y764633D01*
X29792Y764550D01*
X30001Y764300D01*
X30126Y764008D01*
Y762967D01*
G01Y764008D02*
X31334Y764633D01*
G01X29251Y766108D02*
X29001Y766358D01*
X28876Y766650D01*
X28834Y766983D01*
X28917Y767400D01*
X29126Y767692D01*
X29376Y767775D01*
X29626Y767733D01*
X29834Y767567D01*
X30251Y766733D01*
X30542Y766358D01*
X30959Y766108D01*
X31334Y766025D01*
Y767775D01*
G01Y770000D02*
X28834D01*
X29334Y769500D01*
G01X31334D02*
Y770500D01*
G01Y773017D02*
X30792Y773100D01*
X30334Y773225D01*
X29917Y773392D01*
X29459Y773600D01*
X28834Y773933D01*
Y772267D01*
G01X31334Y776700D02*
X28834D01*
X30626Y775158D01*
Y777242D01*
G01X27334Y762967D02*
X24834D01*
Y764008D01*
X24959Y764342D01*
X25126Y764550D01*
X25459Y764633D01*
X25792Y764550D01*
X26001Y764300D01*
X26126Y764008D01*
Y762967D01*
G01Y764008D02*
X27334Y764633D01*
G01X25251Y766108D02*
X25001Y766358D01*
X24876Y766650D01*
X24834Y766983D01*
X24917Y767400D01*
X25126Y767692D01*
X25376Y767775D01*
X25626Y767733D01*
X25834Y767567D01*
X26251Y766733D01*
X26542Y766358D01*
X26959Y766108D01*
X27334Y766025D01*
Y767775D01*
G01Y770000D02*
X24834D01*
X25334Y769500D01*
G01X27334D02*
Y770500D01*
G01Y773100D02*
X24834D01*
X25334Y772600D01*
G01X27334D02*
Y773600D01*
G01Y776117D02*
X26792Y776200D01*
X26334Y776325D01*
X25917Y776492D01*
X25459Y776700D01*
X24834Y777033D01*
Y775367D01*
G01X17042Y764717D02*
X16917Y764467D01*
X16834Y764175D01*
Y763842D01*
X16959Y763467D01*
X17167Y763175D01*
X17417Y762967D01*
X17834Y762800D01*
X18209Y762758D01*
X18584Y762842D01*
X18834Y762967D01*
X19084Y763217D01*
X19251Y763508D01*
X19334Y763800D01*
Y764092D01*
X19251Y764383D01*
X19126Y764633D01*
X18959Y764842D01*
G01X19334Y766817D02*
X18792Y766900D01*
X18334Y767025D01*
X17917Y767192D01*
X17459Y767400D01*
X16834Y767733D01*
Y766067D01*
G01X18834Y769083D02*
X19126Y769333D01*
X19292Y769667D01*
X19334Y770042D01*
X19292Y770375D01*
X19084Y770708D01*
X18834Y770917D01*
X18584Y770958D01*
X18292Y770875D01*
X18084Y770583D01*
X18001Y770292D01*
Y769917D01*
G01Y770292D02*
X17876Y770542D01*
X17667Y770750D01*
X17417Y770833D01*
X17167Y770750D01*
X16959Y770542D01*
X16834Y770167D01*
X16876Y769792D01*
X17042Y769417D01*
G01X19334Y773100D02*
X16834D01*
X17334Y772600D01*
G01X19334D02*
Y773600D01*
G01Y776117D02*
X18792Y776200D01*
X18334Y776325D01*
X17917Y776492D01*
X17459Y776700D01*
X16834Y777033D01*
Y775367D01*
G01X9967Y780167D02*
Y782667D01*
X11008D01*
X11342Y782542D01*
X11550Y782375D01*
X11633Y782042D01*
X11550Y781709D01*
X11300Y781500D01*
X11008Y781375D01*
X9967D01*
G01X11008D02*
X11633Y780167D01*
G01X13192Y780459D02*
X13483Y780250D01*
X13817Y780167D01*
X14150Y780250D01*
X14442Y780500D01*
X14650Y780875D01*
X14733Y781250D01*
Y781709D01*
X14650Y782084D01*
X14442Y782417D01*
X14192Y782584D01*
X13900Y782667D01*
X13567Y782584D01*
X13317Y782417D01*
X13150Y782167D01*
X13067Y781834D01*
X13150Y781542D01*
X13358Y781250D01*
X13608Y781084D01*
X13900Y781042D01*
X14233Y781125D01*
X14483Y781334D01*
X14733Y781709D01*
G01X17000Y782667D02*
X16667Y782584D01*
X16417Y782375D01*
X16250Y782125D01*
X16125Y781792D01*
X16083Y781417D01*
X16125Y781042D01*
X16250Y780709D01*
X16417Y780459D01*
X16667Y780250D01*
X17000Y780167D01*
X17333Y780250D01*
X17583Y780459D01*
X17750Y780709D01*
X17875Y781042D01*
X17917Y781417D01*
X17875Y781792D01*
X17750Y782125D01*
X17583Y782375D01*
X17333Y782584D01*
X17000Y782667D01*
G01X19308Y782250D02*
X19558Y782500D01*
X19850Y782625D01*
X20183Y782667D01*
X20600Y782584D01*
X20892Y782375D01*
X20975Y782125D01*
X20933Y781875D01*
X20767Y781667D01*
X19933Y781250D01*
X19558Y780959D01*
X19308Y780542D01*
X19225Y780167D01*
X20975D01*
G01X23117D02*
X23200Y780709D01*
X23325Y781167D01*
X23492Y781584D01*
X23700Y782042D01*
X24033Y782667D01*
X22367D01*
G01X23334Y762967D02*
X20834D01*
Y764008D01*
X20959Y764342D01*
X21126Y764550D01*
X21459Y764633D01*
X21792Y764550D01*
X22001Y764300D01*
X22126Y764008D01*
Y762967D01*
G01Y764008D02*
X23334Y764633D01*
G01X23042Y766192D02*
X23251Y766483D01*
X23334Y766817D01*
X23251Y767150D01*
X23001Y767442D01*
X22626Y767650D01*
X22251Y767733D01*
X21792D01*
X21417Y767650D01*
X21084Y767442D01*
X20917Y767192D01*
X20834Y766900D01*
X20917Y766567D01*
X21084Y766317D01*
X21334Y766150D01*
X21667Y766067D01*
X21959Y766150D01*
X22251Y766358D01*
X22417Y766608D01*
X22459Y766900D01*
X22376Y767233D01*
X22167Y767483D01*
X21792Y767733D01*
G01X20834Y770000D02*
X20917Y769667D01*
X21126Y769417D01*
X21376Y769250D01*
X21709Y769125D01*
X22084Y769083D01*
X22459Y769125D01*
X22792Y769250D01*
X23042Y769417D01*
X23251Y769667D01*
X23334Y770000D01*
X23251Y770333D01*
X23042Y770583D01*
X22792Y770750D01*
X22459Y770875D01*
X22084Y770917D01*
X21709Y770875D01*
X21376Y770750D01*
X21126Y770583D01*
X20917Y770333D01*
X20834Y770000D01*
G01X21251Y772308D02*
X21001Y772558D01*
X20876Y772850D01*
X20834Y773183D01*
X20917Y773600D01*
X21126Y773892D01*
X21376Y773975D01*
X21626Y773933D01*
X21834Y773767D01*
X22251Y772933D01*
X22542Y772558D01*
X22959Y772308D01*
X23334Y772225D01*
Y773975D01*
G01X22834Y775283D02*
X23126Y775533D01*
X23292Y775867D01*
X23334Y776242D01*
X23292Y776575D01*
X23084Y776908D01*
X22834Y777117D01*
X22584Y777158D01*
X22292Y777075D01*
X22084Y776783D01*
X22001Y776492D01*
Y776117D01*
G01Y776492D02*
X21876Y776742D01*
X21667Y776950D01*
X21417Y777033D01*
X21167Y776950D01*
X20959Y776742D01*
X20834Y776367D01*
X20876Y775992D01*
X21042Y775617D01*
G01X7334Y762967D02*
X4834D01*
Y764008D01*
X4959Y764342D01*
X5126Y764550D01*
X5459Y764633D01*
X5792Y764550D01*
X6001Y764300D01*
X6126Y764008D01*
Y762967D01*
G01Y764008D02*
X7334Y764633D01*
G01X5251Y766108D02*
X5001Y766358D01*
X4876Y766650D01*
X4834Y766983D01*
X4917Y767400D01*
X5126Y767692D01*
X5376Y767775D01*
X5626Y767733D01*
X5834Y767567D01*
X6251Y766733D01*
X6542Y766358D01*
X6959Y766108D01*
X7334Y766025D01*
Y767775D01*
G01Y770000D02*
X4834D01*
X5334Y769500D01*
G01X7334D02*
Y770500D01*
G01Y773017D02*
X6792Y773100D01*
X6334Y773225D01*
X5917Y773392D01*
X5459Y773600D01*
X4834Y773933D01*
Y772267D01*
G01X5251Y775408D02*
X5001Y775658D01*
X4876Y775950D01*
X4834Y776283D01*
X4917Y776700D01*
X5126Y776992D01*
X5376Y777075D01*
X5626Y777033D01*
X5834Y776867D01*
X6251Y776033D01*
X6542Y775658D01*
X6959Y775408D01*
X7334Y775325D01*
Y777075D01*
G01X9967Y757667D02*
Y760167D01*
X11008D01*
X11342Y760042D01*
X11550Y759875D01*
X11633Y759542D01*
X11550Y759209D01*
X11300Y759000D01*
X11008Y758875D01*
X9967D01*
G01X11008D02*
X11633Y757667D01*
G01X13108Y759750D02*
X13358Y760000D01*
X13650Y760125D01*
X13983Y760167D01*
X14400Y760084D01*
X14692Y759875D01*
X14775Y759625D01*
X14733Y759375D01*
X14567Y759167D01*
X13733Y758750D01*
X13358Y758459D01*
X13108Y758042D01*
X13025Y757667D01*
X14775D01*
G01X17000D02*
Y760167D01*
X16500Y759667D01*
G01Y757667D02*
X17500D01*
G01X20100D02*
Y760167D01*
X19600Y759667D01*
G01Y757667D02*
X20600D01*
G01X22283Y758167D02*
X22533Y757875D01*
X22867Y757709D01*
X23242Y757667D01*
X23575Y757709D01*
X23908Y757917D01*
X24117Y758167D01*
X24158Y758417D01*
X24075Y758709D01*
X23783Y758917D01*
X23492Y759000D01*
X23117D01*
G01X23492D02*
X23742Y759125D01*
X23950Y759334D01*
X24033Y759584D01*
X23950Y759834D01*
X23742Y760042D01*
X23367Y760167D01*
X22992Y760125D01*
X22617Y759959D01*
G01X11334Y762967D02*
X8834D01*
Y764008D01*
X8959Y764342D01*
X9126Y764550D01*
X9459Y764633D01*
X9792Y764550D01*
X10001Y764300D01*
X10126Y764008D01*
Y762967D01*
G01Y764008D02*
X11334Y764633D01*
G01X9251Y766108D02*
X9001Y766358D01*
X8876Y766650D01*
X8834Y766983D01*
X8917Y767400D01*
X9126Y767692D01*
X9376Y767775D01*
X9626Y767733D01*
X9834Y767567D01*
X10251Y766733D01*
X10542Y766358D01*
X10959Y766108D01*
X11334Y766025D01*
Y767775D01*
G01Y770000D02*
X8834D01*
X9334Y769500D01*
G01X11334D02*
Y770500D01*
G01X8834Y773100D02*
X8917Y772767D01*
X9126Y772517D01*
X9376Y772350D01*
X9709Y772225D01*
X10084Y772183D01*
X10459Y772225D01*
X10792Y772350D01*
X11042Y772517D01*
X11251Y772767D01*
X11334Y773100D01*
X11251Y773433D01*
X11042Y773683D01*
X10792Y773850D01*
X10459Y773975D01*
X10084Y774017D01*
X9709Y773975D01*
X9376Y773850D01*
X9126Y773683D01*
X8917Y773433D01*
X8834Y773100D01*
G01X10834Y775283D02*
X11126Y775533D01*
X11292Y775867D01*
X11334Y776242D01*
X11292Y776575D01*
X11084Y776908D01*
X10834Y777117D01*
X10584Y777158D01*
X10292Y777075D01*
X10084Y776783D01*
X10001Y776492D01*
Y776117D01*
G01Y776492D02*
X9876Y776742D01*
X9667Y776950D01*
X9417Y777033D01*
X9167Y776950D01*
X8959Y776742D01*
X8834Y776367D01*
X8876Y775992D01*
X9042Y775617D01*
G01X13042Y764717D02*
X12917Y764467D01*
X12834Y764175D01*
Y763842D01*
X12959Y763467D01*
X13167Y763175D01*
X13417Y762967D01*
X13834Y762800D01*
X14209Y762758D01*
X14584Y762842D01*
X14834Y762967D01*
X15084Y763217D01*
X15251Y763508D01*
X15334Y763800D01*
Y764092D01*
X15251Y764383D01*
X15126Y764633D01*
X14959Y764842D01*
G01X15334Y766817D02*
X14792Y766900D01*
X14334Y767025D01*
X13917Y767192D01*
X13459Y767400D01*
X12834Y767733D01*
Y766067D01*
G01X13251Y769208D02*
X13001Y769458D01*
X12876Y769750D01*
X12834Y770083D01*
X12917Y770500D01*
X13126Y770792D01*
X13376Y770875D01*
X13626Y770833D01*
X13834Y770667D01*
X14251Y769833D01*
X14542Y769458D01*
X14959Y769208D01*
X15334Y769125D01*
Y770875D01*
G01Y773017D02*
X14792Y773100D01*
X14334Y773225D01*
X13917Y773392D01*
X13459Y773600D01*
X12834Y773933D01*
Y772267D01*
G01X14834Y775283D02*
X15126Y775533D01*
X15292Y775867D01*
X15334Y776242D01*
X15292Y776575D01*
X15084Y776908D01*
X14834Y777117D01*
X14584Y777158D01*
X14292Y777075D01*
X14084Y776783D01*
X14001Y776492D01*
Y776117D01*
G01Y776492D02*
X13876Y776742D01*
X13667Y776950D01*
X13417Y777033D01*
X13167Y776950D01*
X12959Y776742D01*
X12834Y776367D01*
X12876Y775992D01*
X13042Y775617D01*
G01X13217Y787092D02*
X12967Y787217D01*
X12675Y787300D01*
X12342D01*
X11967Y787175D01*
X11675Y786967D01*
X11467Y786717D01*
X11300Y786300D01*
X11258Y785925D01*
X11342Y785550D01*
X11467Y785300D01*
X11717Y785050D01*
X12008Y784883D01*
X12300Y784800D01*
X12592D01*
X12883Y784883D01*
X13133Y785008D01*
X13342Y785175D01*
G01X15317Y784800D02*
X15400Y785342D01*
X15525Y785800D01*
X15692Y786217D01*
X15900Y786675D01*
X16233Y787300D01*
X14567D01*
G01X17708Y786883D02*
X17958Y787133D01*
X18250Y787258D01*
X18583Y787300D01*
X19000Y787217D01*
X19292Y787008D01*
X19375Y786758D01*
X19333Y786508D01*
X19167Y786300D01*
X18333Y785883D01*
X17958Y785592D01*
X17708Y785175D01*
X17625Y784800D01*
X19375D01*
G01X21517D02*
X21600Y785342D01*
X21725Y785800D01*
X21892Y786217D01*
X22100Y786675D01*
X22433Y787300D01*
X20767D01*
G01X24700Y784800D02*
X24992Y784842D01*
X25325Y784967D01*
X25533Y785175D01*
X25617Y785467D01*
X25533Y785758D01*
X25283Y786008D01*
X24908Y786133D01*
X24492D01*
X24242Y786217D01*
X24033Y786425D01*
X23950Y786717D01*
X24075Y787008D01*
X24367Y787217D01*
X24700Y787300D01*
X25033Y787217D01*
X25325Y787008D01*
X25450Y786717D01*
X25367Y786425D01*
X25158Y786217D01*
X24908Y786133D01*
X24492D01*
X24117Y786008D01*
X23867Y785758D01*
X23783Y785467D01*
X23867Y785175D01*
X24075Y784967D01*
X24408Y784842D01*
X24700Y784800D01*
G01X69300Y196800D02*
X57000D01*
G01X53100D02*
X42300D01*
G01X35650Y207300D02*
X39650D01*
Y214700D01*
G01X51000Y202500D02*
X55000D01*
Y209900D01*
G01X39650Y207300D02*
X43650D01*
Y214700D01*
G01X55000Y202500D02*
X59000D01*
Y209900D01*
G01X67800Y221200D02*
X70133D01*
Y218800D01*
X69433Y218000D01*
X68617Y217467D01*
X67450Y217200D01*
X66283Y217467D01*
X65467Y218000D01*
X64767Y218800D01*
X64300Y219733D01*
X64067Y220800D01*
Y221733D01*
X64300Y222533D01*
X64767Y223467D01*
X65467Y224267D01*
X66167Y224800D01*
X67100Y225200D01*
X67917D01*
X68850Y224933D01*
X69550Y224400D01*
G01X42600Y216000D02*
X62400D01*
Y222300D01*
G01X30542Y227767D02*
X30417Y227517D01*
X30334Y227225D01*
Y226892D01*
X30459Y226517D01*
X30667Y226225D01*
X30917Y226017D01*
X31334Y225850D01*
X31709Y225808D01*
X32084Y225892D01*
X32334Y226017D01*
X32584Y226267D01*
X32751Y226558D01*
X32834Y226850D01*
Y227142D01*
X32751Y227433D01*
X32626Y227683D01*
X32459Y227892D01*
G01X32834Y230450D02*
X30334D01*
X32126Y228908D01*
Y230992D01*
G01X30751Y232258D02*
X30501Y232508D01*
X30376Y232800D01*
X30334Y233133D01*
X30417Y233550D01*
X30626Y233842D01*
X30876Y233925D01*
X31126Y233883D01*
X31334Y233717D01*
X31751Y232883D01*
X32042Y232508D01*
X32459Y232258D01*
X32834Y232175D01*
Y233925D01*
G01Y236150D02*
X30334D01*
X30834Y235650D01*
G01X32834D02*
Y236650D01*
G01X47700Y274800D02*
Y278800D01*
X40300D01*
G01X58705Y277183D02*
Y274183D01*
G01X49800Y281200D02*
Y276200D01*
X54800D01*
G01X35700Y293700D02*
Y265100D01*
G01X41633Y310100D02*
Y318100D01*
X43967D01*
X44900Y317700D01*
X45600Y317167D01*
X46183Y316367D01*
X46650Y315433D01*
X46767Y314100D01*
X46650Y312767D01*
X46183Y311833D01*
X45600Y311033D01*
X44900Y310500D01*
X43967Y310100D01*
X41633D01*
G01X47700Y278900D02*
Y282900D01*
X40300D01*
G01X50783Y308727D02*
X48783D01*
G01X50783Y298884D02*
X47783D01*
G01X50783Y289042D02*
X48783D01*
G01X69100Y334090D02*
X51760D01*
Y324650D01*
X50800D01*
G01X52834Y341075D02*
X50334Y342825D01*
G01Y341075D02*
X52834Y342825D01*
G01Y345050D02*
X50334D01*
X50834Y344550D01*
G01X52834D02*
Y345550D01*
G01X60963Y343787D02*
Y346287D01*
X62004D01*
X62338Y346162D01*
X62546Y345995D01*
X62629Y345662D01*
X62546Y345329D01*
X62296Y345120D01*
X62004Y344995D01*
X60963D01*
G01X62004D02*
X62629Y343787D01*
G01X64104Y345870D02*
X64354Y346120D01*
X64646Y346245D01*
X64979Y346287D01*
X65396Y346204D01*
X65688Y345995D01*
X65771Y345745D01*
X65729Y345495D01*
X65563Y345287D01*
X64729Y344870D01*
X64354Y344579D01*
X64104Y344162D01*
X64021Y343787D01*
X65771D01*
G01X67288Y344079D02*
X67579Y343870D01*
X67913Y343787D01*
X68246Y343870D01*
X68538Y344120D01*
X68746Y344495D01*
X68829Y344870D01*
Y345329D01*
X68746Y345704D01*
X68538Y346037D01*
X68288Y346204D01*
X67996Y346287D01*
X67663Y346204D01*
X67413Y346037D01*
X67246Y345787D01*
X67163Y345454D01*
X67246Y345162D01*
X67454Y344870D01*
X67704Y344704D01*
X67996Y344662D01*
X68329Y344745D01*
X68579Y344954D01*
X68829Y345329D01*
G01X71596Y343787D02*
Y346287D01*
X70054Y344495D01*
X72138D01*
G01X74196Y343787D02*
Y346287D01*
X73696Y345787D01*
G01Y343787D02*
X74696D01*
G01X60300Y332900D02*
X56300D01*
Y325500D01*
G01X64800Y332600D02*
X60800D01*
Y325200D01*
G01X39600Y323400D02*
Y319400D01*
X47000D01*
G01X60673Y318617D02*
Y321617D01*
G01X54800Y319600D02*
X49800D01*
Y314600D01*
G01X60649Y347933D02*
Y350433D01*
X61690D01*
X62024Y350308D01*
X62232Y350141D01*
X62315Y349808D01*
X62232Y349475D01*
X61982Y349266D01*
X61690Y349141D01*
X60649D01*
G01X61690D02*
X62315Y347933D01*
G01X63790Y350016D02*
X64040Y350266D01*
X64332Y350391D01*
X64665Y350433D01*
X65082Y350350D01*
X65374Y350141D01*
X65457Y349891D01*
X65415Y349641D01*
X65249Y349433D01*
X64415Y349016D01*
X64040Y348725D01*
X63790Y348308D01*
X63707Y347933D01*
X65457D01*
G01X66974Y348225D02*
X67265Y348016D01*
X67599Y347933D01*
X67932Y348016D01*
X68224Y348266D01*
X68432Y348641D01*
X68515Y349016D01*
Y349475D01*
X68432Y349850D01*
X68224Y350183D01*
X67974Y350350D01*
X67682Y350433D01*
X67349Y350350D01*
X67099Y350183D01*
X66932Y349933D01*
X66849Y349600D01*
X66932Y349308D01*
X67140Y349016D01*
X67390Y348850D01*
X67682Y348808D01*
X68015Y348891D01*
X68265Y349100D01*
X68515Y349475D01*
G01X69865Y348433D02*
X70115Y348141D01*
X70449Y347975D01*
X70824Y347933D01*
X71157Y347975D01*
X71490Y348183D01*
X71699Y348433D01*
X71740Y348683D01*
X71657Y348975D01*
X71365Y349183D01*
X71074Y349266D01*
X70699D01*
G01X71074D02*
X71324Y349391D01*
X71532Y349600D01*
X71615Y349850D01*
X71532Y350100D01*
X71324Y350308D01*
X70949Y350433D01*
X70574Y350391D01*
X70199Y350225D01*
G01X73882Y347933D02*
X74174Y347975D01*
X74507Y348100D01*
X74715Y348308D01*
X74799Y348600D01*
X74715Y348891D01*
X74465Y349141D01*
X74090Y349266D01*
X73674D01*
X73424Y349350D01*
X73215Y349558D01*
X73132Y349850D01*
X73257Y350141D01*
X73549Y350350D01*
X73882Y350433D01*
X74215Y350350D01*
X74507Y350141D01*
X74632Y349850D01*
X74549Y349558D01*
X74340Y349350D01*
X74090Y349266D01*
X73674D01*
X73299Y349141D01*
X73049Y348891D01*
X72965Y348600D01*
X73049Y348308D01*
X73257Y348100D01*
X73590Y347975D01*
X73882Y347933D01*
G01X51422Y352414D02*
X55422D01*
Y359814D01*
G01X31566Y368707D02*
X50766D01*
Y379907D01*
X31566D01*
Y368707D01*
X31966D01*
G01X31666Y376307D02*
X33766Y374507D01*
X31666Y372307D01*
G01X56050Y354033D02*
Y370133D01*
G01X63050Y354033D02*
X56050D01*
G01X63050Y370133D02*
Y354033D01*
G01X56050Y370133D02*
X63050D01*
G01X50067Y412000D02*
Y414500D01*
X51067D01*
X51400Y414375D01*
X51650Y414083D01*
X51733Y413750D01*
X51650Y413417D01*
X51442Y413167D01*
X51067Y413042D01*
X50067D01*
G01X53083Y414500D02*
Y412708D01*
X53250Y412333D01*
X53583Y412083D01*
X54000Y412000D01*
X54417Y412083D01*
X54750Y412333D01*
X54917Y412708D01*
Y414500D01*
G01X56183Y412375D02*
X56433Y412167D01*
X56725Y412042D01*
X57100Y412000D01*
X57475Y412083D01*
X57767Y412250D01*
X57975Y412542D01*
X58017Y412875D01*
X57933Y413208D01*
X57725Y413417D01*
X57433Y413583D01*
X57142Y413625D01*
X56850Y413583D01*
X56475Y413417D01*
X56600Y414500D01*
X57725D01*
G01X36517Y407500D02*
Y410000D01*
X37517D01*
X37850Y409875D01*
X38100Y409583D01*
X38183Y409250D01*
X38100Y408917D01*
X37892Y408667D01*
X37517Y408542D01*
X36517D01*
G01X39617Y407500D02*
Y410000D01*
X40658D01*
X40992Y409875D01*
X41200Y409708D01*
X41283Y409375D01*
X41200Y409042D01*
X40950Y408833D01*
X40658Y408708D01*
X39617D01*
G01X40658D02*
X41283Y407500D01*
G01X43467D02*
X43550Y408042D01*
X43675Y408500D01*
X43842Y408917D01*
X44050Y409375D01*
X44383Y410000D01*
X42717D01*
G01X45858Y409583D02*
X46108Y409833D01*
X46400Y409958D01*
X46733Y410000D01*
X47150Y409917D01*
X47442Y409708D01*
X47525Y409458D01*
X47483Y409208D01*
X47317Y409000D01*
X46483Y408583D01*
X46108Y408292D01*
X45858Y407875D01*
X45775Y407500D01*
X47525D01*
G01X65736Y390334D02*
X63236D01*
Y391375D01*
X63361Y391709D01*
X63528Y391917D01*
X63861Y392000D01*
X64194Y391917D01*
X64403Y391667D01*
X64528Y391375D01*
Y390334D01*
G01Y391375D02*
X65736Y392000D01*
G01X63653Y393475D02*
X63403Y393725D01*
X63278Y394017D01*
X63236Y394350D01*
X63319Y394767D01*
X63528Y395059D01*
X63778Y395142D01*
X64028Y395100D01*
X64236Y394934D01*
X64653Y394100D01*
X64944Y393725D01*
X65361Y393475D01*
X65736Y393392D01*
Y395142D01*
G01X65444Y396659D02*
X65653Y396950D01*
X65736Y397284D01*
X65653Y397617D01*
X65403Y397909D01*
X65028Y398117D01*
X64653Y398200D01*
X64194D01*
X63819Y398117D01*
X63486Y397909D01*
X63319Y397659D01*
X63236Y397367D01*
X63319Y397034D01*
X63486Y396784D01*
X63736Y396617D01*
X64069Y396534D01*
X64361Y396617D01*
X64653Y396825D01*
X64819Y397075D01*
X64861Y397367D01*
X64778Y397700D01*
X64569Y397950D01*
X64194Y398200D01*
G01X65361Y399550D02*
X65569Y399800D01*
X65694Y400092D01*
X65736Y400467D01*
X65653Y400842D01*
X65486Y401134D01*
X65194Y401342D01*
X64861Y401384D01*
X64528Y401300D01*
X64319Y401092D01*
X64153Y400800D01*
X64111Y400509D01*
X64153Y400217D01*
X64319Y399842D01*
X63236Y399967D01*
Y401092D01*
G01Y403567D02*
X63319Y403234D01*
X63528Y402984D01*
X63778Y402817D01*
X64111Y402692D01*
X64486Y402650D01*
X64861Y402692D01*
X65194Y402817D01*
X65444Y402984D01*
X65653Y403234D01*
X65736Y403567D01*
X65653Y403900D01*
X65444Y404150D01*
X65194Y404317D01*
X64861Y404442D01*
X64486Y404484D01*
X64111Y404442D01*
X63778Y404317D01*
X63528Y404150D01*
X63319Y403900D01*
X63236Y403567D01*
G01X61150Y390502D02*
X58650D01*
Y391543D01*
X58775Y391877D01*
X58942Y392085D01*
X59275Y392168D01*
X59608Y392085D01*
X59817Y391835D01*
X59942Y391543D01*
Y390502D01*
G01Y391543D02*
X61150Y392168D01*
G01Y394935D02*
X58650D01*
X60442Y393393D01*
Y395477D01*
G01X60858Y396827D02*
X61067Y397118D01*
X61150Y397452D01*
X61067Y397785D01*
X60817Y398077D01*
X60442Y398285D01*
X60067Y398368D01*
X59608D01*
X59233Y398285D01*
X58900Y398077D01*
X58733Y397827D01*
X58650Y397535D01*
X58733Y397202D01*
X58900Y396952D01*
X59150Y396785D01*
X59483Y396702D01*
X59775Y396785D01*
X60067Y396993D01*
X60233Y397243D01*
X60275Y397535D01*
X60192Y397868D01*
X59983Y398118D01*
X59608Y398368D01*
G01X60775Y399718D02*
X60983Y399968D01*
X61108Y400260D01*
X61150Y400635D01*
X61067Y401010D01*
X60900Y401302D01*
X60608Y401510D01*
X60275Y401552D01*
X59942Y401468D01*
X59733Y401260D01*
X59567Y400968D01*
X59525Y400677D01*
X59567Y400385D01*
X59733Y400010D01*
X58650Y400135D01*
Y401260D01*
G01X52796Y390208D02*
X50296D01*
Y391249D01*
X50421Y391583D01*
X50588Y391791D01*
X50921Y391874D01*
X51254Y391791D01*
X51463Y391541D01*
X51588Y391249D01*
Y390208D01*
G01Y391249D02*
X52796Y391874D01*
G01X50713Y393349D02*
X50463Y393599D01*
X50338Y393891D01*
X50296Y394224D01*
X50379Y394641D01*
X50588Y394933D01*
X50838Y395016D01*
X51088Y394974D01*
X51296Y394808D01*
X51713Y393974D01*
X52004Y393599D01*
X52421Y393349D01*
X52796Y393266D01*
Y395016D01*
G01X52504Y396533D02*
X52713Y396824D01*
X52796Y397158D01*
X52713Y397491D01*
X52463Y397783D01*
X52088Y397991D01*
X51713Y398074D01*
X51254D01*
X50879Y397991D01*
X50546Y397783D01*
X50379Y397533D01*
X50296Y397241D01*
X50379Y396908D01*
X50546Y396658D01*
X50796Y396491D01*
X51129Y396408D01*
X51421Y396491D01*
X51713Y396699D01*
X51879Y396949D01*
X51921Y397241D01*
X51838Y397574D01*
X51629Y397824D01*
X51254Y398074D01*
G01X52796Y400841D02*
X50296D01*
X52088Y399299D01*
Y401383D01*
G01X52796Y403358D02*
X52254Y403441D01*
X51796Y403566D01*
X51379Y403733D01*
X50921Y403941D01*
X50296Y404274D01*
Y402608D01*
G01X41100Y392100D02*
Y396100D01*
X33700D01*
G01X56811Y408191D02*
Y410691D01*
X57811D01*
X58144Y410566D01*
X58394Y410274D01*
X58477Y409941D01*
X58394Y409608D01*
X58186Y409358D01*
X57811Y409233D01*
X56811D01*
G01X61661Y410483D02*
X61411Y410608D01*
X61119Y410691D01*
X60786D01*
X60411Y410566D01*
X60119Y410358D01*
X59911Y410108D01*
X59744Y409691D01*
X59702Y409316D01*
X59786Y408941D01*
X59911Y408691D01*
X60161Y408441D01*
X60452Y408274D01*
X60744Y408191D01*
X61036D01*
X61327Y408274D01*
X61577Y408399D01*
X61786Y408566D01*
G01X63844Y408191D02*
X64136Y408233D01*
X64469Y408358D01*
X64677Y408566D01*
X64761Y408858D01*
X64677Y409149D01*
X64427Y409399D01*
X64052Y409524D01*
X63636D01*
X63386Y409608D01*
X63177Y409816D01*
X63094Y410108D01*
X63219Y410399D01*
X63511Y410608D01*
X63844Y410691D01*
X64177Y410608D01*
X64469Y410399D01*
X64594Y410108D01*
X64511Y409816D01*
X64302Y409608D01*
X64052Y409524D01*
X63636D01*
X63261Y409399D01*
X63011Y409149D01*
X62927Y408858D01*
X63011Y408566D01*
X63219Y408358D01*
X63552Y408233D01*
X63844Y408191D01*
G01X67444D02*
Y410691D01*
X65902Y408899D01*
X67986D01*
G01X54775Y392169D02*
X54650Y391919D01*
X54567Y391627D01*
Y391294D01*
X54692Y390919D01*
X54900Y390627D01*
X55150Y390419D01*
X55567Y390252D01*
X55942Y390210D01*
X56317Y390294D01*
X56567Y390419D01*
X56817Y390669D01*
X56984Y390960D01*
X57067Y391252D01*
Y391544D01*
X56984Y391835D01*
X56859Y392085D01*
X56692Y392294D01*
G01X57067Y394852D02*
X54567D01*
X56359Y393310D01*
Y395394D01*
G01X56567Y396535D02*
X56859Y396785D01*
X57025Y397119D01*
X57067Y397494D01*
X57025Y397827D01*
X56817Y398160D01*
X56567Y398369D01*
X56317Y398410D01*
X56025Y398327D01*
X55817Y398035D01*
X55734Y397744D01*
Y397369D01*
G01Y397744D02*
X55609Y397994D01*
X55400Y398202D01*
X55150Y398285D01*
X54900Y398202D01*
X54692Y397994D01*
X54567Y397619D01*
X54609Y397244D01*
X54775Y396869D01*
G01X38384Y403993D02*
X38134Y404118D01*
X37842Y404201D01*
X37509D01*
X37134Y404076D01*
X36842Y403868D01*
X36634Y403618D01*
X36467Y403201D01*
X36425Y402826D01*
X36509Y402451D01*
X36634Y402201D01*
X36884Y401951D01*
X37175Y401784D01*
X37467Y401701D01*
X37759D01*
X38050Y401784D01*
X38300Y401909D01*
X38509Y402076D01*
G01X39775Y403784D02*
X40025Y404034D01*
X40317Y404159D01*
X40650Y404201D01*
X41067Y404118D01*
X41359Y403909D01*
X41442Y403659D01*
X41400Y403409D01*
X41234Y403201D01*
X40400Y402784D01*
X40025Y402493D01*
X39775Y402076D01*
X39692Y401701D01*
X41442D01*
G01X42750Y402201D02*
X43000Y401909D01*
X43334Y401743D01*
X43709Y401701D01*
X44042Y401743D01*
X44375Y401951D01*
X44584Y402201D01*
X44625Y402451D01*
X44542Y402743D01*
X44250Y402951D01*
X43959Y403034D01*
X43584D01*
G01X43959D02*
X44209Y403159D01*
X44417Y403368D01*
X44500Y403618D01*
X44417Y403868D01*
X44209Y404076D01*
X43834Y404201D01*
X43459Y404159D01*
X43084Y403993D01*
G01X45975Y403784D02*
X46225Y404034D01*
X46517Y404159D01*
X46850Y404201D01*
X47267Y404118D01*
X47559Y403909D01*
X47642Y403659D01*
X47600Y403409D01*
X47434Y403201D01*
X46600Y402784D01*
X46225Y402493D01*
X45975Y402076D01*
X45892Y401701D01*
X47642D01*
G01X38100Y419600D02*
Y416600D01*
X41100D01*
G01X54900D02*
X57900D01*
Y419600D01*
G01Y432400D02*
Y435400D01*
X54900D01*
G01X37000Y422100D02*
X39000D01*
G01X57000Y429900D02*
X60000D01*
G01X61328Y444544D02*
Y447044D01*
X62328D01*
X62661Y446919D01*
X62911Y446627D01*
X62994Y446294D01*
X62911Y445961D01*
X62703Y445711D01*
X62328Y445586D01*
X61328D01*
G01X66178Y446836D02*
X65928Y446961D01*
X65636Y447044D01*
X65303D01*
X64928Y446919D01*
X64636Y446711D01*
X64428Y446461D01*
X64261Y446044D01*
X64219Y445669D01*
X64303Y445294D01*
X64428Y445044D01*
X64678Y444794D01*
X64969Y444627D01*
X65261Y444544D01*
X65553D01*
X65844Y444627D01*
X66094Y444752D01*
X66303Y444919D01*
G01X68278Y444544D02*
X68361Y445086D01*
X68486Y445544D01*
X68653Y445961D01*
X68861Y446419D01*
X69194Y447044D01*
X67528D01*
G01X71378Y444544D02*
X71461Y445086D01*
X71586Y445544D01*
X71753Y445961D01*
X71961Y446419D01*
X72294Y447044D01*
X70628D01*
G01X35817Y443911D02*
Y446411D01*
X36817D01*
X37150Y446286D01*
X37400Y445994D01*
X37483Y445661D01*
X37400Y445328D01*
X37192Y445078D01*
X36817Y444953D01*
X35817D01*
G01X40667Y446203D02*
X40417Y446328D01*
X40125Y446411D01*
X39792D01*
X39417Y446286D01*
X39125Y446078D01*
X38917Y445828D01*
X38750Y445411D01*
X38708Y445036D01*
X38792Y444661D01*
X38917Y444411D01*
X39167Y444161D01*
X39458Y443994D01*
X39750Y443911D01*
X40042D01*
X40333Y443994D01*
X40583Y444119D01*
X40792Y444286D01*
G01X42850Y443911D02*
X43142Y443953D01*
X43475Y444078D01*
X43683Y444286D01*
X43767Y444578D01*
X43683Y444869D01*
X43433Y445119D01*
X43058Y445244D01*
X42642D01*
X42392Y445328D01*
X42183Y445536D01*
X42100Y445828D01*
X42225Y446119D01*
X42517Y446328D01*
X42850Y446411D01*
X43183Y446328D01*
X43475Y446119D01*
X43600Y445828D01*
X43517Y445536D01*
X43308Y445328D01*
X43058Y445244D01*
X42642D01*
X42267Y445119D01*
X42017Y444869D01*
X41933Y444578D01*
X42017Y444286D01*
X42225Y444078D01*
X42558Y443953D01*
X42850Y443911D01*
G01X45950D02*
Y446411D01*
X45450Y445911D01*
G01Y443911D02*
X46450D01*
G01X66500Y426200D02*
X62500D01*
Y418800D01*
G01X58051Y449824D02*
Y452324D01*
X59051D01*
X59384Y452199D01*
X59634Y451907D01*
X59717Y451574D01*
X59634Y451241D01*
X59426Y450991D01*
X59051Y450866D01*
X58051D01*
G01X62901Y452116D02*
X62651Y452241D01*
X62359Y452324D01*
X62026D01*
X61651Y452199D01*
X61359Y451991D01*
X61151Y451741D01*
X60984Y451324D01*
X60942Y450949D01*
X61026Y450574D01*
X61151Y450324D01*
X61401Y450074D01*
X61692Y449907D01*
X61984Y449824D01*
X62276D01*
X62567Y449907D01*
X62817Y450032D01*
X63026Y450199D01*
G01X65001Y449824D02*
X65084Y450366D01*
X65209Y450824D01*
X65376Y451241D01*
X65584Y451699D01*
X65917Y452324D01*
X64251D01*
G01X67476Y450116D02*
X67767Y449907D01*
X68101Y449824D01*
X68434Y449907D01*
X68726Y450157D01*
X68934Y450532D01*
X69017Y450907D01*
Y451366D01*
X68934Y451741D01*
X68726Y452074D01*
X68476Y452241D01*
X68184Y452324D01*
X67851Y452241D01*
X67601Y452074D01*
X67434Y451824D01*
X67351Y451491D01*
X67434Y451199D01*
X67642Y450907D01*
X67892Y450741D01*
X68184Y450699D01*
X68517Y450782D01*
X68767Y450991D01*
X69017Y451366D01*
G01X34800Y481700D02*
Y468300D01*
G01D02*
X46200D01*
G01D02*
Y481700D01*
G01X51200Y472300D02*
X55200D01*
Y479700D01*
G01X51000Y478700D02*
X47000D01*
Y471300D01*
G01X52561Y447110D02*
X50061D01*
Y448151D01*
X50186Y448485D01*
X50353Y448693D01*
X50686Y448776D01*
X51019Y448693D01*
X51228Y448443D01*
X51353Y448151D01*
Y447110D01*
G01Y448151D02*
X52561Y448776D01*
G01X51519Y450251D02*
X51228Y450543D01*
X51061Y450793D01*
X50978Y451126D01*
X51061Y451418D01*
X51228Y451626D01*
X51478Y451793D01*
X51769Y451835D01*
X52019Y451793D01*
X52269Y451626D01*
X52478Y451376D01*
X52561Y451085D01*
X52478Y450751D01*
X52228Y450460D01*
X51853Y450293D01*
X51436Y450251D01*
X50894Y450335D01*
X50603Y450460D01*
X50311Y450668D01*
X50103Y450960D01*
X50061Y451251D01*
X50144Y451543D01*
X50353Y451751D01*
G01X50061Y454143D02*
X50144Y453810D01*
X50353Y453560D01*
X50603Y453393D01*
X50936Y453268D01*
X51311Y453226D01*
X51686Y453268D01*
X52019Y453393D01*
X52269Y453560D01*
X52478Y453810D01*
X52561Y454143D01*
X52478Y454476D01*
X52269Y454726D01*
X52019Y454893D01*
X51686Y455018D01*
X51311Y455060D01*
X50936Y455018D01*
X50603Y454893D01*
X50353Y454726D01*
X50144Y454476D01*
X50061Y454143D01*
G01Y457243D02*
X50144Y456910D01*
X50353Y456660D01*
X50603Y456493D01*
X50936Y456368D01*
X51311Y456326D01*
X51686Y456368D01*
X52019Y456493D01*
X52269Y456660D01*
X52478Y456910D01*
X52561Y457243D01*
X52478Y457576D01*
X52269Y457826D01*
X52019Y457993D01*
X51686Y458118D01*
X51311Y458160D01*
X50936Y458118D01*
X50603Y457993D01*
X50353Y457826D01*
X50144Y457576D01*
X50061Y457243D01*
G01X55200Y472100D02*
X51200D01*
Y464700D01*
G01X34800Y468000D02*
Y464000D01*
X42200D01*
G01X54477Y456732D02*
Y459232D01*
X55518D01*
X55852Y459107D01*
X56060Y458940D01*
X56143Y458607D01*
X56060Y458274D01*
X55810Y458065D01*
X55518Y457940D01*
X54477D01*
G01X55518D02*
X56143Y456732D01*
G01X57618Y458815D02*
X57868Y459065D01*
X58160Y459190D01*
X58493Y459232D01*
X58910Y459149D01*
X59202Y458940D01*
X59285Y458690D01*
X59243Y458440D01*
X59077Y458232D01*
X58243Y457815D01*
X57868Y457524D01*
X57618Y457107D01*
X57535Y456732D01*
X59285D01*
G01X60593Y457232D02*
X60843Y456940D01*
X61177Y456774D01*
X61552Y456732D01*
X61885Y456774D01*
X62218Y456982D01*
X62427Y457232D01*
X62468Y457482D01*
X62385Y457774D01*
X62093Y457982D01*
X61802Y458065D01*
X61427D01*
G01X61802D02*
X62052Y458190D01*
X62260Y458399D01*
X62343Y458649D01*
X62260Y458899D01*
X62052Y459107D01*
X61677Y459232D01*
X61302Y459190D01*
X60927Y459024D01*
G01X63902Y457024D02*
X64193Y456815D01*
X64527Y456732D01*
X64860Y456815D01*
X65152Y457065D01*
X65360Y457440D01*
X65443Y457815D01*
Y458274D01*
X65360Y458649D01*
X65152Y458982D01*
X64902Y459149D01*
X64610Y459232D01*
X64277Y459149D01*
X64027Y458982D01*
X63860Y458732D01*
X63777Y458399D01*
X63860Y458107D01*
X64068Y457815D01*
X64318Y457649D01*
X64610Y457607D01*
X64943Y457690D01*
X65193Y457899D01*
X65443Y458274D01*
G01X55400Y472100D02*
Y468100D01*
X62800D01*
G01X54477Y460832D02*
Y463332D01*
X55518D01*
X55852Y463207D01*
X56060Y463040D01*
X56143Y462707D01*
X56060Y462374D01*
X55810Y462165D01*
X55518Y462040D01*
X54477D01*
G01X55518D02*
X56143Y460832D01*
G01X57618Y462915D02*
X57868Y463165D01*
X58160Y463290D01*
X58493Y463332D01*
X58910Y463249D01*
X59202Y463040D01*
X59285Y462790D01*
X59243Y462540D01*
X59077Y462332D01*
X58243Y461915D01*
X57868Y461624D01*
X57618Y461207D01*
X57535Y460832D01*
X59285D01*
G01X60593Y461332D02*
X60843Y461040D01*
X61177Y460874D01*
X61552Y460832D01*
X61885Y460874D01*
X62218Y461082D01*
X62427Y461332D01*
X62468Y461582D01*
X62385Y461874D01*
X62093Y462082D01*
X61802Y462165D01*
X61427D01*
G01X61802D02*
X62052Y462290D01*
X62260Y462499D01*
X62343Y462749D01*
X62260Y462999D01*
X62052Y463207D01*
X61677Y463332D01*
X61302Y463290D01*
X60927Y463124D01*
G01X64610Y460832D02*
X64902Y460874D01*
X65235Y460999D01*
X65443Y461207D01*
X65527Y461499D01*
X65443Y461790D01*
X65193Y462040D01*
X64818Y462165D01*
X64402D01*
X64152Y462249D01*
X63943Y462457D01*
X63860Y462749D01*
X63985Y463040D01*
X64277Y463249D01*
X64610Y463332D01*
X64943Y463249D01*
X65235Y463040D01*
X65360Y462749D01*
X65277Y462457D01*
X65068Y462249D01*
X64818Y462165D01*
X64402D01*
X64027Y462040D01*
X63777Y461790D01*
X63693Y461499D01*
X63777Y461207D01*
X63985Y460999D01*
X64318Y460874D01*
X64610Y460832D01*
G01X55400Y476200D02*
Y472200D01*
X62800D01*
G01X48700Y449817D02*
X46200D01*
Y450817D01*
X46325Y451150D01*
X46617Y451400D01*
X46950Y451483D01*
X47283Y451400D01*
X47533Y451192D01*
X47658Y450817D01*
Y449817D01*
G01X47450Y454000D02*
Y454833D01*
X48200D01*
X48450Y454583D01*
X48617Y454292D01*
X48700Y453875D01*
X48617Y453458D01*
X48450Y453167D01*
X48200Y452917D01*
X47908Y452750D01*
X47575Y452667D01*
X47283D01*
X47033Y452750D01*
X46742Y452917D01*
X46492Y453167D01*
X46325Y453417D01*
X46200Y453750D01*
Y454042D01*
X46283Y454375D01*
X46450Y454625D01*
G01X47658Y456058D02*
X47367Y456350D01*
X47200Y456600D01*
X47117Y456933D01*
X47200Y457225D01*
X47367Y457433D01*
X47617Y457600D01*
X47908Y457642D01*
X48158Y457600D01*
X48408Y457433D01*
X48617Y457183D01*
X48700Y456892D01*
X48617Y456558D01*
X48367Y456267D01*
X47992Y456100D01*
X47575Y456058D01*
X47033Y456142D01*
X46742Y456267D01*
X46450Y456475D01*
X46242Y456767D01*
X46200Y457058D01*
X46283Y457350D01*
X46492Y457558D01*
G01X48408Y459242D02*
X48617Y459533D01*
X48700Y459867D01*
X48617Y460200D01*
X48367Y460492D01*
X47992Y460700D01*
X47617Y460783D01*
X47158D01*
X46783Y460700D01*
X46450Y460492D01*
X46283Y460242D01*
X46200Y459950D01*
X46283Y459617D01*
X46450Y459367D01*
X46700Y459200D01*
X47033Y459117D01*
X47325Y459200D01*
X47617Y459408D01*
X47783Y459658D01*
X47825Y459950D01*
X47742Y460283D01*
X47533Y460533D01*
X47158Y460783D01*
G01X44700Y449517D02*
X42200D01*
Y450517D01*
X42325Y450850D01*
X42617Y451100D01*
X42950Y451183D01*
X43283Y451100D01*
X43533Y450892D01*
X43658Y450517D01*
Y449517D01*
G01X43450Y453700D02*
Y454533D01*
X44200D01*
X44450Y454283D01*
X44617Y453992D01*
X44700Y453575D01*
X44617Y453158D01*
X44450Y452867D01*
X44200Y452617D01*
X43908Y452450D01*
X43575Y452367D01*
X43283D01*
X43033Y452450D01*
X42742Y452617D01*
X42492Y452867D01*
X42325Y453117D01*
X42200Y453450D01*
Y453742D01*
X42283Y454075D01*
X42450Y454325D01*
G01X44700Y456550D02*
X42200D01*
X42700Y456050D01*
G01X44700D02*
Y457050D01*
G01X42617Y458858D02*
X42367Y459108D01*
X42242Y459400D01*
X42200Y459733D01*
X42283Y460150D01*
X42492Y460442D01*
X42742Y460525D01*
X42992Y460483D01*
X43200Y460317D01*
X43617Y459483D01*
X43908Y459108D01*
X44325Y458858D01*
X44700Y458775D01*
Y460525D01*
G01X46200Y481700D02*
X34800D01*
G01X61200Y485800D02*
Y499200D01*
G01D02*
X49800D01*
G01D02*
Y485800D01*
G01D02*
X61200D01*
G01X32088Y512216D02*
Y514716D01*
X33129D01*
X33463Y514591D01*
X33671Y514424D01*
X33754Y514091D01*
X33671Y513758D01*
X33421Y513549D01*
X33129Y513424D01*
X32088D01*
G01X33129D02*
X33754Y512216D01*
G01X35229Y514299D02*
X35479Y514549D01*
X35771Y514674D01*
X36104Y514716D01*
X36521Y514633D01*
X36813Y514424D01*
X36896Y514174D01*
X36854Y513924D01*
X36688Y513716D01*
X35854Y513299D01*
X35479Y513008D01*
X35229Y512591D01*
X35146Y512216D01*
X36896D01*
G01X38204Y512716D02*
X38454Y512424D01*
X38788Y512258D01*
X39163Y512216D01*
X39496Y512258D01*
X39829Y512466D01*
X40038Y512716D01*
X40079Y512966D01*
X39996Y513258D01*
X39704Y513466D01*
X39413Y513549D01*
X39038D01*
G01X39413D02*
X39663Y513674D01*
X39871Y513883D01*
X39954Y514133D01*
X39871Y514383D01*
X39663Y514591D01*
X39288Y514716D01*
X38913Y514674D01*
X38538Y514508D01*
G01X42221Y514716D02*
X41888Y514633D01*
X41638Y514424D01*
X41471Y514174D01*
X41346Y513841D01*
X41304Y513466D01*
X41346Y513091D01*
X41471Y512758D01*
X41638Y512508D01*
X41888Y512299D01*
X42221Y512216D01*
X42554Y512299D01*
X42804Y512508D01*
X42971Y512758D01*
X43096Y513091D01*
X43138Y513466D01*
X43096Y513841D01*
X42971Y514174D01*
X42804Y514424D01*
X42554Y514633D01*
X42221Y514716D01*
G01X33500Y493367D02*
X31000D01*
Y494408D01*
X31125Y494742D01*
X31292Y494950D01*
X31625Y495033D01*
X31958Y494950D01*
X32167Y494700D01*
X32292Y494408D01*
Y493367D01*
G01Y494408D02*
X33500Y495033D01*
G01Y497300D02*
X31000D01*
X31500Y496800D01*
G01X33500D02*
Y497800D01*
G01Y500317D02*
X32958Y500400D01*
X32500Y500525D01*
X32083Y500692D01*
X31625Y500900D01*
X31000Y501233D01*
Y499567D01*
G01X62000Y488800D02*
X66000D01*
Y496200D01*
G01X34988Y505487D02*
Y507987D01*
X36029D01*
X36363Y507862D01*
X36571Y507695D01*
X36654Y507362D01*
X36571Y507029D01*
X36321Y506820D01*
X36029Y506695D01*
X34988D01*
G01X36029D02*
X36654Y505487D01*
G01X38004Y505987D02*
X38254Y505695D01*
X38588Y505529D01*
X38963Y505487D01*
X39296Y505529D01*
X39629Y505737D01*
X39838Y505987D01*
X39879Y506237D01*
X39796Y506529D01*
X39504Y506737D01*
X39213Y506820D01*
X38838D01*
G01X39213D02*
X39463Y506945D01*
X39671Y507154D01*
X39754Y507404D01*
X39671Y507654D01*
X39463Y507862D01*
X39088Y507987D01*
X38713Y507945D01*
X38338Y507779D01*
G01X41229Y506529D02*
X41521Y506820D01*
X41771Y506987D01*
X42104Y507070D01*
X42396Y506987D01*
X42604Y506820D01*
X42771Y506570D01*
X42813Y506279D01*
X42771Y506029D01*
X42604Y505779D01*
X42354Y505570D01*
X42063Y505487D01*
X41729Y505570D01*
X41438Y505820D01*
X41271Y506195D01*
X41229Y506612D01*
X41313Y507154D01*
X41438Y507445D01*
X41646Y507737D01*
X41938Y507945D01*
X42229Y507987D01*
X42521Y507904D01*
X42729Y507695D01*
G01X44204Y505862D02*
X44454Y505654D01*
X44746Y505529D01*
X45121Y505487D01*
X45496Y505570D01*
X45788Y505737D01*
X45996Y506029D01*
X46038Y506362D01*
X45954Y506695D01*
X45746Y506904D01*
X45454Y507070D01*
X45163Y507112D01*
X44871Y507070D01*
X44496Y506904D01*
X44621Y507987D01*
X45746D01*
G01X51800Y503917D02*
X49300D01*
Y504958D01*
X49425Y505292D01*
X49592Y505500D01*
X49925Y505583D01*
X50258Y505500D01*
X50467Y505250D01*
X50592Y504958D01*
Y503917D01*
G01Y504958D02*
X51800Y505583D01*
G01Y507850D02*
X49300D01*
X49800Y507350D01*
G01X51800D02*
Y508350D01*
G01X50758Y510158D02*
X50467Y510450D01*
X50300Y510700D01*
X50217Y511033D01*
X50300Y511325D01*
X50467Y511533D01*
X50717Y511700D01*
X51008Y511742D01*
X51258Y511700D01*
X51508Y511533D01*
X51717Y511283D01*
X51800Y510992D01*
X51717Y510658D01*
X51467Y510367D01*
X51092Y510200D01*
X50675Y510158D01*
X50133Y510242D01*
X49842Y510367D01*
X49550Y510575D01*
X49342Y510867D01*
X49300Y511158D01*
X49383Y511450D01*
X49592Y511658D01*
G01X51300Y513133D02*
X51592Y513383D01*
X51758Y513717D01*
X51800Y514092D01*
X51758Y514425D01*
X51550Y514758D01*
X51300Y514967D01*
X51050Y515008D01*
X50758Y514925D01*
X50550Y514633D01*
X50467Y514342D01*
Y513967D01*
G01Y514342D02*
X50342Y514592D01*
X50133Y514800D01*
X49883Y514883D01*
X49633Y514800D01*
X49425Y514592D01*
X49300Y514217D01*
X49342Y513842D01*
X49508Y513467D01*
G01X57261Y512841D02*
X53261D01*
Y505441D01*
G01X44900Y488500D02*
X48900D01*
Y495900D01*
G01X57017Y506400D02*
Y508900D01*
X58058D01*
X58392Y508775D01*
X58600Y508608D01*
X58683Y508275D01*
X58600Y507942D01*
X58350Y507733D01*
X58058Y507608D01*
X57017D01*
G01X58058D02*
X58683Y506400D01*
G01X61450D02*
Y508900D01*
X59908Y507108D01*
X61992D01*
G01X64050Y508900D02*
X63717Y508817D01*
X63467Y508608D01*
X63300Y508358D01*
X63175Y508025D01*
X63133Y507650D01*
X63175Y507275D01*
X63300Y506942D01*
X63467Y506692D01*
X63717Y506483D01*
X64050Y506400D01*
X64383Y506483D01*
X64633Y506692D01*
X64800Y506942D01*
X64925Y507275D01*
X64967Y507650D01*
X64925Y508025D01*
X64800Y508358D01*
X64633Y508608D01*
X64383Y508817D01*
X64050Y508900D01*
G01X67067Y506400D02*
X67150Y506942D01*
X67275Y507400D01*
X67442Y507817D01*
X67650Y508275D01*
X67983Y508900D01*
X66317D01*
G01X61569Y504220D02*
Y500220D01*
X68969D01*
G01X35300Y486500D02*
Y482500D01*
X42700D01*
G01X61200Y481000D02*
Y485000D01*
X53800D01*
G01X37317Y500900D02*
Y503400D01*
X38358D01*
X38692Y503275D01*
X38900Y503108D01*
X38983Y502775D01*
X38900Y502442D01*
X38650Y502233D01*
X38358Y502108D01*
X37317D01*
G01X38358D02*
X38983Y500900D01*
G01X40458Y502983D02*
X40708Y503233D01*
X41000Y503358D01*
X41333Y503400D01*
X41750Y503317D01*
X42042Y503108D01*
X42125Y502858D01*
X42083Y502608D01*
X41917Y502400D01*
X41083Y501983D01*
X40708Y501692D01*
X40458Y501275D01*
X40375Y500900D01*
X42125D01*
G01X43642Y501192D02*
X43933Y500983D01*
X44267Y500900D01*
X44600Y500983D01*
X44892Y501233D01*
X45100Y501608D01*
X45183Y501983D01*
Y502442D01*
X45100Y502817D01*
X44892Y503150D01*
X44642Y503317D01*
X44350Y503400D01*
X44017Y503317D01*
X43767Y503150D01*
X43600Y502900D01*
X43517Y502567D01*
X43600Y502275D01*
X43808Y501983D01*
X44058Y501817D01*
X44350Y501775D01*
X44683Y501858D01*
X44933Y502067D01*
X45183Y502442D01*
G01X46658Y501942D02*
X46950Y502233D01*
X47200Y502400D01*
X47533Y502483D01*
X47825Y502400D01*
X48033Y502233D01*
X48200Y501983D01*
X48242Y501692D01*
X48200Y501442D01*
X48033Y501192D01*
X47783Y500983D01*
X47492Y500900D01*
X47158Y500983D01*
X46867Y501233D01*
X46700Y501608D01*
X46658Y502025D01*
X46742Y502567D01*
X46867Y502858D01*
X47075Y503150D01*
X47367Y503358D01*
X47658Y503400D01*
X47950Y503317D01*
X48158Y503108D01*
G01X61200Y500000D02*
Y504000D01*
X53800D01*
G01X52117Y541076D02*
Y543576D01*
X53158D01*
X53492Y543451D01*
X53700Y543284D01*
X53783Y542951D01*
X53700Y542618D01*
X53450Y542409D01*
X53158Y542284D01*
X52117D01*
G01X53158D02*
X53783Y541076D01*
G01X55133Y541576D02*
X55383Y541284D01*
X55717Y541118D01*
X56092Y541076D01*
X56425Y541118D01*
X56758Y541326D01*
X56967Y541576D01*
X57008Y541826D01*
X56925Y542118D01*
X56633Y542326D01*
X56342Y542409D01*
X55967D01*
G01X56342D02*
X56592Y542534D01*
X56800Y542743D01*
X56883Y542993D01*
X56800Y543243D01*
X56592Y543451D01*
X56217Y543576D01*
X55842Y543534D01*
X55467Y543368D01*
G01X59650Y541076D02*
Y543576D01*
X58108Y541784D01*
X60192D01*
G01X61333Y541576D02*
X61583Y541284D01*
X61917Y541118D01*
X62292Y541076D01*
X62625Y541118D01*
X62958Y541326D01*
X63167Y541576D01*
X63208Y541826D01*
X63125Y542118D01*
X62833Y542326D01*
X62542Y542409D01*
X62167D01*
G01X62542D02*
X62792Y542534D01*
X63000Y542743D01*
X63083Y542993D01*
X63000Y543243D01*
X62792Y543451D01*
X62417Y543576D01*
X62042Y543534D01*
X61667Y543368D01*
G01X52117Y537576D02*
Y540076D01*
X53158D01*
X53492Y539951D01*
X53700Y539784D01*
X53783Y539451D01*
X53700Y539118D01*
X53450Y538909D01*
X53158Y538784D01*
X52117D01*
G01X53158D02*
X53783Y537576D01*
G01X55133Y538076D02*
X55383Y537784D01*
X55717Y537618D01*
X56092Y537576D01*
X56425Y537618D01*
X56758Y537826D01*
X56967Y538076D01*
X57008Y538326D01*
X56925Y538618D01*
X56633Y538826D01*
X56342Y538909D01*
X55967D01*
G01X56342D02*
X56592Y539034D01*
X56800Y539243D01*
X56883Y539493D01*
X56800Y539743D01*
X56592Y539951D01*
X56217Y540076D01*
X55842Y540034D01*
X55467Y539868D01*
G01X59650Y537576D02*
Y540076D01*
X58108Y538284D01*
X60192D01*
G01X62167Y537576D02*
X62250Y538118D01*
X62375Y538576D01*
X62542Y538993D01*
X62750Y539451D01*
X63083Y540076D01*
X61417D01*
G01X32088Y520216D02*
Y522716D01*
X33129D01*
X33463Y522591D01*
X33671Y522424D01*
X33754Y522091D01*
X33671Y521758D01*
X33421Y521549D01*
X33129Y521424D01*
X32088D01*
G01X33129D02*
X33754Y520216D01*
G01X35104Y520716D02*
X35354Y520424D01*
X35688Y520258D01*
X36063Y520216D01*
X36396Y520258D01*
X36729Y520466D01*
X36938Y520716D01*
X36979Y520966D01*
X36896Y521258D01*
X36604Y521466D01*
X36313Y521549D01*
X35938D01*
G01X36313D02*
X36563Y521674D01*
X36771Y521883D01*
X36854Y522133D01*
X36771Y522383D01*
X36563Y522591D01*
X36188Y522716D01*
X35813Y522674D01*
X35438Y522508D01*
G01X38204Y520591D02*
X38454Y520383D01*
X38746Y520258D01*
X39121Y520216D01*
X39496Y520299D01*
X39788Y520466D01*
X39996Y520758D01*
X40038Y521091D01*
X39954Y521424D01*
X39746Y521633D01*
X39454Y521799D01*
X39163Y521841D01*
X38871Y521799D01*
X38496Y521633D01*
X38621Y522716D01*
X39746D01*
G01X41304Y520716D02*
X41554Y520424D01*
X41888Y520258D01*
X42263Y520216D01*
X42596Y520258D01*
X42929Y520466D01*
X43138Y520716D01*
X43179Y520966D01*
X43096Y521258D01*
X42804Y521466D01*
X42513Y521549D01*
X42138D01*
G01X42513D02*
X42763Y521674D01*
X42971Y521883D01*
X43054Y522133D01*
X42971Y522383D01*
X42763Y522591D01*
X42388Y522716D01*
X42013Y522674D01*
X41638Y522508D01*
G01X52117Y544576D02*
Y547076D01*
X53158D01*
X53492Y546951D01*
X53700Y546784D01*
X53783Y546451D01*
X53700Y546118D01*
X53450Y545909D01*
X53158Y545784D01*
X52117D01*
G01X53158D02*
X53783Y544576D01*
G01X55133Y545076D02*
X55383Y544784D01*
X55717Y544618D01*
X56092Y544576D01*
X56425Y544618D01*
X56758Y544826D01*
X56967Y545076D01*
X57008Y545326D01*
X56925Y545618D01*
X56633Y545826D01*
X56342Y545909D01*
X55967D01*
G01X56342D02*
X56592Y546034D01*
X56800Y546243D01*
X56883Y546493D01*
X56800Y546743D01*
X56592Y546951D01*
X56217Y547076D01*
X55842Y547034D01*
X55467Y546868D01*
G01X58233Y544951D02*
X58483Y544743D01*
X58775Y544618D01*
X59150Y544576D01*
X59525Y544659D01*
X59817Y544826D01*
X60025Y545118D01*
X60067Y545451D01*
X59983Y545784D01*
X59775Y545993D01*
X59483Y546159D01*
X59192Y546201D01*
X58900Y546159D01*
X58525Y545993D01*
X58650Y547076D01*
X59775D01*
G01X62750Y544576D02*
Y547076D01*
X61208Y545284D01*
X63292D01*
G01X47817Y528567D02*
Y531067D01*
X48858D01*
X49192Y530942D01*
X49400Y530775D01*
X49483Y530442D01*
X49400Y530109D01*
X49150Y529900D01*
X48858Y529775D01*
X47817D01*
G01X48858D02*
X49483Y528567D01*
G01X50833Y529067D02*
X51083Y528775D01*
X51417Y528609D01*
X51792Y528567D01*
X52125Y528609D01*
X52458Y528817D01*
X52667Y529067D01*
X52708Y529317D01*
X52625Y529609D01*
X52333Y529817D01*
X52042Y529900D01*
X51667D01*
G01X52042D02*
X52292Y530025D01*
X52500Y530234D01*
X52583Y530484D01*
X52500Y530734D01*
X52292Y530942D01*
X51917Y531067D01*
X51542Y531025D01*
X51167Y530859D01*
G01X53933Y528942D02*
X54183Y528734D01*
X54475Y528609D01*
X54850Y528567D01*
X55225Y528650D01*
X55517Y528817D01*
X55725Y529109D01*
X55767Y529442D01*
X55683Y529775D01*
X55475Y529984D01*
X55183Y530150D01*
X54892Y530192D01*
X54600Y530150D01*
X54225Y529984D01*
X54350Y531067D01*
X55475D01*
G01X57867Y528567D02*
X57950Y529109D01*
X58075Y529567D01*
X58242Y529984D01*
X58450Y530442D01*
X58783Y531067D01*
X57117D01*
G01X52117Y534076D02*
Y536576D01*
X53158D01*
X53492Y536451D01*
X53700Y536284D01*
X53783Y535951D01*
X53700Y535618D01*
X53450Y535409D01*
X53158Y535284D01*
X52117D01*
G01X53158D02*
X53783Y534076D01*
G01X55133Y534576D02*
X55383Y534284D01*
X55717Y534118D01*
X56092Y534076D01*
X56425Y534118D01*
X56758Y534326D01*
X56967Y534576D01*
X57008Y534826D01*
X56925Y535118D01*
X56633Y535326D01*
X56342Y535409D01*
X55967D01*
G01X56342D02*
X56592Y535534D01*
X56800Y535743D01*
X56883Y535993D01*
X56800Y536243D01*
X56592Y536451D01*
X56217Y536576D01*
X55842Y536534D01*
X55467Y536368D01*
G01X58358Y535118D02*
X58650Y535409D01*
X58900Y535576D01*
X59233Y535659D01*
X59525Y535576D01*
X59733Y535409D01*
X59900Y535159D01*
X59942Y534868D01*
X59900Y534618D01*
X59733Y534368D01*
X59483Y534159D01*
X59192Y534076D01*
X58858Y534159D01*
X58567Y534409D01*
X58400Y534784D01*
X58358Y535201D01*
X58442Y535743D01*
X58567Y536034D01*
X58775Y536326D01*
X59067Y536534D01*
X59358Y536576D01*
X59650Y536493D01*
X59858Y536284D01*
G01X61333Y534576D02*
X61583Y534284D01*
X61917Y534118D01*
X62292Y534076D01*
X62625Y534118D01*
X62958Y534326D01*
X63167Y534576D01*
X63208Y534826D01*
X63125Y535118D01*
X62833Y535326D01*
X62542Y535409D01*
X62167D01*
G01X62542D02*
X62792Y535534D01*
X63000Y535743D01*
X63083Y535993D01*
X63000Y536243D01*
X62792Y536451D01*
X62417Y536576D01*
X62042Y536534D01*
X61667Y536368D01*
G01X37807Y545096D02*
Y547596D01*
X38848D01*
X39182Y547471D01*
X39390Y547304D01*
X39473Y546971D01*
X39390Y546638D01*
X39140Y546429D01*
X38848Y546304D01*
X37807D01*
G01X38848D02*
X39473Y545096D01*
G01X40823Y545596D02*
X41073Y545304D01*
X41407Y545138D01*
X41782Y545096D01*
X42115Y545138D01*
X42448Y545346D01*
X42657Y545596D01*
X42698Y545846D01*
X42615Y546138D01*
X42323Y546346D01*
X42032Y546429D01*
X41657D01*
G01X42032D02*
X42282Y546554D01*
X42490Y546763D01*
X42573Y547013D01*
X42490Y547263D01*
X42282Y547471D01*
X41907Y547596D01*
X41532Y547554D01*
X41157Y547388D01*
G01X44048Y546138D02*
X44340Y546429D01*
X44590Y546596D01*
X44923Y546679D01*
X45215Y546596D01*
X45423Y546429D01*
X45590Y546179D01*
X45632Y545888D01*
X45590Y545638D01*
X45423Y545388D01*
X45173Y545179D01*
X44882Y545096D01*
X44548Y545179D01*
X44257Y545429D01*
X44090Y545804D01*
X44048Y546221D01*
X44132Y546763D01*
X44257Y547054D01*
X44465Y547346D01*
X44757Y547554D01*
X45048Y547596D01*
X45340Y547513D01*
X45548Y547304D01*
G01X47857Y545096D02*
X47940Y545638D01*
X48065Y546096D01*
X48232Y546513D01*
X48440Y546971D01*
X48773Y547596D01*
X47107D01*
G01X47886Y525090D02*
Y527590D01*
X48927D01*
X49261Y527465D01*
X49469Y527298D01*
X49552Y526965D01*
X49469Y526632D01*
X49219Y526423D01*
X48927Y526298D01*
X47886D01*
G01X48927D02*
X49552Y525090D01*
G01X50902Y525590D02*
X51152Y525298D01*
X51486Y525132D01*
X51861Y525090D01*
X52194Y525132D01*
X52527Y525340D01*
X52736Y525590D01*
X52777Y525840D01*
X52694Y526132D01*
X52402Y526340D01*
X52111Y526423D01*
X51736D01*
G01X52111D02*
X52361Y526548D01*
X52569Y526757D01*
X52652Y527007D01*
X52569Y527257D01*
X52361Y527465D01*
X51986Y527590D01*
X51611Y527548D01*
X51236Y527382D01*
G01X55419Y525090D02*
Y527590D01*
X53877Y525798D01*
X55961D01*
G01X58019Y525090D02*
X58311Y525132D01*
X58644Y525257D01*
X58852Y525465D01*
X58936Y525757D01*
X58852Y526048D01*
X58602Y526298D01*
X58227Y526423D01*
X57811D01*
X57561Y526507D01*
X57352Y526715D01*
X57269Y527007D01*
X57394Y527298D01*
X57686Y527507D01*
X58019Y527590D01*
X58352Y527507D01*
X58644Y527298D01*
X58769Y527007D01*
X58686Y526715D01*
X58477Y526507D01*
X58227Y526423D01*
X57811D01*
X57436Y526298D01*
X57186Y526048D01*
X57102Y525757D01*
X57186Y525465D01*
X57394Y525257D01*
X57727Y525132D01*
X58019Y525090D01*
G01X47661Y521331D02*
Y523831D01*
X48702D01*
X49036Y523706D01*
X49244Y523539D01*
X49327Y523206D01*
X49244Y522873D01*
X48994Y522664D01*
X48702Y522539D01*
X47661D01*
G01X48702D02*
X49327Y521331D01*
G01X50677Y521831D02*
X50927Y521539D01*
X51261Y521373D01*
X51636Y521331D01*
X51969Y521373D01*
X52302Y521581D01*
X52511Y521831D01*
X52552Y522081D01*
X52469Y522373D01*
X52177Y522581D01*
X51886Y522664D01*
X51511D01*
G01X51886D02*
X52136Y522789D01*
X52344Y522998D01*
X52427Y523248D01*
X52344Y523498D01*
X52136Y523706D01*
X51761Y523831D01*
X51386Y523789D01*
X51011Y523623D01*
G01X53777Y521706D02*
X54027Y521498D01*
X54319Y521373D01*
X54694Y521331D01*
X55069Y521414D01*
X55361Y521581D01*
X55569Y521873D01*
X55611Y522206D01*
X55527Y522539D01*
X55319Y522748D01*
X55027Y522914D01*
X54736Y522956D01*
X54444Y522914D01*
X54069Y522748D01*
X54194Y523831D01*
X55319D01*
G01X57002Y523414D02*
X57252Y523664D01*
X57544Y523789D01*
X57877Y523831D01*
X58294Y523748D01*
X58586Y523539D01*
X58669Y523289D01*
X58627Y523039D01*
X58461Y522831D01*
X57627Y522414D01*
X57252Y522123D01*
X57002Y521706D01*
X56919Y521331D01*
X58669D01*
G01X47661Y517331D02*
Y519831D01*
X48702D01*
X49036Y519706D01*
X49244Y519539D01*
X49327Y519206D01*
X49244Y518873D01*
X48994Y518664D01*
X48702Y518539D01*
X47661D01*
G01X48702D02*
X49327Y517331D01*
G01X50677Y517831D02*
X50927Y517539D01*
X51261Y517373D01*
X51636Y517331D01*
X51969Y517373D01*
X52302Y517581D01*
X52511Y517831D01*
X52552Y518081D01*
X52469Y518373D01*
X52177Y518581D01*
X51886Y518664D01*
X51511D01*
G01X51886D02*
X52136Y518789D01*
X52344Y518998D01*
X52427Y519248D01*
X52344Y519498D01*
X52136Y519706D01*
X51761Y519831D01*
X51386Y519789D01*
X51011Y519623D01*
G01X53902Y518373D02*
X54194Y518664D01*
X54444Y518831D01*
X54777Y518914D01*
X55069Y518831D01*
X55277Y518664D01*
X55444Y518414D01*
X55486Y518123D01*
X55444Y517873D01*
X55277Y517623D01*
X55027Y517414D01*
X54736Y517331D01*
X54402Y517414D01*
X54111Y517664D01*
X53944Y518039D01*
X53902Y518456D01*
X53986Y518998D01*
X54111Y519289D01*
X54319Y519581D01*
X54611Y519789D01*
X54902Y519831D01*
X55194Y519748D01*
X55402Y519539D01*
G01X57794Y517331D02*
X58086Y517373D01*
X58419Y517498D01*
X58627Y517706D01*
X58711Y517998D01*
X58627Y518289D01*
X58377Y518539D01*
X58002Y518664D01*
X57586D01*
X57336Y518748D01*
X57127Y518956D01*
X57044Y519248D01*
X57169Y519539D01*
X57461Y519748D01*
X57794Y519831D01*
X58127Y519748D01*
X58419Y519539D01*
X58544Y519248D01*
X58461Y518956D01*
X58252Y518748D01*
X58002Y518664D01*
X57586D01*
X57211Y518539D01*
X56961Y518289D01*
X56877Y517998D01*
X56961Y517706D01*
X57169Y517498D01*
X57502Y517373D01*
X57794Y517331D01*
G01X32088Y516216D02*
Y518716D01*
X33129D01*
X33463Y518591D01*
X33671Y518424D01*
X33754Y518091D01*
X33671Y517758D01*
X33421Y517549D01*
X33129Y517424D01*
X32088D01*
G01X33129D02*
X33754Y516216D01*
G01X35104Y516716D02*
X35354Y516424D01*
X35688Y516258D01*
X36063Y516216D01*
X36396Y516258D01*
X36729Y516466D01*
X36938Y516716D01*
X36979Y516966D01*
X36896Y517258D01*
X36604Y517466D01*
X36313Y517549D01*
X35938D01*
G01X36313D02*
X36563Y517674D01*
X36771Y517883D01*
X36854Y518133D01*
X36771Y518383D01*
X36563Y518591D01*
X36188Y518716D01*
X35813Y518674D01*
X35438Y518508D01*
G01X38329Y517258D02*
X38621Y517549D01*
X38871Y517716D01*
X39204Y517799D01*
X39496Y517716D01*
X39704Y517549D01*
X39871Y517299D01*
X39913Y517008D01*
X39871Y516758D01*
X39704Y516508D01*
X39454Y516299D01*
X39163Y516216D01*
X38829Y516299D01*
X38538Y516549D01*
X38371Y516924D01*
X38329Y517341D01*
X38413Y517883D01*
X38538Y518174D01*
X38746Y518466D01*
X39038Y518674D01*
X39329Y518716D01*
X39621Y518633D01*
X39829Y518424D01*
G01X41513Y516508D02*
X41804Y516299D01*
X42138Y516216D01*
X42471Y516299D01*
X42763Y516549D01*
X42971Y516924D01*
X43054Y517299D01*
Y517758D01*
X42971Y518133D01*
X42763Y518466D01*
X42513Y518633D01*
X42221Y518716D01*
X41888Y518633D01*
X41638Y518466D01*
X41471Y518216D01*
X41388Y517883D01*
X41471Y517591D01*
X41679Y517299D01*
X41929Y517133D01*
X42221Y517091D01*
X42554Y517174D01*
X42804Y517383D01*
X43054Y517758D01*
G01X37100Y530562D02*
Y523562D01*
G01X57300Y569000D02*
Y576000D01*
X70700D01*
Y569000D01*
X57300D01*
G01Y561000D02*
Y568000D01*
X70700D01*
Y561000D01*
X57300D01*
G01X52117Y548076D02*
Y550576D01*
X53158D01*
X53492Y550451D01*
X53700Y550284D01*
X53783Y549951D01*
X53700Y549618D01*
X53450Y549409D01*
X53158Y549284D01*
X52117D01*
G01X53158D02*
X53783Y548076D01*
G01X55133Y548576D02*
X55383Y548284D01*
X55717Y548118D01*
X56092Y548076D01*
X56425Y548118D01*
X56758Y548326D01*
X56967Y548576D01*
X57008Y548826D01*
X56925Y549118D01*
X56633Y549326D01*
X56342Y549409D01*
X55967D01*
G01X56342D02*
X56592Y549534D01*
X56800Y549743D01*
X56883Y549993D01*
X56800Y550243D01*
X56592Y550451D01*
X56217Y550576D01*
X55842Y550534D01*
X55467Y550368D01*
G01X58233Y548451D02*
X58483Y548243D01*
X58775Y548118D01*
X59150Y548076D01*
X59525Y548159D01*
X59817Y548326D01*
X60025Y548618D01*
X60067Y548951D01*
X59983Y549284D01*
X59775Y549493D01*
X59483Y549659D01*
X59192Y549701D01*
X58900Y549659D01*
X58525Y549493D01*
X58650Y550576D01*
X59775D01*
G01X62250Y548076D02*
X62542Y548118D01*
X62875Y548243D01*
X63083Y548451D01*
X63167Y548743D01*
X63083Y549034D01*
X62833Y549284D01*
X62458Y549409D01*
X62042D01*
X61792Y549493D01*
X61583Y549701D01*
X61500Y549993D01*
X61625Y550284D01*
X61917Y550493D01*
X62250Y550576D01*
X62583Y550493D01*
X62875Y550284D01*
X63000Y549993D01*
X62917Y549701D01*
X62708Y549493D01*
X62458Y549409D01*
X62042D01*
X61667Y549284D01*
X61417Y549034D01*
X61333Y548743D01*
X61417Y548451D01*
X61625Y548243D01*
X61958Y548118D01*
X62250Y548076D01*
G01X52117Y551576D02*
Y554076D01*
X53158D01*
X53492Y553951D01*
X53700Y553784D01*
X53783Y553451D01*
X53700Y553118D01*
X53450Y552909D01*
X53158Y552784D01*
X52117D01*
G01X53158D02*
X53783Y551576D01*
G01X55133Y552076D02*
X55383Y551784D01*
X55717Y551618D01*
X56092Y551576D01*
X56425Y551618D01*
X56758Y551826D01*
X56967Y552076D01*
X57008Y552326D01*
X56925Y552618D01*
X56633Y552826D01*
X56342Y552909D01*
X55967D01*
G01X56342D02*
X56592Y553034D01*
X56800Y553243D01*
X56883Y553493D01*
X56800Y553743D01*
X56592Y553951D01*
X56217Y554076D01*
X55842Y554034D01*
X55467Y553868D01*
G01X58358Y552618D02*
X58650Y552909D01*
X58900Y553076D01*
X59233Y553159D01*
X59525Y553076D01*
X59733Y552909D01*
X59900Y552659D01*
X59942Y552368D01*
X59900Y552118D01*
X59733Y551868D01*
X59483Y551659D01*
X59192Y551576D01*
X58858Y551659D01*
X58567Y551909D01*
X58400Y552284D01*
X58358Y552701D01*
X58442Y553243D01*
X58567Y553534D01*
X58775Y553826D01*
X59067Y554034D01*
X59358Y554076D01*
X59650Y553993D01*
X59858Y553784D01*
G01X61458Y552618D02*
X61750Y552909D01*
X62000Y553076D01*
X62333Y553159D01*
X62625Y553076D01*
X62833Y552909D01*
X63000Y552659D01*
X63042Y552368D01*
X63000Y552118D01*
X62833Y551868D01*
X62583Y551659D01*
X62292Y551576D01*
X61958Y551659D01*
X61667Y551909D01*
X61500Y552284D01*
X61458Y552701D01*
X61542Y553243D01*
X61667Y553534D01*
X61875Y553826D01*
X62167Y554034D01*
X62458Y554076D01*
X62750Y553993D01*
X62958Y553784D01*
G01X37807Y563096D02*
Y565596D01*
X38848D01*
X39182Y565471D01*
X39390Y565304D01*
X39473Y564971D01*
X39390Y564638D01*
X39140Y564429D01*
X38848Y564304D01*
X37807D01*
G01X38848D02*
X39473Y563096D01*
G01X40948Y564138D02*
X41240Y564429D01*
X41490Y564596D01*
X41823Y564679D01*
X42115Y564596D01*
X42323Y564429D01*
X42490Y564179D01*
X42532Y563888D01*
X42490Y563638D01*
X42323Y563388D01*
X42073Y563179D01*
X41782Y563096D01*
X41448Y563179D01*
X41157Y563429D01*
X40990Y563804D01*
X40948Y564221D01*
X41032Y564763D01*
X41157Y565054D01*
X41365Y565346D01*
X41657Y565554D01*
X41948Y565596D01*
X42240Y565513D01*
X42448Y565304D01*
G01X44840Y563096D02*
Y565596D01*
X44340Y565096D01*
G01Y563096D02*
X45340D01*
G01X48440D02*
Y565596D01*
X46898Y563804D01*
X48982D01*
G01X37807Y567329D02*
Y569829D01*
X38848D01*
X39182Y569704D01*
X39390Y569537D01*
X39473Y569204D01*
X39390Y568871D01*
X39140Y568662D01*
X38848Y568537D01*
X37807D01*
G01X38848D02*
X39473Y567329D01*
G01X40948Y568371D02*
X41240Y568662D01*
X41490Y568829D01*
X41823Y568912D01*
X42115Y568829D01*
X42323Y568662D01*
X42490Y568412D01*
X42532Y568121D01*
X42490Y567871D01*
X42323Y567621D01*
X42073Y567412D01*
X41782Y567329D01*
X41448Y567412D01*
X41157Y567662D01*
X40990Y568037D01*
X40948Y568454D01*
X41032Y568996D01*
X41157Y569287D01*
X41365Y569579D01*
X41657Y569787D01*
X41948Y569829D01*
X42240Y569746D01*
X42448Y569537D01*
G01X44840Y569829D02*
X44507Y569746D01*
X44257Y569537D01*
X44090Y569287D01*
X43965Y568954D01*
X43923Y568579D01*
X43965Y568204D01*
X44090Y567871D01*
X44257Y567621D01*
X44507Y567412D01*
X44840Y567329D01*
X45173Y567412D01*
X45423Y567621D01*
X45590Y567871D01*
X45715Y568204D01*
X45757Y568579D01*
X45715Y568954D01*
X45590Y569287D01*
X45423Y569537D01*
X45173Y569746D01*
X44840Y569829D01*
G01X47857Y567329D02*
X47940Y567871D01*
X48065Y568329D01*
X48232Y568746D01*
X48440Y569204D01*
X48773Y569829D01*
X47107D01*
G01X37807Y555729D02*
Y558229D01*
X38848D01*
X39182Y558104D01*
X39390Y557937D01*
X39473Y557604D01*
X39390Y557271D01*
X39140Y557062D01*
X38848Y556937D01*
X37807D01*
G01X38848D02*
X39473Y555729D01*
G01X40948Y556771D02*
X41240Y557062D01*
X41490Y557229D01*
X41823Y557312D01*
X42115Y557229D01*
X42323Y557062D01*
X42490Y556812D01*
X42532Y556521D01*
X42490Y556271D01*
X42323Y556021D01*
X42073Y555812D01*
X41782Y555729D01*
X41448Y555812D01*
X41157Y556062D01*
X40990Y556437D01*
X40948Y556854D01*
X41032Y557396D01*
X41157Y557687D01*
X41365Y557979D01*
X41657Y558187D01*
X41948Y558229D01*
X42240Y558146D01*
X42448Y557937D01*
G01X45340Y555729D02*
Y558229D01*
X43798Y556437D01*
X45882D01*
G01X47940Y558229D02*
X47607Y558146D01*
X47357Y557937D01*
X47190Y557687D01*
X47065Y557354D01*
X47023Y556979D01*
X47065Y556604D01*
X47190Y556271D01*
X47357Y556021D01*
X47607Y555812D01*
X47940Y555729D01*
X48273Y555812D01*
X48523Y556021D01*
X48690Y556271D01*
X48815Y556604D01*
X48857Y556979D01*
X48815Y557354D01*
X48690Y557687D01*
X48523Y557937D01*
X48273Y558146D01*
X47940Y558229D01*
G01X37807Y559229D02*
Y561729D01*
X38848D01*
X39182Y561604D01*
X39390Y561437D01*
X39473Y561104D01*
X39390Y560771D01*
X39140Y560562D01*
X38848Y560437D01*
X37807D01*
G01X38848D02*
X39473Y559229D01*
G01X40948Y560271D02*
X41240Y560562D01*
X41490Y560729D01*
X41823Y560812D01*
X42115Y560729D01*
X42323Y560562D01*
X42490Y560312D01*
X42532Y560021D01*
X42490Y559771D01*
X42323Y559521D01*
X42073Y559312D01*
X41782Y559229D01*
X41448Y559312D01*
X41157Y559562D01*
X40990Y559937D01*
X40948Y560354D01*
X41032Y560896D01*
X41157Y561187D01*
X41365Y561479D01*
X41657Y561687D01*
X41948Y561729D01*
X42240Y561646D01*
X42448Y561437D01*
G01X45340Y559229D02*
Y561729D01*
X43798Y559937D01*
X45882D01*
G01X47023Y559604D02*
X47273Y559396D01*
X47565Y559271D01*
X47940Y559229D01*
X48315Y559312D01*
X48607Y559479D01*
X48815Y559771D01*
X48857Y560104D01*
X48773Y560437D01*
X48565Y560646D01*
X48273Y560812D01*
X47982Y560854D01*
X47690Y560812D01*
X47315Y560646D01*
X47440Y561729D01*
X48565D01*
G01X37407Y571429D02*
Y573929D01*
X38448D01*
X38782Y573804D01*
X38990Y573637D01*
X39073Y573304D01*
X38990Y572971D01*
X38740Y572762D01*
X38448Y572637D01*
X37407D01*
G01X38448D02*
X39073Y571429D01*
G01X40423Y571929D02*
X40673Y571637D01*
X41007Y571471D01*
X41382Y571429D01*
X41715Y571471D01*
X42048Y571679D01*
X42257Y571929D01*
X42298Y572179D01*
X42215Y572471D01*
X41923Y572679D01*
X41632Y572762D01*
X41257D01*
G01X41632D02*
X41882Y572887D01*
X42090Y573096D01*
X42173Y573346D01*
X42090Y573596D01*
X41882Y573804D01*
X41507Y573929D01*
X41132Y573887D01*
X40757Y573721D01*
G01X43648Y573512D02*
X43898Y573762D01*
X44190Y573887D01*
X44523Y573929D01*
X44940Y573846D01*
X45232Y573637D01*
X45315Y573387D01*
X45273Y573137D01*
X45107Y572929D01*
X44273Y572512D01*
X43898Y572221D01*
X43648Y571804D01*
X43565Y571429D01*
X45315D01*
G01X48040D02*
Y573929D01*
X46498Y572137D01*
X48582D01*
G01X37807Y548729D02*
Y551229D01*
X38848D01*
X39182Y551104D01*
X39390Y550937D01*
X39473Y550604D01*
X39390Y550271D01*
X39140Y550062D01*
X38848Y549937D01*
X37807D01*
G01X38848D02*
X39473Y548729D01*
G01X40948Y550812D02*
X41198Y551062D01*
X41490Y551187D01*
X41823Y551229D01*
X42240Y551146D01*
X42532Y550937D01*
X42615Y550687D01*
X42573Y550437D01*
X42407Y550229D01*
X41573Y549812D01*
X41198Y549521D01*
X40948Y549104D01*
X40865Y548729D01*
X42615D01*
G01X44840D02*
X45132Y548771D01*
X45465Y548896D01*
X45673Y549104D01*
X45757Y549396D01*
X45673Y549687D01*
X45423Y549937D01*
X45048Y550062D01*
X44632D01*
X44382Y550146D01*
X44173Y550354D01*
X44090Y550646D01*
X44215Y550937D01*
X44507Y551146D01*
X44840Y551229D01*
X45173Y551146D01*
X45465Y550937D01*
X45590Y550646D01*
X45507Y550354D01*
X45298Y550146D01*
X45048Y550062D01*
X44632D01*
X44257Y549937D01*
X44007Y549687D01*
X43923Y549396D01*
X44007Y549104D01*
X44215Y548896D01*
X44548Y548771D01*
X44840Y548729D01*
G01X47232Y549021D02*
X47523Y548812D01*
X47857Y548729D01*
X48190Y548812D01*
X48482Y549062D01*
X48690Y549437D01*
X48773Y549812D01*
Y550271D01*
X48690Y550646D01*
X48482Y550979D01*
X48232Y551146D01*
X47940Y551229D01*
X47607Y551146D01*
X47357Y550979D01*
X47190Y550729D01*
X47107Y550396D01*
X47190Y550104D01*
X47398Y549812D01*
X47648Y549646D01*
X47940Y549604D01*
X48273Y549687D01*
X48523Y549896D01*
X48773Y550271D01*
G01X37807Y552229D02*
Y554729D01*
X38848D01*
X39182Y554604D01*
X39390Y554437D01*
X39473Y554104D01*
X39390Y553771D01*
X39140Y553562D01*
X38848Y553437D01*
X37807D01*
G01X38848D02*
X39473Y552229D01*
G01X40948Y554312D02*
X41198Y554562D01*
X41490Y554687D01*
X41823Y554729D01*
X42240Y554646D01*
X42532Y554437D01*
X42615Y554187D01*
X42573Y553937D01*
X42407Y553729D01*
X41573Y553312D01*
X41198Y553021D01*
X40948Y552604D01*
X40865Y552229D01*
X42615D01*
G01X44132Y552521D02*
X44423Y552312D01*
X44757Y552229D01*
X45090Y552312D01*
X45382Y552562D01*
X45590Y552937D01*
X45673Y553312D01*
Y553771D01*
X45590Y554146D01*
X45382Y554479D01*
X45132Y554646D01*
X44840Y554729D01*
X44507Y554646D01*
X44257Y554479D01*
X44090Y554229D01*
X44007Y553896D01*
X44090Y553604D01*
X44298Y553312D01*
X44548Y553146D01*
X44840Y553104D01*
X45173Y553187D01*
X45423Y553396D01*
X45673Y553771D01*
G01X47940Y554729D02*
X47607Y554646D01*
X47357Y554437D01*
X47190Y554187D01*
X47065Y553854D01*
X47023Y553479D01*
X47065Y553104D01*
X47190Y552771D01*
X47357Y552521D01*
X47607Y552312D01*
X47940Y552229D01*
X48273Y552312D01*
X48523Y552521D01*
X48690Y552771D01*
X48815Y553104D01*
X48857Y553479D01*
X48815Y553854D01*
X48690Y554187D01*
X48523Y554437D01*
X48273Y554646D01*
X47940Y554729D01*
G01X41280Y576975D02*
X41155Y576725D01*
X41072Y576433D01*
Y576100D01*
X41197Y575725D01*
X41405Y575433D01*
X41655Y575225D01*
X42072Y575058D01*
X42447Y575016D01*
X42822Y575100D01*
X43072Y575225D01*
X43322Y575475D01*
X43489Y575766D01*
X43572Y576058D01*
Y576350D01*
X43489Y576641D01*
X43364Y576891D01*
X43197Y577100D01*
G01X41489Y578366D02*
X41239Y578616D01*
X41114Y578908D01*
X41072Y579241D01*
X41155Y579658D01*
X41364Y579950D01*
X41614Y580033D01*
X41864Y579991D01*
X42072Y579825D01*
X42489Y578991D01*
X42780Y578616D01*
X43197Y578366D01*
X43572Y578283D01*
Y580033D01*
G01X41072Y582258D02*
X41155Y581925D01*
X41364Y581675D01*
X41614Y581508D01*
X41947Y581383D01*
X42322Y581341D01*
X42697Y581383D01*
X43030Y581508D01*
X43280Y581675D01*
X43489Y581925D01*
X43572Y582258D01*
X43489Y582591D01*
X43280Y582841D01*
X43030Y583008D01*
X42697Y583133D01*
X42322Y583175D01*
X41947Y583133D01*
X41614Y583008D01*
X41364Y582841D01*
X41155Y582591D01*
X41072Y582258D01*
G01X41489Y584566D02*
X41239Y584816D01*
X41114Y585108D01*
X41072Y585441D01*
X41155Y585858D01*
X41364Y586150D01*
X41614Y586233D01*
X41864Y586191D01*
X42072Y586025D01*
X42489Y585191D01*
X42780Y584816D01*
X43197Y584566D01*
X43572Y584483D01*
Y586233D01*
G01X45347Y576934D02*
X45222Y576684D01*
X45139Y576392D01*
Y576059D01*
X45264Y575684D01*
X45472Y575392D01*
X45722Y575184D01*
X46139Y575017D01*
X46514Y574975D01*
X46889Y575059D01*
X47139Y575184D01*
X47389Y575434D01*
X47556Y575725D01*
X47639Y576017D01*
Y576309D01*
X47556Y576600D01*
X47431Y576850D01*
X47264Y577059D01*
G01X45556Y578325D02*
X45306Y578575D01*
X45181Y578867D01*
X45139Y579200D01*
X45222Y579617D01*
X45431Y579909D01*
X45681Y579992D01*
X45931Y579950D01*
X46139Y579784D01*
X46556Y578950D01*
X46847Y578575D01*
X47264Y578325D01*
X47639Y578242D01*
Y579992D01*
G01X45139Y582217D02*
X45222Y581884D01*
X45431Y581634D01*
X45681Y581467D01*
X46014Y581342D01*
X46389Y581300D01*
X46764Y581342D01*
X47097Y581467D01*
X47347Y581634D01*
X47556Y581884D01*
X47639Y582217D01*
X47556Y582550D01*
X47347Y582800D01*
X47097Y582967D01*
X46764Y583092D01*
X46389Y583134D01*
X46014Y583092D01*
X45681Y582967D01*
X45431Y582800D01*
X45222Y582550D01*
X45139Y582217D01*
G01X47139Y584400D02*
X47431Y584650D01*
X47597Y584984D01*
X47639Y585359D01*
X47597Y585692D01*
X47389Y586025D01*
X47139Y586234D01*
X46889Y586275D01*
X46597Y586192D01*
X46389Y585900D01*
X46306Y585609D01*
Y585234D01*
G01Y585609D02*
X46181Y585859D01*
X45972Y586067D01*
X45722Y586150D01*
X45472Y586067D01*
X45264Y585859D01*
X45139Y585484D01*
X45181Y585109D01*
X45347Y584734D01*
G01X58939Y592884D02*
X60731D01*
X61106Y593051D01*
X61356Y593384D01*
X61439Y593801D01*
X61356Y594218D01*
X61106Y594551D01*
X60731Y594718D01*
X58939D01*
G01X59356Y596109D02*
X59106Y596359D01*
X58981Y596651D01*
X58939Y596984D01*
X59022Y597401D01*
X59231Y597693D01*
X59481Y597776D01*
X59731Y597734D01*
X59939Y597568D01*
X60356Y596734D01*
X60647Y596359D01*
X61064Y596109D01*
X61439Y596026D01*
Y597776D01*
G01X61064Y599084D02*
X61272Y599334D01*
X61397Y599626D01*
X61439Y600001D01*
X61356Y600376D01*
X61189Y600668D01*
X60897Y600876D01*
X60564Y600918D01*
X60231Y600834D01*
X60022Y600626D01*
X59856Y600334D01*
X59814Y600043D01*
X59856Y599751D01*
X60022Y599376D01*
X58939Y599501D01*
Y600626D01*
G01X47700Y600667D02*
X45200D01*
Y601708D01*
X45325Y602042D01*
X45492Y602250D01*
X45825Y602333D01*
X46158Y602250D01*
X46367Y602000D01*
X46492Y601708D01*
Y600667D01*
G01Y601708D02*
X47700Y602333D01*
G01X47200Y603683D02*
X47492Y603933D01*
X47658Y604267D01*
X47700Y604642D01*
X47658Y604975D01*
X47450Y605308D01*
X47200Y605517D01*
X46950Y605558D01*
X46658Y605475D01*
X46450Y605183D01*
X46367Y604892D01*
Y604517D01*
G01Y604892D02*
X46242Y605142D01*
X46033Y605350D01*
X45783Y605433D01*
X45533Y605350D01*
X45325Y605142D01*
X45200Y604767D01*
X45242Y604392D01*
X45408Y604017D01*
G01X46658Y606908D02*
X46367Y607200D01*
X46200Y607450D01*
X46117Y607783D01*
X46200Y608075D01*
X46367Y608283D01*
X46617Y608450D01*
X46908Y608492D01*
X47158Y608450D01*
X47408Y608283D01*
X47617Y608033D01*
X47700Y607742D01*
X47617Y607408D01*
X47367Y607117D01*
X46992Y606950D01*
X46575Y606908D01*
X46033Y606992D01*
X45742Y607117D01*
X45450Y607325D01*
X45242Y607617D01*
X45200Y607908D01*
X45283Y608200D01*
X45492Y608408D01*
G01X45200Y610800D02*
X45283Y610467D01*
X45492Y610217D01*
X45742Y610050D01*
X46075Y609925D01*
X46450Y609883D01*
X46825Y609925D01*
X47158Y610050D01*
X47408Y610217D01*
X47617Y610467D01*
X47700Y610800D01*
X47617Y611133D01*
X47408Y611383D01*
X47158Y611550D01*
X46825Y611675D01*
X46450Y611717D01*
X46075Y611675D01*
X45742Y611550D01*
X45492Y611383D01*
X45283Y611133D01*
X45200Y610800D01*
G01X47700Y614400D02*
X45200D01*
X46992Y612858D01*
Y614942D01*
G01X57344Y584388D02*
X54844D01*
Y585429D01*
X54969Y585763D01*
X55136Y585971D01*
X55469Y586054D01*
X55802Y585971D01*
X56011Y585721D01*
X56136Y585429D01*
Y584388D01*
G01Y585429D02*
X57344Y586054D01*
G01Y588821D02*
X54844D01*
X56636Y587279D01*
Y589363D01*
G01X57052Y590713D02*
X57261Y591004D01*
X57344Y591338D01*
X57261Y591671D01*
X57011Y591963D01*
X56636Y592171D01*
X56261Y592254D01*
X55802D01*
X55427Y592171D01*
X55094Y591963D01*
X54927Y591713D01*
X54844Y591421D01*
X54927Y591088D01*
X55094Y590838D01*
X55344Y590671D01*
X55677Y590588D01*
X55969Y590671D01*
X56261Y590879D01*
X56427Y591129D01*
X56469Y591421D01*
X56386Y591754D01*
X56177Y592004D01*
X55802Y592254D01*
G01X57344Y594521D02*
X54844D01*
X55344Y594021D01*
G01X57344D02*
Y595021D01*
G01X57561Y596610D02*
X55061D01*
Y597651D01*
X55186Y597985D01*
X55353Y598193D01*
X55686Y598276D01*
X56019Y598193D01*
X56228Y597943D01*
X56353Y597651D01*
Y596610D01*
G01Y597651D02*
X57561Y598276D01*
G01Y601043D02*
X55061D01*
X56853Y599501D01*
Y601585D01*
G01X57561Y603643D02*
X57519Y603935D01*
X57394Y604268D01*
X57186Y604476D01*
X56894Y604560D01*
X56603Y604476D01*
X56353Y604226D01*
X56228Y603851D01*
Y603435D01*
X56144Y603185D01*
X55936Y602976D01*
X55644Y602893D01*
X55353Y603018D01*
X55144Y603310D01*
X55061Y603643D01*
X55144Y603976D01*
X55353Y604268D01*
X55644Y604393D01*
X55936Y604310D01*
X56144Y604101D01*
X56228Y603851D01*
Y603435D01*
X56353Y603060D01*
X56603Y602810D01*
X56894Y602726D01*
X57186Y602810D01*
X57394Y603018D01*
X57519Y603351D01*
X57561Y603643D01*
G01X57269Y606035D02*
X57478Y606326D01*
X57561Y606660D01*
X57478Y606993D01*
X57228Y607285D01*
X56853Y607493D01*
X56478Y607576D01*
X56019D01*
X55644Y607493D01*
X55311Y607285D01*
X55144Y607035D01*
X55061Y606743D01*
X55144Y606410D01*
X55311Y606160D01*
X55561Y605993D01*
X55894Y605910D01*
X56186Y605993D01*
X56478Y606201D01*
X56644Y606451D01*
X56686Y606743D01*
X56603Y607076D01*
X56394Y607326D01*
X56019Y607576D01*
G01X45420Y589825D02*
X45295Y589575D01*
X45212Y589283D01*
Y588950D01*
X45337Y588575D01*
X45545Y588283D01*
X45795Y588075D01*
X46212Y587908D01*
X46587Y587866D01*
X46962Y587950D01*
X47212Y588075D01*
X47462Y588325D01*
X47629Y588616D01*
X47712Y588908D01*
Y589200D01*
X47629Y589491D01*
X47504Y589741D01*
X47337Y589950D01*
G01X47712Y592008D02*
X45212D01*
X45712Y591508D01*
G01X47712D02*
Y592508D01*
G01X47420Y594400D02*
X47629Y594691D01*
X47712Y595025D01*
X47629Y595358D01*
X47379Y595650D01*
X47004Y595858D01*
X46629Y595941D01*
X46170D01*
X45795Y595858D01*
X45462Y595650D01*
X45295Y595400D01*
X45212Y595108D01*
X45295Y594775D01*
X45462Y594525D01*
X45712Y594358D01*
X46045Y594275D01*
X46337Y594358D01*
X46629Y594566D01*
X46795Y594816D01*
X46837Y595108D01*
X46754Y595441D01*
X46545Y595691D01*
X46170Y595941D01*
G01X47337Y597291D02*
X47545Y597541D01*
X47670Y597833D01*
X47712Y598208D01*
X47629Y598583D01*
X47462Y598875D01*
X47170Y599083D01*
X46837Y599125D01*
X46504Y599041D01*
X46295Y598833D01*
X46129Y598541D01*
X46087Y598250D01*
X46129Y597958D01*
X46295Y597583D01*
X45212Y597708D01*
Y598833D01*
G01X41157Y589825D02*
X41032Y589575D01*
X40949Y589283D01*
Y588950D01*
X41074Y588575D01*
X41282Y588283D01*
X41532Y588075D01*
X41949Y587908D01*
X42324Y587866D01*
X42699Y587950D01*
X42949Y588075D01*
X43199Y588325D01*
X43366Y588616D01*
X43449Y588908D01*
Y589200D01*
X43366Y589491D01*
X43241Y589741D01*
X43074Y589950D01*
G01X43449Y592008D02*
X40949D01*
X41449Y591508D01*
G01X43449D02*
Y592508D01*
G01X43157Y594400D02*
X43366Y594691D01*
X43449Y595025D01*
X43366Y595358D01*
X43116Y595650D01*
X42741Y595858D01*
X42366Y595941D01*
X41907D01*
X41532Y595858D01*
X41199Y595650D01*
X41032Y595400D01*
X40949Y595108D01*
X41032Y594775D01*
X41199Y594525D01*
X41449Y594358D01*
X41782Y594275D01*
X42074Y594358D01*
X42366Y594566D01*
X42532Y594816D01*
X42574Y595108D01*
X42491Y595441D01*
X42282Y595691D01*
X41907Y595941D01*
G01X42407Y597416D02*
X42116Y597708D01*
X41949Y597958D01*
X41866Y598291D01*
X41949Y598583D01*
X42116Y598791D01*
X42366Y598958D01*
X42657Y599000D01*
X42907Y598958D01*
X43157Y598791D01*
X43366Y598541D01*
X43449Y598250D01*
X43366Y597916D01*
X43116Y597625D01*
X42741Y597458D01*
X42324Y597416D01*
X41782Y597500D01*
X41491Y597625D01*
X41199Y597833D01*
X40991Y598125D01*
X40949Y598416D01*
X41032Y598708D01*
X41241Y598916D01*
G01X40908Y602467D02*
X40783Y602217D01*
X40700Y601925D01*
Y601592D01*
X40825Y601217D01*
X41033Y600925D01*
X41283Y600717D01*
X41700Y600550D01*
X42075Y600508D01*
X42450Y600592D01*
X42700Y600717D01*
X42950Y600967D01*
X43117Y601258D01*
X43200Y601550D01*
Y601842D01*
X43117Y602133D01*
X42992Y602383D01*
X42825Y602592D01*
G01X43200Y604650D02*
X40700D01*
X41200Y604150D01*
G01X43200D02*
Y605150D01*
G01Y607750D02*
X43158Y608042D01*
X43033Y608375D01*
X42825Y608583D01*
X42533Y608667D01*
X42242Y608583D01*
X41992Y608333D01*
X41867Y607958D01*
Y607542D01*
X41783Y607292D01*
X41575Y607083D01*
X41283Y607000D01*
X40992Y607125D01*
X40783Y607417D01*
X40700Y607750D01*
X40783Y608083D01*
X40992Y608375D01*
X41283Y608500D01*
X41575Y608417D01*
X41783Y608208D01*
X41867Y607958D01*
Y607542D01*
X41992Y607167D01*
X42242Y606917D01*
X42533Y606833D01*
X42825Y606917D01*
X43033Y607125D01*
X43158Y607458D01*
X43200Y607750D01*
G01Y610767D02*
X42658Y610850D01*
X42200Y610975D01*
X41783Y611142D01*
X41325Y611350D01*
X40700Y611683D01*
Y610017D01*
G01X50676Y616946D02*
X48176D01*
Y617987D01*
X48301Y618321D01*
X48468Y618529D01*
X48801Y618612D01*
X49134Y618529D01*
X49343Y618279D01*
X49468Y617987D01*
Y616946D01*
G01Y617987D02*
X50676Y618612D01*
G01Y621379D02*
X48176D01*
X49968Y619837D01*
Y621921D01*
G01X50384Y623271D02*
X50593Y623562D01*
X50676Y623896D01*
X50593Y624229D01*
X50343Y624521D01*
X49968Y624729D01*
X49593Y624812D01*
X49134D01*
X48759Y624729D01*
X48426Y624521D01*
X48259Y624271D01*
X48176Y623979D01*
X48259Y623646D01*
X48426Y623396D01*
X48676Y623229D01*
X49009Y623146D01*
X49301Y623229D01*
X49593Y623437D01*
X49759Y623687D01*
X49801Y623979D01*
X49718Y624312D01*
X49509Y624562D01*
X49134Y624812D01*
G01X50176Y626162D02*
X50468Y626412D01*
X50634Y626746D01*
X50676Y627121D01*
X50634Y627454D01*
X50426Y627787D01*
X50176Y627996D01*
X49926Y628037D01*
X49634Y627954D01*
X49426Y627662D01*
X49343Y627371D01*
Y626996D01*
G01Y627371D02*
X49218Y627621D01*
X49009Y627829D01*
X48759Y627912D01*
X48509Y627829D01*
X48301Y627621D01*
X48176Y627246D01*
X48218Y626871D01*
X48384Y626496D01*
G01X46676Y616896D02*
X44176D01*
Y617937D01*
X44301Y618271D01*
X44468Y618479D01*
X44801Y618562D01*
X45134Y618479D01*
X45343Y618229D01*
X45468Y617937D01*
Y616896D01*
G01Y617937D02*
X46676Y618562D01*
G01Y620829D02*
X46634Y621121D01*
X46509Y621454D01*
X46301Y621662D01*
X46009Y621746D01*
X45718Y621662D01*
X45468Y621412D01*
X45343Y621037D01*
Y620621D01*
X45259Y620371D01*
X45051Y620162D01*
X44759Y620079D01*
X44468Y620204D01*
X44259Y620496D01*
X44176Y620829D01*
X44259Y621162D01*
X44468Y621454D01*
X44759Y621579D01*
X45051Y621496D01*
X45259Y621287D01*
X45343Y621037D01*
Y620621D01*
X45468Y620246D01*
X45718Y619996D01*
X46009Y619912D01*
X46301Y619996D01*
X46509Y620204D01*
X46634Y620537D01*
X46676Y620829D01*
G01X44176Y623929D02*
X44259Y623596D01*
X44468Y623346D01*
X44718Y623179D01*
X45051Y623054D01*
X45426Y623012D01*
X45801Y623054D01*
X46134Y623179D01*
X46384Y623346D01*
X46593Y623596D01*
X46676Y623929D01*
X46593Y624262D01*
X46384Y624512D01*
X46134Y624679D01*
X45801Y624804D01*
X45426Y624846D01*
X45051Y624804D01*
X44718Y624679D01*
X44468Y624512D01*
X44259Y624262D01*
X44176Y623929D01*
G01Y627029D02*
X44259Y626696D01*
X44468Y626446D01*
X44718Y626279D01*
X45051Y626154D01*
X45426Y626112D01*
X45801Y626154D01*
X46134Y626279D01*
X46384Y626446D01*
X46593Y626696D01*
X46676Y627029D01*
X46593Y627362D01*
X46384Y627612D01*
X46134Y627779D01*
X45801Y627904D01*
X45426Y627946D01*
X45051Y627904D01*
X44718Y627779D01*
X44468Y627612D01*
X44259Y627362D01*
X44176Y627029D01*
G01X46676Y630046D02*
X46134Y630129D01*
X45676Y630254D01*
X45259Y630421D01*
X44801Y630629D01*
X44176Y630962D01*
Y629296D01*
G01X38676Y616896D02*
X36176D01*
Y617937D01*
X36301Y618271D01*
X36468Y618479D01*
X36801Y618562D01*
X37134Y618479D01*
X37343Y618229D01*
X37468Y617937D01*
Y616896D01*
G01Y617937D02*
X38676Y618562D01*
G01Y620829D02*
X38634Y621121D01*
X38509Y621454D01*
X38301Y621662D01*
X38009Y621746D01*
X37718Y621662D01*
X37468Y621412D01*
X37343Y621037D01*
Y620621D01*
X37259Y620371D01*
X37051Y620162D01*
X36759Y620079D01*
X36468Y620204D01*
X36259Y620496D01*
X36176Y620829D01*
X36259Y621162D01*
X36468Y621454D01*
X36759Y621579D01*
X37051Y621496D01*
X37259Y621287D01*
X37343Y621037D01*
Y620621D01*
X37468Y620246D01*
X37718Y619996D01*
X38009Y619912D01*
X38301Y619996D01*
X38509Y620204D01*
X38634Y620537D01*
X38676Y620829D01*
G01X36176Y623929D02*
X36259Y623596D01*
X36468Y623346D01*
X36718Y623179D01*
X37051Y623054D01*
X37426Y623012D01*
X37801Y623054D01*
X38134Y623179D01*
X38384Y623346D01*
X38593Y623596D01*
X38676Y623929D01*
X38593Y624262D01*
X38384Y624512D01*
X38134Y624679D01*
X37801Y624804D01*
X37426Y624846D01*
X37051Y624804D01*
X36718Y624679D01*
X36468Y624512D01*
X36259Y624262D01*
X36176Y623929D01*
G01Y627029D02*
X36259Y626696D01*
X36468Y626446D01*
X36718Y626279D01*
X37051Y626154D01*
X37426Y626112D01*
X37801Y626154D01*
X38134Y626279D01*
X38384Y626446D01*
X38593Y626696D01*
X38676Y627029D01*
X38593Y627362D01*
X38384Y627612D01*
X38134Y627779D01*
X37801Y627904D01*
X37426Y627946D01*
X37051Y627904D01*
X36718Y627779D01*
X36468Y627612D01*
X36259Y627362D01*
X36176Y627029D01*
G01X38176Y629212D02*
X38468Y629462D01*
X38634Y629796D01*
X38676Y630171D01*
X38634Y630504D01*
X38426Y630837D01*
X38176Y631046D01*
X37926Y631087D01*
X37634Y631004D01*
X37426Y630712D01*
X37343Y630421D01*
Y630046D01*
G01Y630421D02*
X37218Y630671D01*
X37009Y630879D01*
X36759Y630962D01*
X36509Y630879D01*
X36301Y630671D01*
X36176Y630296D01*
X36218Y629921D01*
X36384Y629546D01*
G01X42676Y616896D02*
X40176D01*
Y617937D01*
X40301Y618271D01*
X40468Y618479D01*
X40801Y618562D01*
X41134Y618479D01*
X41343Y618229D01*
X41468Y617937D01*
Y616896D01*
G01Y617937D02*
X42676Y618562D01*
G01Y620829D02*
X42634Y621121D01*
X42509Y621454D01*
X42301Y621662D01*
X42009Y621746D01*
X41718Y621662D01*
X41468Y621412D01*
X41343Y621037D01*
Y620621D01*
X41259Y620371D01*
X41051Y620162D01*
X40759Y620079D01*
X40468Y620204D01*
X40259Y620496D01*
X40176Y620829D01*
X40259Y621162D01*
X40468Y621454D01*
X40759Y621579D01*
X41051Y621496D01*
X41259Y621287D01*
X41343Y621037D01*
Y620621D01*
X41468Y620246D01*
X41718Y619996D01*
X42009Y619912D01*
X42301Y619996D01*
X42509Y620204D01*
X42634Y620537D01*
X42676Y620829D01*
G01X40176Y623929D02*
X40259Y623596D01*
X40468Y623346D01*
X40718Y623179D01*
X41051Y623054D01*
X41426Y623012D01*
X41801Y623054D01*
X42134Y623179D01*
X42384Y623346D01*
X42593Y623596D01*
X42676Y623929D01*
X42593Y624262D01*
X42384Y624512D01*
X42134Y624679D01*
X41801Y624804D01*
X41426Y624846D01*
X41051Y624804D01*
X40718Y624679D01*
X40468Y624512D01*
X40259Y624262D01*
X40176Y623929D01*
G01Y627029D02*
X40259Y626696D01*
X40468Y626446D01*
X40718Y626279D01*
X41051Y626154D01*
X41426Y626112D01*
X41801Y626154D01*
X42134Y626279D01*
X42384Y626446D01*
X42593Y626696D01*
X42676Y627029D01*
X42593Y627362D01*
X42384Y627612D01*
X42134Y627779D01*
X41801Y627904D01*
X41426Y627946D01*
X41051Y627904D01*
X40718Y627779D01*
X40468Y627612D01*
X40259Y627362D01*
X40176Y627029D01*
G01X42301Y629212D02*
X42509Y629462D01*
X42634Y629754D01*
X42676Y630129D01*
X42593Y630504D01*
X42426Y630796D01*
X42134Y631004D01*
X41801Y631046D01*
X41468Y630962D01*
X41259Y630754D01*
X41093Y630462D01*
X41051Y630171D01*
X41093Y629879D01*
X41259Y629504D01*
X40176Y629629D01*
Y630754D01*
G01X59219Y616934D02*
X56719D01*
Y617768D01*
X56844Y618101D01*
X57011Y618351D01*
X57261Y618559D01*
X57552Y618726D01*
X57969Y618768D01*
X58386Y618726D01*
X58677Y618559D01*
X58927Y618351D01*
X59094Y618101D01*
X59219Y617768D01*
Y616934D01*
G01Y620951D02*
X56719D01*
X57219Y620451D01*
G01X59219D02*
Y621451D01*
G01Y624551D02*
X56719D01*
X58511Y623009D01*
Y625093D01*
G01X56719Y627151D02*
X56802Y626818D01*
X57011Y626568D01*
X57261Y626401D01*
X57594Y626276D01*
X57969Y626234D01*
X58344Y626276D01*
X58677Y626401D01*
X58927Y626568D01*
X59136Y626818D01*
X59219Y627151D01*
X59136Y627484D01*
X58927Y627734D01*
X58677Y627901D01*
X58344Y628026D01*
X57969Y628068D01*
X57594Y628026D01*
X57261Y627901D01*
X57011Y627734D01*
X56802Y627484D01*
X56719Y627151D01*
G01X59219Y630251D02*
X56719D01*
X57219Y629751D01*
G01X59219D02*
Y630751D01*
G01X55138Y616812D02*
X52638D01*
Y617646D01*
X52763Y617979D01*
X52930Y618229D01*
X53180Y618437D01*
X53471Y618604D01*
X53888Y618646D01*
X54305Y618604D01*
X54596Y618437D01*
X54846Y618229D01*
X55013Y617979D01*
X55138Y617646D01*
Y616812D01*
G01Y620829D02*
X52638D01*
X53138Y620329D01*
G01X55138D02*
Y621329D01*
G01Y624429D02*
X52638D01*
X54430Y622887D01*
Y624971D01*
G01X52638Y627029D02*
X52721Y626696D01*
X52930Y626446D01*
X53180Y626279D01*
X53513Y626154D01*
X53888Y626112D01*
X54263Y626154D01*
X54596Y626279D01*
X54846Y626446D01*
X55055Y626696D01*
X55138Y627029D01*
X55055Y627362D01*
X54846Y627612D01*
X54596Y627779D01*
X54263Y627904D01*
X53888Y627946D01*
X53513Y627904D01*
X53180Y627779D01*
X52930Y627612D01*
X52721Y627362D01*
X52638Y627029D01*
G01X53055Y629337D02*
X52805Y629587D01*
X52680Y629879D01*
X52638Y630212D01*
X52721Y630629D01*
X52930Y630921D01*
X53180Y631004D01*
X53430Y630962D01*
X53638Y630796D01*
X54055Y629962D01*
X54346Y629587D01*
X54763Y629337D01*
X55138Y629254D01*
Y631004D01*
G01X63261Y679044D02*
X63136Y678794D01*
X63053Y678502D01*
Y678169D01*
X63178Y677794D01*
X63386Y677502D01*
X63636Y677294D01*
X64053Y677127D01*
X64428Y677085D01*
X64803Y677169D01*
X65053Y677294D01*
X65303Y677544D01*
X65470Y677835D01*
X65553Y678127D01*
Y678419D01*
X65470Y678710D01*
X65345Y678960D01*
X65178Y679169D01*
G01X65053Y680310D02*
X65345Y680560D01*
X65511Y680894D01*
X65553Y681269D01*
X65511Y681602D01*
X65303Y681935D01*
X65053Y682144D01*
X64803Y682185D01*
X64511Y682102D01*
X64303Y681810D01*
X64220Y681519D01*
Y681144D01*
G01Y681519D02*
X64095Y681769D01*
X63886Y681977D01*
X63636Y682060D01*
X63386Y681977D01*
X63178Y681769D01*
X63053Y681394D01*
X63095Y681019D01*
X63261Y680644D01*
G01X65053Y683410D02*
X65345Y683660D01*
X65511Y683994D01*
X65553Y684369D01*
X65511Y684702D01*
X65303Y685035D01*
X65053Y685244D01*
X64803Y685285D01*
X64511Y685202D01*
X64303Y684910D01*
X64220Y684619D01*
Y684244D01*
G01Y684619D02*
X64095Y684869D01*
X63886Y685077D01*
X63636Y685160D01*
X63386Y685077D01*
X63178Y684869D01*
X63053Y684494D01*
X63095Y684119D01*
X63261Y683744D01*
G01X65261Y686719D02*
X65470Y687010D01*
X65553Y687344D01*
X65470Y687677D01*
X65220Y687969D01*
X64845Y688177D01*
X64470Y688260D01*
X64011D01*
X63636Y688177D01*
X63303Y687969D01*
X63136Y687719D01*
X63053Y687427D01*
X63136Y687094D01*
X63303Y686844D01*
X63553Y686677D01*
X63886Y686594D01*
X64178Y686677D01*
X64470Y686885D01*
X64636Y687135D01*
X64678Y687427D01*
X64595Y687760D01*
X64386Y688010D01*
X64011Y688260D01*
G01X37062Y670132D02*
X34562D01*
Y671173D01*
X34687Y671507D01*
X34854Y671715D01*
X35187Y671798D01*
X35520Y671715D01*
X35729Y671465D01*
X35854Y671173D01*
Y670132D01*
G01Y671173D02*
X37062Y671798D01*
G01Y673982D02*
X36520Y674065D01*
X36062Y674190D01*
X35645Y674357D01*
X35187Y674565D01*
X34562Y674898D01*
Y673232D01*
G01X36562Y676248D02*
X36854Y676498D01*
X37020Y676832D01*
X37062Y677207D01*
X37020Y677540D01*
X36812Y677873D01*
X36562Y678082D01*
X36312Y678123D01*
X36020Y678040D01*
X35812Y677748D01*
X35729Y677457D01*
Y677082D01*
G01Y677457D02*
X35604Y677707D01*
X35395Y677915D01*
X35145Y677998D01*
X34895Y677915D01*
X34687Y677707D01*
X34562Y677332D01*
X34604Y676957D01*
X34770Y676582D01*
G01X37062Y680265D02*
X37020Y680557D01*
X36895Y680890D01*
X36687Y681098D01*
X36395Y681182D01*
X36104Y681098D01*
X35854Y680848D01*
X35729Y680473D01*
Y680057D01*
X35645Y679807D01*
X35437Y679598D01*
X35145Y679515D01*
X34854Y679640D01*
X34645Y679932D01*
X34562Y680265D01*
X34645Y680598D01*
X34854Y680890D01*
X35145Y681015D01*
X35437Y680932D01*
X35645Y680723D01*
X35729Y680473D01*
Y680057D01*
X35854Y679682D01*
X36104Y679432D01*
X36395Y679348D01*
X36687Y679432D01*
X36895Y679640D01*
X37020Y679973D01*
X37062Y680265D01*
G01X49492Y672901D02*
Y675401D01*
X50533D01*
X50867Y675276D01*
X51075Y675109D01*
X51158Y674776D01*
X51075Y674443D01*
X50825Y674234D01*
X50533Y674109D01*
X49492D01*
G01X50533D02*
X51158Y672901D01*
G01X52633Y673943D02*
X52925Y674234D01*
X53175Y674401D01*
X53508Y674484D01*
X53800Y674401D01*
X54008Y674234D01*
X54175Y673984D01*
X54217Y673693D01*
X54175Y673443D01*
X54008Y673193D01*
X53758Y672984D01*
X53467Y672901D01*
X53133Y672984D01*
X52842Y673234D01*
X52675Y673609D01*
X52633Y674026D01*
X52717Y674568D01*
X52842Y674859D01*
X53050Y675151D01*
X53342Y675359D01*
X53633Y675401D01*
X53925Y675318D01*
X54133Y675109D01*
G01X55733Y673943D02*
X56025Y674234D01*
X56275Y674401D01*
X56608Y674484D01*
X56900Y674401D01*
X57108Y674234D01*
X57275Y673984D01*
X57317Y673693D01*
X57275Y673443D01*
X57108Y673193D01*
X56858Y672984D01*
X56567Y672901D01*
X56233Y672984D01*
X55942Y673234D01*
X55775Y673609D01*
X55733Y674026D01*
X55817Y674568D01*
X55942Y674859D01*
X56150Y675151D01*
X56442Y675359D01*
X56733Y675401D01*
X57025Y675318D01*
X57233Y675109D01*
G01X60125Y672901D02*
Y675401D01*
X58583Y673609D01*
X60667D01*
G01X55200Y681000D02*
X59200D01*
Y688400D01*
G01X49492Y676901D02*
Y679401D01*
X50492D01*
X50825Y679276D01*
X51075Y678984D01*
X51158Y678651D01*
X51075Y678318D01*
X50867Y678068D01*
X50492Y677943D01*
X49492D01*
G01X52592Y676901D02*
Y679401D01*
X53633D01*
X53967Y679276D01*
X54175Y679109D01*
X54258Y678776D01*
X54175Y678443D01*
X53925Y678234D01*
X53633Y678109D01*
X52592D01*
G01X53633D02*
X54258Y676901D01*
G01X55608Y677401D02*
X55858Y677109D01*
X56192Y676943D01*
X56567Y676901D01*
X56900Y676943D01*
X57233Y677151D01*
X57442Y677401D01*
X57483Y677651D01*
X57400Y677943D01*
X57108Y678151D01*
X56817Y678234D01*
X56442D01*
G01X56817D02*
X57067Y678359D01*
X57275Y678568D01*
X57358Y678818D01*
X57275Y679068D01*
X57067Y679276D01*
X56692Y679401D01*
X56317Y679359D01*
X55942Y679193D01*
G01X58917Y677193D02*
X59208Y676984D01*
X59542Y676901D01*
X59875Y676984D01*
X60167Y677234D01*
X60375Y677609D01*
X60458Y677984D01*
Y678443D01*
X60375Y678818D01*
X60167Y679151D01*
X59917Y679318D01*
X59625Y679401D01*
X59292Y679318D01*
X59042Y679151D01*
X58875Y678901D01*
X58792Y678568D01*
X58875Y678276D01*
X59083Y677984D01*
X59333Y677818D01*
X59625Y677776D01*
X59958Y677859D01*
X60208Y678068D01*
X60458Y678443D01*
G01X40388Y677057D02*
X40055Y677099D01*
X39763Y677265D01*
X39513Y677515D01*
X39346Y677807D01*
X39263Y678140D01*
Y678474D01*
X39346Y678807D01*
X39513Y679099D01*
X39763Y679349D01*
X40055Y679515D01*
X40388Y679557D01*
X40721Y679515D01*
X41013Y679349D01*
X41263Y679099D01*
X41430Y678807D01*
X41513Y678474D01*
Y678140D01*
X41430Y677807D01*
X41263Y677515D01*
X41013Y677265D01*
X40721Y677099D01*
X40388Y677057D01*
G01X40721Y677724D02*
X41221Y677057D01*
G01X42780Y677349D02*
X43071Y677140D01*
X43405Y677057D01*
X43738Y677140D01*
X44030Y677390D01*
X44238Y677765D01*
X44321Y678140D01*
Y678599D01*
X44238Y678974D01*
X44030Y679307D01*
X43780Y679474D01*
X43488Y679557D01*
X43155Y679474D01*
X42905Y679307D01*
X42738Y679057D01*
X42655Y678724D01*
X42738Y678432D01*
X42946Y678140D01*
X43196Y677974D01*
X43488Y677932D01*
X43821Y678015D01*
X44071Y678224D01*
X44321Y678599D01*
G01X45796Y678099D02*
X46088Y678390D01*
X46338Y678557D01*
X46671Y678640D01*
X46963Y678557D01*
X47171Y678390D01*
X47338Y678140D01*
X47380Y677849D01*
X47338Y677599D01*
X47171Y677349D01*
X46921Y677140D01*
X46630Y677057D01*
X46296Y677140D01*
X46005Y677390D01*
X45838Y677765D01*
X45796Y678182D01*
X45880Y678724D01*
X46005Y679015D01*
X46213Y679307D01*
X46505Y679515D01*
X46796Y679557D01*
X47088Y679474D01*
X47296Y679265D01*
G01X53300Y715100D02*
X49300D01*
Y707700D01*
G01X45300Y715100D02*
X41300D01*
Y707700D01*
G01X42718Y698342D02*
Y700842D01*
X43759D01*
X44093Y700717D01*
X44301Y700550D01*
X44384Y700217D01*
X44301Y699884D01*
X44051Y699675D01*
X43759Y699550D01*
X42718D01*
G01X43759D02*
X44384Y698342D01*
G01X46651D02*
Y700842D01*
X46151Y700342D01*
G01Y698342D02*
X47151D01*
G01X48959Y700425D02*
X49209Y700675D01*
X49501Y700800D01*
X49834Y700842D01*
X50251Y700759D01*
X50543Y700550D01*
X50626Y700300D01*
X50584Y700050D01*
X50418Y699842D01*
X49584Y699425D01*
X49209Y699134D01*
X48959Y698717D01*
X48876Y698342D01*
X50626D01*
G01X52059Y700425D02*
X52309Y700675D01*
X52601Y700800D01*
X52934Y700842D01*
X53351Y700759D01*
X53643Y700550D01*
X53726Y700300D01*
X53684Y700050D01*
X53518Y699842D01*
X52684Y699425D01*
X52309Y699134D01*
X52059Y698717D01*
X51976Y698342D01*
X53726D01*
G01X55868D02*
X55951Y698884D01*
X56076Y699342D01*
X56243Y699759D01*
X56451Y700217D01*
X56784Y700842D01*
X55118D01*
G01X60800Y706900D02*
Y710900D01*
X53400D01*
G01X42718Y702442D02*
Y704942D01*
X43759D01*
X44093Y704817D01*
X44301Y704650D01*
X44384Y704317D01*
X44301Y703984D01*
X44051Y703775D01*
X43759Y703650D01*
X42718D01*
G01X43759D02*
X44384Y702442D01*
G01X46651D02*
Y704942D01*
X46151Y704442D01*
G01Y702442D02*
X47151D01*
G01X48959Y704525D02*
X49209Y704775D01*
X49501Y704900D01*
X49834Y704942D01*
X50251Y704859D01*
X50543Y704650D01*
X50626Y704400D01*
X50584Y704150D01*
X50418Y703942D01*
X49584Y703525D01*
X49209Y703234D01*
X48959Y702817D01*
X48876Y702442D01*
X50626D01*
G01X52059Y704525D02*
X52309Y704775D01*
X52601Y704900D01*
X52934Y704942D01*
X53351Y704859D01*
X53643Y704650D01*
X53726Y704400D01*
X53684Y704150D01*
X53518Y703942D01*
X52684Y703525D01*
X52309Y703234D01*
X52059Y702817D01*
X51976Y702442D01*
X53726D01*
G01X55159Y703484D02*
X55451Y703775D01*
X55701Y703942D01*
X56034Y704025D01*
X56326Y703942D01*
X56534Y703775D01*
X56701Y703525D01*
X56743Y703234D01*
X56701Y702984D01*
X56534Y702734D01*
X56284Y702525D01*
X55993Y702442D01*
X55659Y702525D01*
X55368Y702775D01*
X55201Y703150D01*
X55159Y703567D01*
X55243Y704109D01*
X55368Y704400D01*
X55576Y704692D01*
X55868Y704900D01*
X56159Y704942D01*
X56451Y704859D01*
X56659Y704650D01*
G01X53400Y715000D02*
Y711000D01*
X60800D01*
G01X59200Y696000D02*
X55200D01*
Y688600D01*
G01X34800Y684900D02*
Y697900D01*
G01X40700Y683800D02*
X54700D01*
G01X40700Y696800D02*
Y683800D01*
G01X54700Y696800D02*
X40700D01*
G01X54700Y683800D02*
Y696800D01*
G01X53313Y718950D02*
Y721950D01*
G01Y749850D02*
Y747850D01*
G01X38350Y739820D02*
X41350D01*
G01X39350Y729980D02*
X41350D01*
G01X68150Y726050D02*
Y721050D01*
X63150D01*
G01X40450Y743750D02*
Y748750D01*
X45450D01*
G01X40450Y726050D02*
Y721050D01*
X45450D01*
G01X32033Y753666D02*
Y751874D01*
X32200Y751499D01*
X32533Y751249D01*
X32950Y751166D01*
X33367Y751249D01*
X33700Y751499D01*
X33867Y751874D01*
Y753666D01*
G01X35258Y753249D02*
X35508Y753499D01*
X35800Y753624D01*
X36133Y753666D01*
X36550Y753583D01*
X36842Y753374D01*
X36925Y753124D01*
X36883Y752874D01*
X36717Y752666D01*
X35883Y752249D01*
X35508Y751958D01*
X35258Y751541D01*
X35175Y751166D01*
X36925D01*
G01X58800Y761100D02*
X62800D01*
Y768500D01*
G01X67000D02*
X63000D01*
Y761100D01*
G01X54700D02*
X58700D01*
Y768500D01*
G01X58600Y768800D02*
Y772800D01*
X51200D01*
G01X50300Y761200D02*
X54300D01*
Y768600D01*
G01X33000Y761400D02*
X37000D01*
Y768800D01*
G01Y761400D02*
X41000D01*
Y768800D01*
G01X88800Y196800D02*
X73500D01*
G01X101400Y221700D02*
Y196800D01*
X92100D01*
G01X90400Y201900D02*
X94400D01*
Y209300D01*
G01X86400Y201900D02*
X90400D01*
Y209300D01*
G01X75800Y207400D02*
X79800D01*
Y214800D01*
G01X71800Y207400D02*
X75800D01*
Y214800D01*
G01X85704Y230549D02*
Y225549D01*
G01X83787Y230549D02*
X87621D01*
G01X89637Y225549D02*
Y230549D01*
X91637D01*
X92304Y230299D01*
X92804Y229716D01*
X92971Y229049D01*
X92804Y228382D01*
X92387Y227882D01*
X91637Y227632D01*
X89637D01*
G01X94737Y225549D02*
Y230549D01*
X96904Y226382D01*
X99071Y230549D01*
Y225549D01*
G01X92700Y221700D02*
X101400D01*
G01X79200Y227700D02*
X83100D01*
Y221700D01*
X87600D01*
G01X69000Y227700D02*
X72600D01*
G01X90400Y213300D02*
X94400D01*
Y220700D01*
G01X71800Y218900D02*
X75800D01*
Y226300D01*
G01X86400Y213300D02*
X90400D01*
Y220700D01*
G01X75800Y218900D02*
X79800D01*
Y226300D01*
G01X83590Y234031D02*
X126190D01*
Y262031D01*
X83590D01*
Y234031D01*
G01X95900Y274000D02*
Y270000D01*
X103300D01*
G01X74170Y257220D02*
X78170D01*
Y264620D01*
G01X82300Y264600D02*
X78300D01*
Y257200D01*
G01X68547Y277183D02*
Y275183D01*
G01X78390Y277183D02*
Y274183D01*
G01X72994Y250350D02*
X72744Y250475D01*
X72452Y250558D01*
X72119D01*
X71744Y250433D01*
X71452Y250225D01*
X71244Y249975D01*
X71077Y249558D01*
X71035Y249183D01*
X71119Y248808D01*
X71244Y248558D01*
X71494Y248308D01*
X71785Y248141D01*
X72077Y248058D01*
X72369D01*
X72660Y248141D01*
X72910Y248266D01*
X73119Y248433D01*
G01X74219Y248058D02*
Y250558D01*
X76135Y248058D01*
Y250558D01*
G01X78277Y248058D02*
Y250558D01*
X77777Y250058D01*
G01Y248058D02*
X78777D01*
G01X81377D02*
Y250558D01*
X80877Y250058D01*
G01Y248058D02*
X81877D01*
G01X103200Y274300D02*
Y278300D01*
X95800D01*
G01X93607Y283582D02*
Y279582D01*
X101007D01*
G01X92217Y291010D02*
X94217D01*
G01X92217Y300853D02*
X95217D01*
G01X111520Y338350D02*
X106940D01*
Y347160D01*
X76200D01*
Y334090D01*
X71900D01*
G01X97670Y346211D02*
X93670D01*
Y338811D01*
G01X93600Y346100D02*
X89600D01*
Y338700D01*
G01X92217Y310695D02*
X94217D01*
G01X80358Y318617D02*
Y321617D01*
G01X70516Y318617D02*
Y320617D01*
G01X93200Y314600D02*
Y319600D01*
X88200D01*
G01X74291Y367075D02*
Y363075D01*
X81691D01*
G01X72591Y368599D02*
X68591D01*
Y361199D01*
G01X72654Y376260D02*
X68654D01*
Y368860D01*
G01X74105Y362727D02*
Y358727D01*
X81505D01*
G01X82760Y349817D02*
Y352317D01*
X83801D01*
X84135Y352192D01*
X84343Y352025D01*
X84426Y351692D01*
X84343Y351359D01*
X84093Y351150D01*
X83801Y351025D01*
X82760D01*
G01X83801D02*
X84426Y349817D01*
G01X85901Y351900D02*
X86151Y352150D01*
X86443Y352275D01*
X86776Y352317D01*
X87193Y352234D01*
X87485Y352025D01*
X87568Y351775D01*
X87526Y351525D01*
X87360Y351317D01*
X86526Y350900D01*
X86151Y350609D01*
X85901Y350192D01*
X85818Y349817D01*
X87568D01*
G01X89085Y350109D02*
X89376Y349900D01*
X89710Y349817D01*
X90043Y349900D01*
X90335Y350150D01*
X90543Y350525D01*
X90626Y350900D01*
Y351359D01*
X90543Y351734D01*
X90335Y352067D01*
X90085Y352234D01*
X89793Y352317D01*
X89460Y352234D01*
X89210Y352067D01*
X89043Y351817D01*
X88960Y351484D01*
X89043Y351192D01*
X89251Y350900D01*
X89501Y350734D01*
X89793Y350692D01*
X90126Y350775D01*
X90376Y350984D01*
X90626Y351359D01*
G01X93393Y349817D02*
Y352317D01*
X91851Y350525D01*
X93935D01*
G01X95201Y351900D02*
X95451Y352150D01*
X95743Y352275D01*
X96076Y352317D01*
X96493Y352234D01*
X96785Y352025D01*
X96868Y351775D01*
X96826Y351525D01*
X96660Y351317D01*
X95826Y350900D01*
X95451Y350609D01*
X95201Y350192D01*
X95118Y349817D01*
X96868D01*
G01X83700Y362000D02*
Y358000D01*
X91100D01*
G01X72543Y352737D02*
Y356737D01*
X65143D01*
G01X95678Y358882D02*
X95636Y358549D01*
X95470Y358257D01*
X95220Y358007D01*
X94928Y357840D01*
X94595Y357757D01*
X94261D01*
X93928Y357840D01*
X93636Y358007D01*
X93386Y358257D01*
X93220Y358549D01*
X93178Y358882D01*
X93220Y359215D01*
X93386Y359507D01*
X93636Y359757D01*
X93928Y359924D01*
X94261Y360007D01*
X94595D01*
X94928Y359924D01*
X95220Y359757D01*
X95470Y359507D01*
X95636Y359215D01*
X95678Y358882D01*
G01X95011Y359215D02*
X95678Y359715D01*
G01X93595Y361190D02*
X93345Y361440D01*
X93220Y361732D01*
X93178Y362065D01*
X93261Y362482D01*
X93470Y362774D01*
X93720Y362857D01*
X93970Y362815D01*
X94178Y362649D01*
X94595Y361815D01*
X94886Y361440D01*
X95303Y361190D01*
X95678Y361107D01*
Y362857D01*
G01X93178Y365082D02*
X93261Y364749D01*
X93470Y364499D01*
X93720Y364332D01*
X94053Y364207D01*
X94428Y364165D01*
X94803Y364207D01*
X95136Y364332D01*
X95386Y364499D01*
X95595Y364749D01*
X95678Y365082D01*
X95595Y365415D01*
X95386Y365665D01*
X95136Y365832D01*
X94803Y365957D01*
X94428Y365999D01*
X94053Y365957D01*
X93720Y365832D01*
X93470Y365665D01*
X93261Y365415D01*
X93178Y365082D01*
G01X73292Y381937D02*
Y367937D01*
G01D02*
X86292D01*
G01D02*
Y381937D01*
G01X99678Y358998D02*
X99636Y358665D01*
X99470Y358373D01*
X99220Y358123D01*
X98928Y357956D01*
X98595Y357873D01*
X98261D01*
X97928Y357956D01*
X97636Y358123D01*
X97386Y358373D01*
X97220Y358665D01*
X97178Y358998D01*
X97220Y359331D01*
X97386Y359623D01*
X97636Y359873D01*
X97928Y360040D01*
X98261Y360123D01*
X98595D01*
X98928Y360040D01*
X99220Y359873D01*
X99470Y359623D01*
X99636Y359331D01*
X99678Y358998D01*
G01X99011Y359331D02*
X99678Y359831D01*
G01X99178Y361181D02*
X99470Y361431D01*
X99636Y361765D01*
X99678Y362140D01*
X99636Y362473D01*
X99428Y362806D01*
X99178Y363015D01*
X98928Y363056D01*
X98636Y362973D01*
X98428Y362681D01*
X98345Y362390D01*
Y362015D01*
G01Y362390D02*
X98220Y362640D01*
X98011Y362848D01*
X97761Y362931D01*
X97511Y362848D01*
X97303Y362640D01*
X97178Y362265D01*
X97220Y361890D01*
X97386Y361515D01*
G01X98636Y364406D02*
X98345Y364698D01*
X98178Y364948D01*
X98095Y365281D01*
X98178Y365573D01*
X98345Y365781D01*
X98595Y365948D01*
X98886Y365990D01*
X99136Y365948D01*
X99386Y365781D01*
X99595Y365531D01*
X99678Y365240D01*
X99595Y364906D01*
X99345Y364615D01*
X98970Y364448D01*
X98553Y364406D01*
X98011Y364490D01*
X97720Y364615D01*
X97428Y364823D01*
X97220Y365115D01*
X97178Y365406D01*
X97261Y365698D01*
X97470Y365906D01*
G01X87468Y367957D02*
X100468D01*
G01X87468Y381957D02*
Y367957D01*
G01X87588Y409065D02*
X97588D01*
G01D02*
Y395665D01*
G01D02*
X87588D01*
G01D02*
Y409065D01*
G01X72144Y386123D02*
Y388623D01*
X73185D01*
X73519Y388498D01*
X73727Y388331D01*
X73810Y387998D01*
X73727Y387665D01*
X73477Y387456D01*
X73185Y387331D01*
X72144D01*
G01X73185D02*
X73810Y386123D01*
G01X75285Y388206D02*
X75535Y388456D01*
X75827Y388581D01*
X76160Y388623D01*
X76577Y388540D01*
X76869Y388331D01*
X76952Y388081D01*
X76910Y387831D01*
X76744Y387623D01*
X75910Y387206D01*
X75535Y386915D01*
X75285Y386498D01*
X75202Y386123D01*
X76952D01*
G01X78469Y386415D02*
X78760Y386206D01*
X79094Y386123D01*
X79427Y386206D01*
X79719Y386456D01*
X79927Y386831D01*
X80010Y387206D01*
Y387665D01*
X79927Y388040D01*
X79719Y388373D01*
X79469Y388540D01*
X79177Y388623D01*
X78844Y388540D01*
X78594Y388373D01*
X78427Y388123D01*
X78344Y387790D01*
X78427Y387498D01*
X78635Y387206D01*
X78885Y387040D01*
X79177Y386998D01*
X79510Y387081D01*
X79760Y387290D01*
X80010Y387665D01*
G01X82777Y386123D02*
Y388623D01*
X81235Y386831D01*
X83319D01*
G01X84460Y386623D02*
X84710Y386331D01*
X85044Y386165D01*
X85419Y386123D01*
X85752Y386165D01*
X86085Y386373D01*
X86294Y386623D01*
X86335Y386873D01*
X86252Y387165D01*
X85960Y387373D01*
X85669Y387456D01*
X85294D01*
G01X85669D02*
X85919Y387581D01*
X86127Y387790D01*
X86210Y388040D01*
X86127Y388290D01*
X85919Y388498D01*
X85544Y388623D01*
X85169Y388581D01*
X84794Y388415D01*
G01X71579Y400403D02*
X69079D01*
Y401444D01*
X69204Y401778D01*
X69371Y401986D01*
X69704Y402069D01*
X70037Y401986D01*
X70246Y401736D01*
X70371Y401444D01*
Y400403D01*
G01Y401444D02*
X71579Y402069D01*
G01X69496Y403544D02*
X69246Y403794D01*
X69121Y404086D01*
X69079Y404419D01*
X69162Y404836D01*
X69371Y405128D01*
X69621Y405211D01*
X69871Y405169D01*
X70079Y405003D01*
X70496Y404169D01*
X70787Y403794D01*
X71204Y403544D01*
X71579Y403461D01*
Y405211D01*
G01X71287Y406728D02*
X71496Y407019D01*
X71579Y407353D01*
X71496Y407686D01*
X71246Y407978D01*
X70871Y408186D01*
X70496Y408269D01*
X70037D01*
X69662Y408186D01*
X69329Y407978D01*
X69162Y407728D01*
X69079Y407436D01*
X69162Y407103D01*
X69329Y406853D01*
X69579Y406686D01*
X69912Y406603D01*
X70204Y406686D01*
X70496Y406894D01*
X70662Y407144D01*
X70704Y407436D01*
X70621Y407769D01*
X70412Y408019D01*
X70037Y408269D01*
G01X71579Y411036D02*
X69079D01*
X70871Y409494D01*
Y411578D01*
G01X71204Y412719D02*
X71412Y412969D01*
X71537Y413261D01*
X71579Y413636D01*
X71496Y414011D01*
X71329Y414303D01*
X71037Y414511D01*
X70704Y414553D01*
X70371Y414469D01*
X70162Y414261D01*
X69996Y413969D01*
X69954Y413678D01*
X69996Y413386D01*
X70162Y413011D01*
X69079Y413136D01*
Y414261D01*
G01X82000Y408900D02*
X78000D01*
Y401500D01*
G01X74953Y400458D02*
X72453D01*
Y401499D01*
X72578Y401833D01*
X72745Y402041D01*
X73078Y402124D01*
X73411Y402041D01*
X73620Y401791D01*
X73745Y401499D01*
Y400458D01*
G01Y401499D02*
X74953Y402124D01*
G01X72870Y403599D02*
X72620Y403849D01*
X72495Y404141D01*
X72453Y404474D01*
X72536Y404891D01*
X72745Y405183D01*
X72995Y405266D01*
X73245Y405224D01*
X73453Y405058D01*
X73870Y404224D01*
X74161Y403849D01*
X74578Y403599D01*
X74953Y403516D01*
Y405266D01*
G01X74661Y406783D02*
X74870Y407074D01*
X74953Y407408D01*
X74870Y407741D01*
X74620Y408033D01*
X74245Y408241D01*
X73870Y408324D01*
X73411D01*
X73036Y408241D01*
X72703Y408033D01*
X72536Y407783D01*
X72453Y407491D01*
X72536Y407158D01*
X72703Y406908D01*
X72953Y406741D01*
X73286Y406658D01*
X73578Y406741D01*
X73870Y406949D01*
X74036Y407199D01*
X74078Y407491D01*
X73995Y407824D01*
X73786Y408074D01*
X73411Y408324D01*
G01X74953Y411091D02*
X72453D01*
X74245Y409549D01*
Y411633D01*
G01X73911Y412899D02*
X73620Y413191D01*
X73453Y413441D01*
X73370Y413774D01*
X73453Y414066D01*
X73620Y414274D01*
X73870Y414441D01*
X74161Y414483D01*
X74411Y414441D01*
X74661Y414274D01*
X74870Y414024D01*
X74953Y413733D01*
X74870Y413399D01*
X74620Y413108D01*
X74245Y412941D01*
X73828Y412899D01*
X73286Y412983D01*
X72995Y413108D01*
X72703Y413316D01*
X72495Y413608D01*
X72453Y413899D01*
X72536Y414191D01*
X72745Y414399D01*
G01X86274Y404541D02*
X82274D01*
Y397141D01*
G01X78990Y394665D02*
Y390665D01*
X86390D01*
G01X68154Y389362D02*
X68029Y389112D01*
X67946Y388820D01*
Y388487D01*
X68071Y388112D01*
X68279Y387820D01*
X68529Y387612D01*
X68946Y387445D01*
X69321Y387403D01*
X69696Y387487D01*
X69946Y387612D01*
X70196Y387862D01*
X70363Y388153D01*
X70446Y388445D01*
Y388737D01*
X70363Y389028D01*
X70238Y389278D01*
X70071Y389487D01*
G01X68363Y390753D02*
X68113Y391003D01*
X67988Y391295D01*
X67946Y391628D01*
X68029Y392045D01*
X68238Y392337D01*
X68488Y392420D01*
X68738Y392378D01*
X68946Y392212D01*
X69363Y391378D01*
X69654Y391003D01*
X70071Y390753D01*
X70446Y390670D01*
Y392420D01*
G01Y394562D02*
X69904Y394645D01*
X69446Y394770D01*
X69029Y394937D01*
X68571Y395145D01*
X67946Y395478D01*
Y393812D01*
G01X69404Y396953D02*
X69113Y397245D01*
X68946Y397495D01*
X68863Y397828D01*
X68946Y398120D01*
X69113Y398328D01*
X69363Y398495D01*
X69654Y398537D01*
X69904Y398495D01*
X70154Y398328D01*
X70363Y398078D01*
X70446Y397787D01*
X70363Y397453D01*
X70113Y397162D01*
X69738Y396995D01*
X69321Y396953D01*
X68779Y397037D01*
X68488Y397162D01*
X68196Y397370D01*
X67988Y397662D01*
X67946Y397953D01*
X68029Y398245D01*
X68238Y398453D01*
G01X95527Y413828D02*
X95277Y413953D01*
X94985Y414036D01*
X94652D01*
X94277Y413911D01*
X93985Y413703D01*
X93777Y413453D01*
X93610Y413036D01*
X93568Y412661D01*
X93652Y412286D01*
X93777Y412036D01*
X94027Y411786D01*
X94318Y411619D01*
X94610Y411536D01*
X94902D01*
X95193Y411619D01*
X95443Y411744D01*
X95652Y411911D01*
G01X96918Y413619D02*
X97168Y413869D01*
X97460Y413994D01*
X97793Y414036D01*
X98210Y413953D01*
X98502Y413744D01*
X98585Y413494D01*
X98543Y413244D01*
X98377Y413036D01*
X97543Y412619D01*
X97168Y412328D01*
X96918Y411911D01*
X96835Y411536D01*
X98585D01*
G01X100810D02*
X101102Y411578D01*
X101435Y411703D01*
X101643Y411911D01*
X101727Y412203D01*
X101643Y412494D01*
X101393Y412744D01*
X101018Y412869D01*
X100602D01*
X100352Y412953D01*
X100143Y413161D01*
X100060Y413453D01*
X100185Y413744D01*
X100477Y413953D01*
X100810Y414036D01*
X101143Y413953D01*
X101435Y413744D01*
X101560Y413453D01*
X101477Y413161D01*
X101268Y412953D01*
X101018Y412869D01*
X100602D01*
X100227Y412744D01*
X99977Y412494D01*
X99893Y412203D01*
X99977Y411911D01*
X100185Y411703D01*
X100518Y411578D01*
X100810Y411536D01*
G01X103827D02*
X103910Y412078D01*
X104035Y412536D01*
X104202Y412953D01*
X104410Y413411D01*
X104743Y414036D01*
X103077D01*
G01X86292Y381937D02*
X73292D01*
G01X100468Y381957D02*
X87468D01*
G01X89277Y412483D02*
X86777D01*
Y413524D01*
X86902Y413858D01*
X87069Y414066D01*
X87402Y414149D01*
X87735Y414066D01*
X87944Y413816D01*
X88069Y413524D01*
Y412483D01*
G01Y413524D02*
X89277Y414149D01*
G01X88985Y415708D02*
X89194Y415999D01*
X89277Y416333D01*
X89194Y416666D01*
X88944Y416958D01*
X88569Y417166D01*
X88194Y417249D01*
X87735D01*
X87360Y417166D01*
X87027Y416958D01*
X86860Y416708D01*
X86777Y416416D01*
X86860Y416083D01*
X87027Y415833D01*
X87277Y415666D01*
X87610Y415583D01*
X87902Y415666D01*
X88194Y415874D01*
X88360Y416124D01*
X88402Y416416D01*
X88319Y416749D01*
X88110Y416999D01*
X87735Y417249D01*
G01X86777Y419516D02*
X86860Y419183D01*
X87069Y418933D01*
X87319Y418766D01*
X87652Y418641D01*
X88027Y418599D01*
X88402Y418641D01*
X88735Y418766D01*
X88985Y418933D01*
X89194Y419183D01*
X89277Y419516D01*
X89194Y419849D01*
X88985Y420099D01*
X88735Y420266D01*
X88402Y420391D01*
X88027Y420433D01*
X87652Y420391D01*
X87319Y420266D01*
X87069Y420099D01*
X86860Y419849D01*
X86777Y419516D01*
G01X89277Y423116D02*
X86777D01*
X88569Y421574D01*
Y423658D01*
G01X89277Y425633D02*
X88735Y425716D01*
X88277Y425841D01*
X87860Y426008D01*
X87402Y426216D01*
X86777Y426549D01*
Y424883D01*
G01X98046Y428730D02*
X94046D01*
Y421330D01*
G01X94043Y428743D02*
X98043D01*
Y436143D01*
G01X85895Y412504D02*
X83395D01*
Y413504D01*
X83520Y413837D01*
X83812Y414087D01*
X84145Y414170D01*
X84478Y414087D01*
X84728Y413879D01*
X84853Y413504D01*
Y412504D01*
G01X85895Y415604D02*
X83395D01*
Y416645D01*
X83520Y416979D01*
X83687Y417187D01*
X84020Y417270D01*
X84353Y417187D01*
X84562Y416937D01*
X84687Y416645D01*
Y415604D01*
G01Y416645D02*
X85895Y417270D01*
G01Y419454D02*
X85353Y419537D01*
X84895Y419662D01*
X84478Y419829D01*
X84020Y420037D01*
X83395Y420370D01*
Y418704D01*
G01Y422637D02*
X83478Y422304D01*
X83687Y422054D01*
X83937Y421887D01*
X84270Y421762D01*
X84645Y421720D01*
X85020Y421762D01*
X85353Y421887D01*
X85603Y422054D01*
X85812Y422304D01*
X85895Y422637D01*
X85812Y422970D01*
X85603Y423220D01*
X85353Y423387D01*
X85020Y423512D01*
X84645Y423554D01*
X84270Y423512D01*
X83937Y423387D01*
X83687Y423220D01*
X83478Y422970D01*
X83395Y422637D01*
G01X70500Y418800D02*
X74500D01*
Y426200D01*
G01X79025Y412886D02*
X76525D01*
Y413886D01*
X76650Y414219D01*
X76942Y414469D01*
X77275Y414552D01*
X77608Y414469D01*
X77858Y414261D01*
X77983Y413886D01*
Y412886D01*
G01X79025Y415986D02*
X76525D01*
Y417027D01*
X76650Y417361D01*
X76817Y417569D01*
X77150Y417652D01*
X77483Y417569D01*
X77692Y417319D01*
X77817Y417027D01*
Y415986D01*
G01Y417027D02*
X79025Y417652D01*
G01X78733Y419211D02*
X78942Y419502D01*
X79025Y419836D01*
X78942Y420169D01*
X78692Y420461D01*
X78317Y420669D01*
X77942Y420752D01*
X77483D01*
X77108Y420669D01*
X76775Y420461D01*
X76608Y420211D01*
X76525Y419919D01*
X76608Y419586D01*
X76775Y419336D01*
X77025Y419169D01*
X77358Y419086D01*
X77650Y419169D01*
X77942Y419377D01*
X78108Y419627D01*
X78150Y419919D01*
X78067Y420252D01*
X77858Y420502D01*
X77483Y420752D01*
G01X79025Y423019D02*
X76525D01*
X77025Y422519D01*
G01X79025D02*
Y423519D01*
G01X92673Y412661D02*
X90173D01*
Y413702D01*
X90298Y414036D01*
X90465Y414244D01*
X90798Y414327D01*
X91131Y414244D01*
X91340Y413994D01*
X91465Y413702D01*
Y412661D01*
G01Y413702D02*
X92673Y414327D01*
G01X92381Y415886D02*
X92590Y416177D01*
X92673Y416511D01*
X92590Y416844D01*
X92340Y417136D01*
X91965Y417344D01*
X91590Y417427D01*
X91131D01*
X90756Y417344D01*
X90423Y417136D01*
X90256Y416886D01*
X90173Y416594D01*
X90256Y416261D01*
X90423Y416011D01*
X90673Y415844D01*
X91006Y415761D01*
X91298Y415844D01*
X91590Y416052D01*
X91756Y416302D01*
X91798Y416594D01*
X91715Y416927D01*
X91506Y417177D01*
X91131Y417427D01*
G01X90173Y419694D02*
X90256Y419361D01*
X90465Y419111D01*
X90715Y418944D01*
X91048Y418819D01*
X91423Y418777D01*
X91798Y418819D01*
X92131Y418944D01*
X92381Y419111D01*
X92590Y419361D01*
X92673Y419694D01*
X92590Y420027D01*
X92381Y420277D01*
X92131Y420444D01*
X91798Y420569D01*
X91423Y420611D01*
X91048Y420569D01*
X90715Y420444D01*
X90465Y420277D01*
X90256Y420027D01*
X90173Y419694D01*
G01X92673Y423294D02*
X90173D01*
X91965Y421752D01*
Y423836D01*
G01X92298Y424977D02*
X92506Y425227D01*
X92631Y425519D01*
X92673Y425894D01*
X92590Y426269D01*
X92423Y426561D01*
X92131Y426769D01*
X91798Y426811D01*
X91465Y426727D01*
X91256Y426519D01*
X91090Y426227D01*
X91048Y425936D01*
X91090Y425644D01*
X91256Y425269D01*
X90173Y425394D01*
Y426519D01*
G01X82587Y412631D02*
X80087D01*
Y413631D01*
X80212Y413964D01*
X80504Y414214D01*
X80837Y414297D01*
X81170Y414214D01*
X81420Y414006D01*
X81545Y413631D01*
Y412631D01*
G01X80295Y417481D02*
X80170Y417231D01*
X80087Y416939D01*
Y416606D01*
X80212Y416231D01*
X80420Y415939D01*
X80670Y415731D01*
X81087Y415564D01*
X81462Y415522D01*
X81837Y415606D01*
X82087Y415731D01*
X82337Y415981D01*
X82504Y416272D01*
X82587Y416564D01*
Y416856D01*
X82504Y417147D01*
X82379Y417397D01*
X82212Y417606D01*
G01X82587Y419581D02*
X82045Y419664D01*
X81587Y419789D01*
X81170Y419956D01*
X80712Y420164D01*
X80087Y420497D01*
Y418831D01*
G01X82587Y422764D02*
X82545Y423056D01*
X82420Y423389D01*
X82212Y423597D01*
X81920Y423681D01*
X81629Y423597D01*
X81379Y423347D01*
X81254Y422972D01*
Y422556D01*
X81170Y422306D01*
X80962Y422097D01*
X80670Y422014D01*
X80379Y422139D01*
X80170Y422431D01*
X80087Y422764D01*
X80170Y423097D01*
X80379Y423389D01*
X80670Y423514D01*
X80962Y423431D01*
X81170Y423222D01*
X81254Y422972D01*
Y422556D01*
X81379Y422181D01*
X81629Y421931D01*
X81920Y421847D01*
X82212Y421931D01*
X82420Y422139D01*
X82545Y422472D01*
X82587Y422764D01*
G01X95531Y417244D02*
X95281Y417369D01*
X94989Y417452D01*
X94656D01*
X94281Y417327D01*
X93989Y417119D01*
X93781Y416869D01*
X93614Y416452D01*
X93572Y416077D01*
X93656Y415702D01*
X93781Y415452D01*
X94031Y415202D01*
X94322Y415035D01*
X94614Y414952D01*
X94906D01*
X95197Y415035D01*
X95447Y415160D01*
X95656Y415327D01*
G01X96922Y417035D02*
X97172Y417285D01*
X97464Y417410D01*
X97797Y417452D01*
X98214Y417369D01*
X98506Y417160D01*
X98589Y416910D01*
X98547Y416660D01*
X98381Y416452D01*
X97547Y416035D01*
X97172Y415744D01*
X96922Y415327D01*
X96839Y414952D01*
X98589D01*
G01X100814D02*
X101106Y414994D01*
X101439Y415119D01*
X101647Y415327D01*
X101731Y415619D01*
X101647Y415910D01*
X101397Y416160D01*
X101022Y416285D01*
X100606D01*
X100356Y416369D01*
X100147Y416577D01*
X100064Y416869D01*
X100189Y417160D01*
X100481Y417369D01*
X100814Y417452D01*
X101147Y417369D01*
X101439Y417160D01*
X101564Y416869D01*
X101481Y416577D01*
X101272Y416369D01*
X101022Y416285D01*
X100606D01*
X100231Y416160D01*
X99981Y415910D01*
X99897Y415619D01*
X99981Y415327D01*
X100189Y415119D01*
X100522Y414994D01*
X100814Y414952D01*
G01X103122Y415994D02*
X103414Y416285D01*
X103664Y416452D01*
X103997Y416535D01*
X104289Y416452D01*
X104497Y416285D01*
X104664Y416035D01*
X104706Y415744D01*
X104664Y415494D01*
X104497Y415244D01*
X104247Y415035D01*
X103956Y414952D01*
X103622Y415035D01*
X103331Y415285D01*
X103164Y415660D01*
X103122Y416077D01*
X103206Y416619D01*
X103331Y416910D01*
X103539Y417202D01*
X103831Y417410D01*
X104122Y417452D01*
X104414Y417369D01*
X104622Y417160D01*
G01X95243Y450029D02*
X92743D01*
Y451070D01*
X92868Y451404D01*
X93035Y451612D01*
X93368Y451695D01*
X93701Y451612D01*
X93910Y451362D01*
X94035Y451070D01*
Y450029D01*
G01Y451070D02*
X95243Y451695D01*
G01X93160Y453170D02*
X92910Y453420D01*
X92785Y453712D01*
X92743Y454045D01*
X92826Y454462D01*
X93035Y454754D01*
X93285Y454837D01*
X93535Y454795D01*
X93743Y454629D01*
X94160Y453795D01*
X94451Y453420D01*
X94868Y453170D01*
X95243Y453087D01*
Y454837D01*
G01X94743Y456145D02*
X95035Y456395D01*
X95201Y456729D01*
X95243Y457104D01*
X95201Y457437D01*
X94993Y457770D01*
X94743Y457979D01*
X94493Y458020D01*
X94201Y457937D01*
X93993Y457645D01*
X93910Y457354D01*
Y456979D01*
G01Y457354D02*
X93785Y457604D01*
X93576Y457812D01*
X93326Y457895D01*
X93076Y457812D01*
X92868Y457604D01*
X92743Y457229D01*
X92785Y456854D01*
X92951Y456479D01*
G01X95243Y460662D02*
X92743D01*
X94535Y459120D01*
Y461204D01*
G01X94500Y475200D02*
X90500D01*
Y467800D01*
G01X84289Y462351D02*
Y464851D01*
X85330D01*
X85664Y464726D01*
X85872Y464559D01*
X85955Y464226D01*
X85872Y463893D01*
X85622Y463684D01*
X85330Y463559D01*
X84289D01*
G01X85330D02*
X85955Y462351D01*
G01X87305Y462726D02*
X87555Y462518D01*
X87847Y462393D01*
X88222Y462351D01*
X88597Y462434D01*
X88889Y462601D01*
X89097Y462893D01*
X89139Y463226D01*
X89055Y463559D01*
X88847Y463768D01*
X88555Y463934D01*
X88264Y463976D01*
X87972Y463934D01*
X87597Y463768D01*
X87722Y464851D01*
X88847D01*
G01X91822Y462351D02*
Y464851D01*
X90280Y463059D01*
X92364D01*
G01X94422Y462351D02*
Y464851D01*
X93922Y464351D01*
G01Y462351D02*
X94922D01*
G01X91649Y479241D02*
Y475241D01*
X99049D01*
G01X99659Y450153D02*
X97159D01*
Y451194D01*
X97284Y451528D01*
X97451Y451736D01*
X97784Y451819D01*
X98117Y451736D01*
X98326Y451486D01*
X98451Y451194D01*
Y450153D01*
G01Y451194D02*
X99659Y451819D01*
G01X98617Y453294D02*
X98326Y453586D01*
X98159Y453836D01*
X98076Y454169D01*
X98159Y454461D01*
X98326Y454669D01*
X98576Y454836D01*
X98867Y454878D01*
X99117Y454836D01*
X99367Y454669D01*
X99576Y454419D01*
X99659Y454128D01*
X99576Y453794D01*
X99326Y453503D01*
X98951Y453336D01*
X98534Y453294D01*
X97992Y453378D01*
X97701Y453503D01*
X97409Y453711D01*
X97201Y454003D01*
X97159Y454294D01*
X97242Y454586D01*
X97451Y454794D01*
G01X99659Y457186D02*
X99617Y457478D01*
X99492Y457811D01*
X99284Y458019D01*
X98992Y458103D01*
X98701Y458019D01*
X98451Y457769D01*
X98326Y457394D01*
Y456978D01*
X98242Y456728D01*
X98034Y456519D01*
X97742Y456436D01*
X97451Y456561D01*
X97242Y456853D01*
X97159Y457186D01*
X97242Y457519D01*
X97451Y457811D01*
X97742Y457936D01*
X98034Y457853D01*
X98242Y457644D01*
X98326Y457394D01*
Y456978D01*
X98451Y456603D01*
X98701Y456353D01*
X98992Y456269D01*
X99284Y456353D01*
X99492Y456561D01*
X99617Y456894D01*
X99659Y457186D01*
G01Y460786D02*
X97159D01*
X98951Y459244D01*
Y461328D01*
G01X98700Y475100D02*
X94700D01*
Y467700D01*
G01X66700Y475317D02*
X64200D01*
Y476358D01*
X64325Y476692D01*
X64492Y476900D01*
X64825Y476983D01*
X65158Y476900D01*
X65367Y476650D01*
X65492Y476358D01*
Y475317D01*
G01Y476358D02*
X66700Y476983D01*
G01X65658Y478458D02*
X65367Y478750D01*
X65200Y479000D01*
X65117Y479333D01*
X65200Y479625D01*
X65367Y479833D01*
X65617Y480000D01*
X65908Y480042D01*
X66158Y480000D01*
X66408Y479833D01*
X66617Y479583D01*
X66700Y479292D01*
X66617Y478958D01*
X66367Y478667D01*
X65992Y478500D01*
X65575Y478458D01*
X65033Y478542D01*
X64742Y478667D01*
X64450Y478875D01*
X64242Y479167D01*
X64200Y479458D01*
X64283Y479750D01*
X64492Y479958D01*
G01X64200Y482350D02*
X64283Y482017D01*
X64492Y481767D01*
X64742Y481600D01*
X65075Y481475D01*
X65450Y481433D01*
X65825Y481475D01*
X66158Y481600D01*
X66408Y481767D01*
X66617Y482017D01*
X66700Y482350D01*
X66617Y482683D01*
X66408Y482933D01*
X66158Y483100D01*
X65825Y483225D01*
X65450Y483267D01*
X65075Y483225D01*
X64742Y483100D01*
X64492Y482933D01*
X64283Y482683D01*
X64200Y482350D01*
G01X66700Y485450D02*
X64200D01*
X64700Y484950D01*
G01X66700D02*
Y485950D01*
G01X96034Y490124D02*
Y492624D01*
X97075D01*
X97409Y492499D01*
X97617Y492332D01*
X97700Y491999D01*
X97617Y491666D01*
X97367Y491457D01*
X97075Y491332D01*
X96034D01*
G01X97075D02*
X97700Y490124D01*
G01X99884D02*
X99967Y490666D01*
X100092Y491124D01*
X100259Y491541D01*
X100467Y491999D01*
X100800Y492624D01*
X99134D01*
G01X102150Y490624D02*
X102400Y490332D01*
X102734Y490166D01*
X103109Y490124D01*
X103442Y490166D01*
X103775Y490374D01*
X103984Y490624D01*
X104025Y490874D01*
X103942Y491166D01*
X103650Y491374D01*
X103359Y491457D01*
X102984D01*
G01X103359D02*
X103609Y491582D01*
X103817Y491791D01*
X103900Y492041D01*
X103817Y492291D01*
X103609Y492499D01*
X103234Y492624D01*
X102859Y492582D01*
X102484Y492416D01*
G01X76200Y512500D02*
Y516500D01*
X68800D01*
G01X76200Y504500D02*
Y508500D01*
X68800D01*
G01X77569Y515090D02*
Y511090D01*
X84969D01*
G01X78444Y510831D02*
Y506831D01*
X85844D01*
G01X90300Y508000D02*
Y504000D01*
X97700D01*
G01X78444Y506831D02*
Y502831D01*
X85844D01*
G01X76200Y508500D02*
Y512500D01*
X68800D01*
G01X69332Y497442D02*
X69082Y497567D01*
X68790Y497650D01*
X68457D01*
X68082Y497525D01*
X67790Y497317D01*
X67582Y497067D01*
X67415Y496650D01*
X67373Y496275D01*
X67457Y495900D01*
X67582Y495650D01*
X67832Y495400D01*
X68123Y495233D01*
X68415Y495150D01*
X68707D01*
X68998Y495233D01*
X69248Y495358D01*
X69457Y495525D01*
G01X70598Y495650D02*
X70848Y495358D01*
X71182Y495192D01*
X71557Y495150D01*
X71890Y495192D01*
X72223Y495400D01*
X72432Y495650D01*
X72473Y495900D01*
X72390Y496192D01*
X72098Y496400D01*
X71807Y496483D01*
X71432D01*
G01X71807D02*
X72057Y496608D01*
X72265Y496817D01*
X72348Y497067D01*
X72265Y497317D01*
X72057Y497525D01*
X71682Y497650D01*
X71307Y497608D01*
X70932Y497442D01*
G01X73823Y496192D02*
X74115Y496483D01*
X74365Y496650D01*
X74698Y496733D01*
X74990Y496650D01*
X75198Y496483D01*
X75365Y496233D01*
X75407Y495942D01*
X75365Y495692D01*
X75198Y495442D01*
X74948Y495233D01*
X74657Y495150D01*
X74323Y495233D01*
X74032Y495483D01*
X73865Y495858D01*
X73823Y496275D01*
X73907Y496817D01*
X74032Y497108D01*
X74240Y497400D01*
X74532Y497608D01*
X74823Y497650D01*
X75115Y497567D01*
X75323Y497358D01*
G01X77632Y495150D02*
X77715Y495692D01*
X77840Y496150D01*
X78007Y496567D01*
X78215Y497025D01*
X78548Y497650D01*
X76882D01*
G01X69332Y493642D02*
X69082Y493767D01*
X68790Y493850D01*
X68457D01*
X68082Y493725D01*
X67790Y493517D01*
X67582Y493267D01*
X67415Y492850D01*
X67373Y492475D01*
X67457Y492100D01*
X67582Y491850D01*
X67832Y491600D01*
X68123Y491433D01*
X68415Y491350D01*
X68707D01*
X68998Y491433D01*
X69248Y491558D01*
X69457Y491725D01*
G01X70598Y491850D02*
X70848Y491558D01*
X71182Y491392D01*
X71557Y491350D01*
X71890Y491392D01*
X72223Y491600D01*
X72432Y491850D01*
X72473Y492100D01*
X72390Y492392D01*
X72098Y492600D01*
X71807Y492683D01*
X71432D01*
G01X71807D02*
X72057Y492808D01*
X72265Y493017D01*
X72348Y493267D01*
X72265Y493517D01*
X72057Y493725D01*
X71682Y493850D01*
X71307Y493808D01*
X70932Y493642D01*
G01X73823Y492392D02*
X74115Y492683D01*
X74365Y492850D01*
X74698Y492933D01*
X74990Y492850D01*
X75198Y492683D01*
X75365Y492433D01*
X75407Y492142D01*
X75365Y491892D01*
X75198Y491642D01*
X74948Y491433D01*
X74657Y491350D01*
X74323Y491433D01*
X74032Y491683D01*
X73865Y492058D01*
X73823Y492475D01*
X73907Y493017D01*
X74032Y493308D01*
X74240Y493600D01*
X74532Y493808D01*
X74823Y493850D01*
X75115Y493767D01*
X75323Y493558D01*
G01X77715Y491350D02*
X78007Y491392D01*
X78340Y491517D01*
X78548Y491725D01*
X78632Y492017D01*
X78548Y492308D01*
X78298Y492558D01*
X77923Y492683D01*
X77507D01*
X77257Y492767D01*
X77048Y492975D01*
X76965Y493267D01*
X77090Y493558D01*
X77382Y493767D01*
X77715Y493850D01*
X78048Y493767D01*
X78340Y493558D01*
X78465Y493267D01*
X78382Y492975D01*
X78173Y492767D01*
X77923Y492683D01*
X77507D01*
X77132Y492558D01*
X76882Y492308D01*
X76798Y492017D01*
X76882Y491725D01*
X77090Y491517D01*
X77423Y491392D01*
X77715Y491350D01*
G01X90300Y528500D02*
Y524500D01*
X97700D01*
G01X90300D02*
Y520500D01*
X97700D01*
G01X90300Y532500D02*
Y528500D01*
X97700D01*
G01X77569Y519090D02*
Y515090D01*
X84969D01*
G01X90300Y536500D02*
Y532500D01*
X97700D01*
G01X90300Y520500D02*
Y516500D01*
X97700D01*
G01X90300Y540500D02*
Y536500D01*
X97700D01*
G01X86400Y527300D02*
Y531300D01*
X79000D01*
G01X72340Y525270D02*
Y529270D01*
X64940D01*
G01X86200Y540300D02*
Y544300D01*
X78800D01*
G01X86200D02*
Y548300D01*
X78800D01*
G01Y536300D02*
Y532300D01*
X86200D01*
G01X78800Y540300D02*
Y536300D01*
X86200D01*
G01X65720Y537931D02*
Y533931D01*
X73120D01*
G01X65720Y533831D02*
Y529831D01*
X73120D01*
G01X90756Y574657D02*
X90714Y574324D01*
X90548Y574032D01*
X90298Y573782D01*
X90006Y573615D01*
X89673Y573532D01*
X89339D01*
X89006Y573615D01*
X88714Y573782D01*
X88464Y574032D01*
X88298Y574324D01*
X88256Y574657D01*
X88298Y574990D01*
X88464Y575282D01*
X88714Y575532D01*
X89006Y575699D01*
X89339Y575782D01*
X89673D01*
X90006Y575699D01*
X90298Y575532D01*
X90548Y575282D01*
X90714Y574990D01*
X90756Y574657D01*
G01X90423Y576882D02*
X90631Y577215D01*
X90756Y577590D01*
Y577924D01*
X90631Y578257D01*
X90423Y578507D01*
X90131Y578632D01*
X89839Y578549D01*
X89589Y578340D01*
X89423Y577965D01*
X89339Y577465D01*
X89173Y577174D01*
X88881Y577049D01*
X88589Y577132D01*
X88381Y577340D01*
X88256Y577632D01*
Y577924D01*
X88339Y578215D01*
X88548Y578465D01*
G01X88464Y581774D02*
X88339Y581524D01*
X88256Y581232D01*
Y580899D01*
X88381Y580524D01*
X88589Y580232D01*
X88839Y580024D01*
X89256Y579857D01*
X89631Y579815D01*
X90006Y579899D01*
X90256Y580024D01*
X90506Y580274D01*
X90673Y580565D01*
X90756Y580857D01*
Y581149D01*
X90673Y581440D01*
X90548Y581690D01*
X90381Y581899D01*
G01X90756Y583957D02*
X88256D01*
X88756Y583457D01*
G01X90756D02*
Y584457D01*
G01X104550Y589350D02*
Y572650D01*
X92450D01*
Y589350D01*
X104550D01*
G01X103700Y567500D02*
Y571500D01*
X96300D01*
G01X86100Y548400D02*
Y552400D01*
X78700D01*
G01X86200Y552500D02*
Y556500D01*
X78800D01*
G01X86200D02*
Y560500D01*
X78800D01*
G01X71800Y584000D02*
Y580000D01*
X79200D01*
G01X94600Y608584D02*
X96392D01*
X96767Y608751D01*
X97017Y609084D01*
X97100Y609501D01*
X97017Y609918D01*
X96767Y610251D01*
X96392Y610418D01*
X94600D01*
G01X97100Y612601D02*
X97058Y612893D01*
X96933Y613226D01*
X96725Y613434D01*
X96433Y613518D01*
X96142Y613434D01*
X95892Y613184D01*
X95767Y612809D01*
Y612393D01*
X95683Y612143D01*
X95475Y611934D01*
X95183Y611851D01*
X94892Y611976D01*
X94683Y612268D01*
X94600Y612601D01*
X94683Y612934D01*
X94892Y613226D01*
X95183Y613351D01*
X95475Y613268D01*
X95683Y613059D01*
X95767Y612809D01*
Y612393D01*
X95892Y612018D01*
X96142Y611768D01*
X96433Y611684D01*
X96725Y611768D01*
X96933Y611976D01*
X97058Y612309D01*
X97100Y612601D01*
G01X94600Y615701D02*
X94683Y615368D01*
X94892Y615118D01*
X95142Y614951D01*
X95475Y614826D01*
X95850Y614784D01*
X96225Y614826D01*
X96558Y614951D01*
X96808Y615118D01*
X97017Y615368D01*
X97100Y615701D01*
X97017Y616034D01*
X96808Y616284D01*
X96558Y616451D01*
X96225Y616576D01*
X95850Y616618D01*
X95475Y616576D01*
X95142Y616451D01*
X94892Y616284D01*
X94683Y616034D01*
X94600Y615701D01*
G01X81800Y593000D02*
Y603000D01*
G01D02*
X95200D01*
G01D02*
Y593000D01*
G01D02*
X81800D01*
G01X69269Y602920D02*
X79269D01*
G01D02*
Y589520D01*
G01D02*
X69269D01*
G01D02*
Y602920D01*
G01X103700Y590500D02*
Y594500D01*
X96300D01*
G01X82900Y580300D02*
X86900D01*
Y587700D01*
G01X90000Y612300D02*
X86000D01*
Y604900D01*
G01X78300Y608500D02*
Y604500D01*
X85700D01*
G01X64000Y588800D02*
X68000D01*
Y596200D01*
G01X74000Y611700D02*
X70000D01*
Y604300D01*
G01X78000Y611700D02*
X74000D01*
Y604300D01*
G01X68000Y603700D02*
X64000D01*
Y596300D01*
G01X79200Y584000D02*
Y588000D01*
X71800D01*
G01X96777Y606639D02*
X96527Y606764D01*
X96235Y606847D01*
X95902D01*
X95527Y606722D01*
X95235Y606514D01*
X95027Y606264D01*
X94860Y605847D01*
X94818Y605472D01*
X94902Y605097D01*
X95027Y604847D01*
X95277Y604597D01*
X95568Y604430D01*
X95860Y604347D01*
X96152D01*
X96443Y604430D01*
X96693Y604555D01*
X96902Y604722D01*
G01X98168Y606430D02*
X98418Y606680D01*
X98710Y606805D01*
X99043Y606847D01*
X99460Y606764D01*
X99752Y606555D01*
X99835Y606305D01*
X99793Y606055D01*
X99627Y605847D01*
X98793Y605430D01*
X98418Y605139D01*
X98168Y604722D01*
X98085Y604347D01*
X99835D01*
G01X101268Y605389D02*
X101560Y605680D01*
X101810Y605847D01*
X102143Y605930D01*
X102435Y605847D01*
X102643Y605680D01*
X102810Y605430D01*
X102852Y605139D01*
X102810Y604889D01*
X102643Y604639D01*
X102393Y604430D01*
X102102Y604347D01*
X101768Y604430D01*
X101477Y604680D01*
X101310Y605055D01*
X101268Y605472D01*
X101352Y606014D01*
X101477Y606305D01*
X101685Y606597D01*
X101977Y606805D01*
X102268Y606847D01*
X102560Y606764D01*
X102768Y606555D01*
G01X105660Y604347D02*
Y606847D01*
X104118Y605055D01*
X106202D01*
G01X82000Y612400D02*
X75000D01*
G01D02*
Y628500D01*
G01X82000D02*
Y612400D01*
G01X73500D02*
X66500D01*
G01D02*
Y628500D01*
G01X73500D02*
Y612400D01*
G01X86102Y619733D02*
Y617941D01*
X86269Y617566D01*
X86602Y617316D01*
X87019Y617233D01*
X87436Y617316D01*
X87769Y617566D01*
X87936Y617941D01*
Y619733D01*
G01X89202Y617733D02*
X89452Y617441D01*
X89786Y617275D01*
X90161Y617233D01*
X90494Y617275D01*
X90827Y617483D01*
X91036Y617733D01*
X91077Y617983D01*
X90994Y618275D01*
X90702Y618483D01*
X90411Y618566D01*
X90036D01*
G01X90411D02*
X90661Y618691D01*
X90869Y618900D01*
X90952Y619150D01*
X90869Y619400D01*
X90661Y619608D01*
X90286Y619733D01*
X89911Y619691D01*
X89536Y619525D01*
G01X92302Y617608D02*
X92552Y617400D01*
X92844Y617275D01*
X93219Y617233D01*
X93594Y617316D01*
X93886Y617483D01*
X94094Y617775D01*
X94136Y618108D01*
X94052Y618441D01*
X93844Y618650D01*
X93552Y618816D01*
X93261Y618858D01*
X92969Y618816D01*
X92594Y618650D01*
X92719Y619733D01*
X93844D01*
G01X94500Y625300D02*
X84500D01*
G01D02*
Y638700D01*
G01D02*
X94500D01*
G01D02*
Y625300D01*
G01X99500Y637200D02*
X95500D01*
Y629800D01*
G01X92200Y640000D02*
Y644000D01*
X84800D01*
G01X92200D02*
Y648000D01*
X84800D01*
G01X81049Y643083D02*
X80924Y642833D01*
X80841Y642541D01*
Y642208D01*
X80966Y641833D01*
X81174Y641541D01*
X81424Y641333D01*
X81841Y641166D01*
X82216Y641124D01*
X82591Y641208D01*
X82841Y641333D01*
X83091Y641583D01*
X83258Y641874D01*
X83341Y642166D01*
Y642458D01*
X83258Y642749D01*
X83133Y642999D01*
X82966Y643208D01*
G01X81258Y644474D02*
X81008Y644724D01*
X80883Y645016D01*
X80841Y645349D01*
X80924Y645766D01*
X81133Y646058D01*
X81383Y646141D01*
X81633Y646099D01*
X81841Y645933D01*
X82258Y645099D01*
X82549Y644724D01*
X82966Y644474D01*
X83341Y644391D01*
Y646141D01*
G01Y648283D02*
X82799Y648366D01*
X82341Y648491D01*
X81924Y648658D01*
X81466Y648866D01*
X80841Y649199D01*
Y647533D01*
G01X82966Y650549D02*
X83174Y650799D01*
X83299Y651091D01*
X83341Y651466D01*
X83258Y651841D01*
X83091Y652133D01*
X82799Y652341D01*
X82466Y652383D01*
X82133Y652299D01*
X81924Y652091D01*
X81758Y651799D01*
X81716Y651508D01*
X81758Y651216D01*
X81924Y650841D01*
X80841Y650966D01*
Y652091D01*
G01X75000Y628500D02*
X82000D01*
G01X66500D02*
X73500D01*
G01X69553Y677294D02*
X67053D01*
Y678335D01*
X67178Y678669D01*
X67345Y678877D01*
X67678Y678960D01*
X68011Y678877D01*
X68220Y678627D01*
X68345Y678335D01*
Y677294D01*
G01Y678335D02*
X69553Y678960D01*
G01X68511Y680435D02*
X68220Y680727D01*
X68053Y680977D01*
X67970Y681310D01*
X68053Y681602D01*
X68220Y681810D01*
X68470Y681977D01*
X68761Y682019D01*
X69011Y681977D01*
X69261Y681810D01*
X69470Y681560D01*
X69553Y681269D01*
X69470Y680935D01*
X69220Y680644D01*
X68845Y680477D01*
X68428Y680435D01*
X67886Y680519D01*
X67595Y680644D01*
X67303Y680852D01*
X67095Y681144D01*
X67053Y681435D01*
X67136Y681727D01*
X67345Y681935D01*
G01X69261Y683619D02*
X69470Y683910D01*
X69553Y684244D01*
X69470Y684577D01*
X69220Y684869D01*
X68845Y685077D01*
X68470Y685160D01*
X68011D01*
X67636Y685077D01*
X67303Y684869D01*
X67136Y684619D01*
X67053Y684327D01*
X67136Y683994D01*
X67303Y683744D01*
X67553Y683577D01*
X67886Y683494D01*
X68178Y683577D01*
X68470Y683785D01*
X68636Y684035D01*
X68678Y684327D01*
X68595Y684660D01*
X68386Y684910D01*
X68011Y685160D01*
G01X67470Y686635D02*
X67220Y686885D01*
X67095Y687177D01*
X67053Y687510D01*
X67136Y687927D01*
X67345Y688219D01*
X67595Y688302D01*
X67845Y688260D01*
X68053Y688094D01*
X68470Y687260D01*
X68761Y686885D01*
X69178Y686635D01*
X69553Y686552D01*
Y688302D01*
G01X74694Y671841D02*
Y674341D01*
X75694D01*
X76027Y674216D01*
X76277Y673924D01*
X76360Y673591D01*
X76277Y673258D01*
X76069Y673008D01*
X75694Y672883D01*
X74694D01*
G01X77794Y671841D02*
Y674341D01*
X78835D01*
X79169Y674216D01*
X79377Y674049D01*
X79460Y673716D01*
X79377Y673383D01*
X79127Y673174D01*
X78835Y673049D01*
X77794D01*
G01X78835D02*
X79460Y671841D01*
G01X80810Y672341D02*
X81060Y672049D01*
X81394Y671883D01*
X81769Y671841D01*
X82102Y671883D01*
X82435Y672091D01*
X82644Y672341D01*
X82685Y672591D01*
X82602Y672883D01*
X82310Y673091D01*
X82019Y673174D01*
X81644D01*
G01X82019D02*
X82269Y673299D01*
X82477Y673508D01*
X82560Y673758D01*
X82477Y674008D01*
X82269Y674216D01*
X81894Y674341D01*
X81519Y674299D01*
X81144Y674133D01*
G01X84827Y671841D02*
X85119Y671883D01*
X85452Y672008D01*
X85660Y672216D01*
X85744Y672508D01*
X85660Y672799D01*
X85410Y673049D01*
X85035Y673174D01*
X84619D01*
X84369Y673258D01*
X84160Y673466D01*
X84077Y673758D01*
X84202Y674049D01*
X84494Y674258D01*
X84827Y674341D01*
X85160Y674258D01*
X85452Y674049D01*
X85577Y673758D01*
X85494Y673466D01*
X85285Y673258D01*
X85035Y673174D01*
X84619D01*
X84244Y673049D01*
X83994Y672799D01*
X83910Y672508D01*
X83994Y672216D01*
X84202Y672008D01*
X84535Y671883D01*
X84827Y671841D01*
G01X77900Y683900D02*
Y679900D01*
X85300D01*
G01X73553Y677294D02*
X71053D01*
Y678335D01*
X71178Y678669D01*
X71345Y678877D01*
X71678Y678960D01*
X72011Y678877D01*
X72220Y678627D01*
X72345Y678335D01*
Y677294D01*
G01Y678335D02*
X73553Y678960D01*
G01X72511Y680435D02*
X72220Y680727D01*
X72053Y680977D01*
X71970Y681310D01*
X72053Y681602D01*
X72220Y681810D01*
X72470Y681977D01*
X72761Y682019D01*
X73011Y681977D01*
X73261Y681810D01*
X73470Y681560D01*
X73553Y681269D01*
X73470Y680935D01*
X73220Y680644D01*
X72845Y680477D01*
X72428Y680435D01*
X71886Y680519D01*
X71595Y680644D01*
X71303Y680852D01*
X71095Y681144D01*
X71053Y681435D01*
X71136Y681727D01*
X71345Y681935D01*
G01X73261Y683619D02*
X73470Y683910D01*
X73553Y684244D01*
X73470Y684577D01*
X73220Y684869D01*
X72845Y685077D01*
X72470Y685160D01*
X72011D01*
X71636Y685077D01*
X71303Y684869D01*
X71136Y684619D01*
X71053Y684327D01*
X71136Y683994D01*
X71303Y683744D01*
X71553Y683577D01*
X71886Y683494D01*
X72178Y683577D01*
X72470Y683785D01*
X72636Y684035D01*
X72678Y684327D01*
X72595Y684660D01*
X72386Y684910D01*
X72011Y685160D01*
G01X73553Y687427D02*
X71053D01*
X71553Y686927D01*
G01X73553D02*
Y687927D01*
G01X83017Y676167D02*
Y678667D01*
X84058D01*
X84392Y678542D01*
X84600Y678375D01*
X84683Y678042D01*
X84600Y677709D01*
X84350Y677500D01*
X84058Y677375D01*
X83017D01*
G01X84058D02*
X84683Y676167D01*
G01X86158Y677209D02*
X86450Y677500D01*
X86700Y677667D01*
X87033Y677750D01*
X87325Y677667D01*
X87533Y677500D01*
X87700Y677250D01*
X87742Y676959D01*
X87700Y676709D01*
X87533Y676459D01*
X87283Y676250D01*
X86992Y676167D01*
X86658Y676250D01*
X86367Y676500D01*
X86200Y676875D01*
X86158Y677292D01*
X86242Y677834D01*
X86367Y678125D01*
X86575Y678417D01*
X86867Y678625D01*
X87158Y678667D01*
X87450Y678584D01*
X87658Y678375D01*
G01X90550Y676167D02*
Y678667D01*
X89008Y676875D01*
X91092D01*
G01X93150Y676167D02*
X93442Y676209D01*
X93775Y676334D01*
X93983Y676542D01*
X94067Y676834D01*
X93983Y677125D01*
X93733Y677375D01*
X93358Y677500D01*
X92942D01*
X92692Y677584D01*
X92483Y677792D01*
X92400Y678084D01*
X92525Y678375D01*
X92817Y678584D01*
X93150Y678667D01*
X93483Y678584D01*
X93775Y678375D01*
X93900Y678084D01*
X93817Y677792D01*
X93608Y677584D01*
X93358Y677500D01*
X92942D01*
X92567Y677375D01*
X92317Y677125D01*
X92233Y676834D01*
X92317Y676542D01*
X92525Y676334D01*
X92858Y676209D01*
X93150Y676167D01*
G01X85500Y683900D02*
Y679900D01*
X92900D01*
G01X90138Y672047D02*
Y674547D01*
X91179D01*
X91513Y674422D01*
X91721Y674255D01*
X91804Y673922D01*
X91721Y673589D01*
X91471Y673380D01*
X91179Y673255D01*
X90138D01*
G01X91179D02*
X91804Y672047D01*
G01X93279Y673089D02*
X93571Y673380D01*
X93821Y673547D01*
X94154Y673630D01*
X94446Y673547D01*
X94654Y673380D01*
X94821Y673130D01*
X94863Y672839D01*
X94821Y672589D01*
X94654Y672339D01*
X94404Y672130D01*
X94113Y672047D01*
X93779Y672130D01*
X93488Y672380D01*
X93321Y672755D01*
X93279Y673172D01*
X93363Y673714D01*
X93488Y674005D01*
X93696Y674297D01*
X93988Y674505D01*
X94279Y674547D01*
X94571Y674464D01*
X94779Y674255D01*
G01X97171Y672047D02*
Y674547D01*
X96671Y674047D01*
G01Y672047D02*
X97671D01*
G01X100188D02*
X100271Y672589D01*
X100396Y673047D01*
X100563Y673464D01*
X100771Y673922D01*
X101104Y674547D01*
X99438D01*
G01X85715Y650216D02*
Y652716D01*
X86756D01*
X87090Y652591D01*
X87298Y652424D01*
X87381Y652091D01*
X87298Y651758D01*
X87048Y651549D01*
X86756Y651424D01*
X85715D01*
G01X86756D02*
X87381Y650216D01*
G01X88731Y650591D02*
X88981Y650383D01*
X89273Y650258D01*
X89648Y650216D01*
X90023Y650299D01*
X90315Y650466D01*
X90523Y650758D01*
X90565Y651091D01*
X90481Y651424D01*
X90273Y651633D01*
X89981Y651799D01*
X89690Y651841D01*
X89398Y651799D01*
X89023Y651633D01*
X89148Y652716D01*
X90273D01*
G01X92748D02*
X92415Y652633D01*
X92165Y652424D01*
X91998Y652174D01*
X91873Y651841D01*
X91831Y651466D01*
X91873Y651091D01*
X91998Y650758D01*
X92165Y650508D01*
X92415Y650299D01*
X92748Y650216D01*
X93081Y650299D01*
X93331Y650508D01*
X93498Y650758D01*
X93623Y651091D01*
X93665Y651466D01*
X93623Y651841D01*
X93498Y652174D01*
X93331Y652424D01*
X93081Y652633D01*
X92748Y652716D01*
G01X94931Y650591D02*
X95181Y650383D01*
X95473Y650258D01*
X95848Y650216D01*
X96223Y650299D01*
X96515Y650466D01*
X96723Y650758D01*
X96765Y651091D01*
X96681Y651424D01*
X96473Y651633D01*
X96181Y651799D01*
X95890Y651841D01*
X95598Y651799D01*
X95223Y651633D01*
X95348Y652716D01*
X96473D01*
G01X85715Y654383D02*
Y656883D01*
X86756D01*
X87090Y656758D01*
X87298Y656591D01*
X87381Y656258D01*
X87298Y655925D01*
X87048Y655716D01*
X86756Y655591D01*
X85715D01*
G01X86756D02*
X87381Y654383D01*
G01X88731Y654758D02*
X88981Y654550D01*
X89273Y654425D01*
X89648Y654383D01*
X90023Y654466D01*
X90315Y654633D01*
X90523Y654925D01*
X90565Y655258D01*
X90481Y655591D01*
X90273Y655800D01*
X89981Y655966D01*
X89690Y656008D01*
X89398Y655966D01*
X89023Y655800D01*
X89148Y656883D01*
X90273D01*
G01X92748Y654383D02*
Y656883D01*
X92248Y656383D01*
G01Y654383D02*
X93248D01*
G01X95848Y656883D02*
X95515Y656800D01*
X95265Y656591D01*
X95098Y656341D01*
X94973Y656008D01*
X94931Y655633D01*
X94973Y655258D01*
X95098Y654925D01*
X95265Y654675D01*
X95515Y654466D01*
X95848Y654383D01*
X96181Y654466D01*
X96431Y654675D01*
X96598Y654925D01*
X96723Y655258D01*
X96765Y655633D01*
X96723Y656008D01*
X96598Y656341D01*
X96431Y656591D01*
X96181Y656800D01*
X95848Y656883D01*
G01X73700Y697400D02*
Y691900D01*
X65700D01*
Y697500D01*
G01X73700Y709500D02*
Y704000D01*
G01Y709500D02*
X65700D01*
Y704000D01*
G01X75359Y709945D02*
Y712445D01*
X76359D01*
X76692Y712320D01*
X76942Y712028D01*
X77025Y711695D01*
X76942Y711362D01*
X76734Y711112D01*
X76359Y710987D01*
X75359D01*
G01X78500Y712028D02*
X78750Y712278D01*
X79042Y712403D01*
X79375Y712445D01*
X79792Y712362D01*
X80084Y712153D01*
X80167Y711903D01*
X80125Y711653D01*
X79959Y711445D01*
X79125Y711028D01*
X78750Y710737D01*
X78500Y710320D01*
X78417Y709945D01*
X80167D01*
G01X82392D02*
Y712445D01*
X81892Y711945D01*
G01Y709945D02*
X82892D01*
G01X84700Y712028D02*
X84950Y712278D01*
X85242Y712403D01*
X85575Y712445D01*
X85992Y712362D01*
X86284Y712153D01*
X86367Y711903D01*
X86325Y711653D01*
X86159Y711445D01*
X85325Y711028D01*
X84950Y710737D01*
X84700Y710320D01*
X84617Y709945D01*
X86367D01*
G01X88592D02*
Y712445D01*
X88092Y711945D01*
G01Y709945D02*
X89092D01*
G01X94517Y701167D02*
Y703667D01*
X95558D01*
X95892Y703542D01*
X96100Y703375D01*
X96183Y703042D01*
X96100Y702709D01*
X95850Y702500D01*
X95558Y702375D01*
X94517D01*
G01X95558D02*
X96183Y701167D01*
G01X97658Y702209D02*
X97950Y702500D01*
X98200Y702667D01*
X98533Y702750D01*
X98825Y702667D01*
X99033Y702500D01*
X99200Y702250D01*
X99242Y701959D01*
X99200Y701709D01*
X99033Y701459D01*
X98783Y701250D01*
X98492Y701167D01*
X98158Y701250D01*
X97867Y701500D01*
X97700Y701875D01*
X97658Y702292D01*
X97742Y702834D01*
X97867Y703125D01*
X98075Y703417D01*
X98367Y703625D01*
X98658Y703667D01*
X98950Y703584D01*
X99158Y703375D01*
G01X100842Y701459D02*
X101133Y701250D01*
X101467Y701167D01*
X101800Y701250D01*
X102092Y701500D01*
X102300Y701875D01*
X102383Y702250D01*
Y702709D01*
X102300Y703084D01*
X102092Y703417D01*
X101842Y703584D01*
X101550Y703667D01*
X101217Y703584D01*
X100967Y703417D01*
X100800Y703167D01*
X100717Y702834D01*
X100800Y702542D01*
X101008Y702250D01*
X101258Y702084D01*
X101550Y702042D01*
X101883Y702125D01*
X102133Y702334D01*
X102383Y702709D01*
G01X104650Y703667D02*
X104317Y703584D01*
X104067Y703375D01*
X103900Y703125D01*
X103775Y702792D01*
X103733Y702417D01*
X103775Y702042D01*
X103900Y701709D01*
X104067Y701459D01*
X104317Y701250D01*
X104650Y701167D01*
X104983Y701250D01*
X105233Y701459D01*
X105400Y701709D01*
X105525Y702042D01*
X105567Y702417D01*
X105525Y702792D01*
X105400Y703125D01*
X105233Y703375D01*
X104983Y703584D01*
X104650Y703667D01*
G01X78950Y699950D02*
X82950D01*
Y707350D01*
G01X100400Y679900D02*
Y683900D01*
X93000D01*
G01X97334Y706517D02*
X94834D01*
Y707517D01*
X94959Y707850D01*
X95251Y708100D01*
X95584Y708183D01*
X95917Y708100D01*
X96167Y707892D01*
X96292Y707517D01*
Y706517D01*
G01X97334Y710450D02*
X97292Y710117D01*
X97126Y709825D01*
X96876Y709575D01*
X96584Y709408D01*
X96251Y709325D01*
X95917D01*
X95584Y709408D01*
X95292Y709575D01*
X95042Y709825D01*
X94876Y710117D01*
X94834Y710450D01*
X94876Y710783D01*
X95042Y711075D01*
X95292Y711325D01*
X95584Y711492D01*
X95917Y711575D01*
X96251D01*
X96584Y711492D01*
X96876Y711325D01*
X97126Y711075D01*
X97292Y710783D01*
X97334Y710450D01*
G01X96667Y710783D02*
X97334Y711283D01*
G01X96834Y712633D02*
X97126Y712883D01*
X97292Y713217D01*
X97334Y713592D01*
X97292Y713925D01*
X97084Y714258D01*
X96834Y714467D01*
X96584Y714508D01*
X96292Y714425D01*
X96084Y714133D01*
X96001Y713842D01*
Y713467D01*
G01Y713842D02*
X95876Y714092D01*
X95667Y714300D01*
X95417Y714383D01*
X95167Y714300D01*
X94959Y714092D01*
X94834Y713717D01*
X94876Y713342D01*
X95042Y712967D01*
G01X96834Y715733D02*
X97126Y715983D01*
X97292Y716317D01*
X97334Y716692D01*
X97292Y717025D01*
X97084Y717358D01*
X96834Y717567D01*
X96584Y717608D01*
X96292Y717525D01*
X96084Y717233D01*
X96001Y716942D01*
Y716567D01*
G01Y716942D02*
X95876Y717192D01*
X95667Y717400D01*
X95417Y717483D01*
X95167Y717400D01*
X94959Y717192D01*
X94834Y716817D01*
X94876Y716442D01*
X95042Y716067D01*
G01X77834Y686400D02*
X77792Y686067D01*
X77626Y685775D01*
X77376Y685525D01*
X77084Y685358D01*
X76751Y685275D01*
X76417D01*
X76084Y685358D01*
X75792Y685525D01*
X75542Y685775D01*
X75376Y686067D01*
X75334Y686400D01*
X75376Y686733D01*
X75542Y687025D01*
X75792Y687275D01*
X76084Y687442D01*
X76417Y687525D01*
X76751D01*
X77084Y687442D01*
X77376Y687275D01*
X77626Y687025D01*
X77792Y686733D01*
X77834Y686400D01*
G01X77167Y686733D02*
X77834Y687233D01*
G01X77542Y688792D02*
X77751Y689083D01*
X77834Y689417D01*
X77751Y689750D01*
X77501Y690042D01*
X77126Y690250D01*
X76751Y690333D01*
X76292D01*
X75917Y690250D01*
X75584Y690042D01*
X75417Y689792D01*
X75334Y689500D01*
X75417Y689167D01*
X75584Y688917D01*
X75834Y688750D01*
X76167Y688667D01*
X76459Y688750D01*
X76751Y688958D01*
X76917Y689208D01*
X76959Y689500D01*
X76876Y689833D01*
X76667Y690083D01*
X76292Y690333D01*
G01X77334Y691683D02*
X77626Y691933D01*
X77792Y692267D01*
X77834Y692642D01*
X77792Y692975D01*
X77584Y693308D01*
X77334Y693517D01*
X77084Y693558D01*
X76792Y693475D01*
X76584Y693183D01*
X76501Y692892D01*
Y692517D01*
G01Y692892D02*
X76376Y693142D01*
X76167Y693350D01*
X75917Y693433D01*
X75667Y693350D01*
X75459Y693142D01*
X75334Y692767D01*
X75376Y692392D01*
X75542Y692017D01*
G01X79450Y698650D02*
Y684650D01*
G01X92450Y698650D02*
X79450D01*
G01X92450Y684650D02*
Y698650D01*
G01X79450Y684650D02*
X92450D01*
G01X93450Y698650D02*
Y684650D01*
G01X106450Y698650D02*
X93450D01*
G01Y684650D02*
X106450D01*
G01X70250Y737852D02*
X67250D01*
G01X69250Y728012D02*
X67250D01*
G01X83800Y729300D02*
Y733300D01*
X76400D01*
G01X83800Y725300D02*
Y729300D01*
X76400D01*
G01X89800Y717700D02*
X93800D01*
Y725100D01*
G01X73800Y725200D02*
Y721200D01*
X81200D01*
G01X85000Y738900D02*
Y742900D01*
X77600D01*
G01X85000D02*
Y746900D01*
X77600D01*
G01X88917Y742800D02*
Y745300D01*
X89958D01*
X90292Y745175D01*
X90500Y745008D01*
X90583Y744675D01*
X90500Y744342D01*
X90250Y744133D01*
X89958Y744008D01*
X88917D01*
G01X89958D02*
X90583Y742800D01*
G01X92142Y743092D02*
X92433Y742883D01*
X92767Y742800D01*
X93100Y742883D01*
X93392Y743133D01*
X93600Y743508D01*
X93683Y743883D01*
Y744342D01*
X93600Y744717D01*
X93392Y745050D01*
X93142Y745217D01*
X92850Y745300D01*
X92517Y745217D01*
X92267Y745050D01*
X92100Y744800D01*
X92017Y744467D01*
X92100Y744175D01*
X92308Y743883D01*
X92558Y743717D01*
X92850Y743675D01*
X93183Y743758D01*
X93433Y743967D01*
X93683Y744342D01*
G01X95158Y743842D02*
X95450Y744133D01*
X95700Y744300D01*
X96033Y744383D01*
X96325Y744300D01*
X96533Y744133D01*
X96700Y743883D01*
X96742Y743592D01*
X96700Y743342D01*
X96533Y743092D01*
X96283Y742883D01*
X95992Y742800D01*
X95658Y742883D01*
X95367Y743133D01*
X95200Y743508D01*
X95158Y743925D01*
X95242Y744467D01*
X95367Y744758D01*
X95575Y745050D01*
X95867Y745258D01*
X96158Y745300D01*
X96450Y745217D01*
X96658Y745008D01*
G01X98967Y742800D02*
X99050Y743342D01*
X99175Y743800D01*
X99342Y744217D01*
X99550Y744675D01*
X99883Y745300D01*
X98217D01*
G01X97200Y734300D02*
Y730300D01*
X104600D01*
G01X88917Y738300D02*
Y740800D01*
X89958D01*
X90292Y740675D01*
X90500Y740508D01*
X90583Y740175D01*
X90500Y739842D01*
X90250Y739633D01*
X89958Y739508D01*
X88917D01*
G01X89958D02*
X90583Y738300D01*
G01X92142Y738592D02*
X92433Y738383D01*
X92767Y738300D01*
X93100Y738383D01*
X93392Y738633D01*
X93600Y739008D01*
X93683Y739383D01*
Y739842D01*
X93600Y740217D01*
X93392Y740550D01*
X93142Y740717D01*
X92850Y740800D01*
X92517Y740717D01*
X92267Y740550D01*
X92100Y740300D01*
X92017Y739967D01*
X92100Y739675D01*
X92308Y739383D01*
X92558Y739217D01*
X92850Y739175D01*
X93183Y739258D01*
X93433Y739467D01*
X93683Y739842D01*
G01X95158Y739342D02*
X95450Y739633D01*
X95700Y739800D01*
X96033Y739883D01*
X96325Y739800D01*
X96533Y739633D01*
X96700Y739383D01*
X96742Y739092D01*
X96700Y738842D01*
X96533Y738592D01*
X96283Y738383D01*
X95992Y738300D01*
X95658Y738383D01*
X95367Y738633D01*
X95200Y739008D01*
X95158Y739425D01*
X95242Y739967D01*
X95367Y740258D01*
X95575Y740550D01*
X95867Y740758D01*
X96158Y740800D01*
X96450Y740717D01*
X96658Y740508D01*
G01X98133Y738675D02*
X98383Y738467D01*
X98675Y738342D01*
X99050Y738300D01*
X99425Y738383D01*
X99717Y738550D01*
X99925Y738842D01*
X99967Y739175D01*
X99883Y739508D01*
X99675Y739717D01*
X99383Y739883D01*
X99092Y739925D01*
X98800Y739883D01*
X98425Y739717D01*
X98550Y740800D01*
X99675D01*
G01X104600Y725800D02*
Y729800D01*
X97200D01*
G01X82300Y723600D02*
X88300D01*
Y719200D01*
X82300D01*
Y723600D01*
G01X66834Y781967D02*
X64334D01*
Y783008D01*
X64459Y783342D01*
X64626Y783550D01*
X64959Y783633D01*
X65292Y783550D01*
X65501Y783300D01*
X65626Y783008D01*
Y781967D01*
G01Y783008D02*
X66834Y783633D01*
G01X64751Y785108D02*
X64501Y785358D01*
X64376Y785650D01*
X64334Y785983D01*
X64417Y786400D01*
X64626Y786692D01*
X64876Y786775D01*
X65126Y786733D01*
X65334Y786567D01*
X65751Y785733D01*
X66042Y785358D01*
X66459Y785108D01*
X66834Y785025D01*
Y786775D01*
G01Y789000D02*
X64334D01*
X64834Y788500D01*
G01X66834D02*
Y789500D01*
G01Y792017D02*
X66292Y792100D01*
X65834Y792225D01*
X65417Y792392D01*
X64959Y792600D01*
X64334Y792933D01*
Y791267D01*
G01X66834Y795200D02*
X64334D01*
X64834Y794700D01*
G01X66834D02*
Y795700D01*
G01X81967Y782167D02*
Y784667D01*
X83008D01*
X83342Y784542D01*
X83550Y784375D01*
X83633Y784042D01*
X83550Y783709D01*
X83300Y783500D01*
X83008Y783375D01*
X81967D01*
G01X83008D02*
X83633Y782167D01*
G01X85108Y784250D02*
X85358Y784500D01*
X85650Y784625D01*
X85983Y784667D01*
X86400Y784584D01*
X86692Y784375D01*
X86775Y784125D01*
X86733Y783875D01*
X86567Y783667D01*
X85733Y783250D01*
X85358Y782959D01*
X85108Y782542D01*
X85025Y782167D01*
X86775D01*
G01X89000D02*
Y784667D01*
X88500Y784167D01*
G01Y782167D02*
X89500D01*
G01X91308Y784250D02*
X91558Y784500D01*
X91850Y784625D01*
X92183Y784667D01*
X92600Y784584D01*
X92892Y784375D01*
X92975Y784125D01*
X92933Y783875D01*
X92767Y783667D01*
X91933Y783250D01*
X91558Y782959D01*
X91308Y782542D01*
X91225Y782167D01*
X92975D01*
G01X94283Y782667D02*
X94533Y782375D01*
X94867Y782209D01*
X95242Y782167D01*
X95575Y782209D01*
X95908Y782417D01*
X96117Y782667D01*
X96158Y782917D01*
X96075Y783209D01*
X95783Y783417D01*
X95492Y783500D01*
X95117D01*
G01X95492D02*
X95742Y783625D01*
X95950Y783834D01*
X96033Y784084D01*
X95950Y784334D01*
X95742Y784542D01*
X95367Y784667D01*
X94992Y784625D01*
X94617Y784459D01*
G01X81967Y778167D02*
Y780667D01*
X83008D01*
X83342Y780542D01*
X83550Y780375D01*
X83633Y780042D01*
X83550Y779709D01*
X83300Y779500D01*
X83008Y779375D01*
X81967D01*
G01X83008D02*
X83633Y778167D01*
G01X85192Y778459D02*
X85483Y778250D01*
X85817Y778167D01*
X86150Y778250D01*
X86442Y778500D01*
X86650Y778875D01*
X86733Y779250D01*
Y779709D01*
X86650Y780084D01*
X86442Y780417D01*
X86192Y780584D01*
X85900Y780667D01*
X85567Y780584D01*
X85317Y780417D01*
X85150Y780167D01*
X85067Y779834D01*
X85150Y779542D01*
X85358Y779250D01*
X85608Y779084D01*
X85900Y779042D01*
X86233Y779125D01*
X86483Y779334D01*
X86733Y779709D01*
G01X89000Y780667D02*
X88667Y780584D01*
X88417Y780375D01*
X88250Y780125D01*
X88125Y779792D01*
X88083Y779417D01*
X88125Y779042D01*
X88250Y778709D01*
X88417Y778459D01*
X88667Y778250D01*
X89000Y778167D01*
X89333Y778250D01*
X89583Y778459D01*
X89750Y778709D01*
X89875Y779042D01*
X89917Y779417D01*
X89875Y779792D01*
X89750Y780125D01*
X89583Y780375D01*
X89333Y780584D01*
X89000Y780667D01*
G01X91308Y780250D02*
X91558Y780500D01*
X91850Y780625D01*
X92183Y780667D01*
X92600Y780584D01*
X92892Y780375D01*
X92975Y780125D01*
X92933Y779875D01*
X92767Y779667D01*
X91933Y779250D01*
X91558Y778959D01*
X91308Y778542D01*
X91225Y778167D01*
X92975D01*
G01X94283Y778542D02*
X94533Y778334D01*
X94825Y778209D01*
X95200Y778167D01*
X95575Y778250D01*
X95867Y778417D01*
X96075Y778709D01*
X96117Y779042D01*
X96033Y779375D01*
X95825Y779584D01*
X95533Y779750D01*
X95242Y779792D01*
X94950Y779750D01*
X94575Y779584D01*
X94700Y780667D01*
X95825D01*
G01X69008Y777117D02*
X68883Y776867D01*
X68800Y776575D01*
Y776242D01*
X68925Y775867D01*
X69133Y775575D01*
X69383Y775367D01*
X69800Y775200D01*
X70175Y775158D01*
X70550Y775242D01*
X70800Y775367D01*
X71050Y775617D01*
X71217Y775908D01*
X71300Y776200D01*
Y776492D01*
X71217Y776783D01*
X71092Y777033D01*
X70925Y777242D01*
G01X71300Y779217D02*
X70758Y779300D01*
X70300Y779425D01*
X69883Y779592D01*
X69425Y779800D01*
X68800Y780133D01*
Y778467D01*
G01X70800Y781483D02*
X71092Y781733D01*
X71258Y782067D01*
X71300Y782442D01*
X71258Y782775D01*
X71050Y783108D01*
X70800Y783317D01*
X70550Y783358D01*
X70258Y783275D01*
X70050Y782983D01*
X69967Y782692D01*
Y782317D01*
G01Y782692D02*
X69842Y782942D01*
X69633Y783150D01*
X69383Y783233D01*
X69133Y783150D01*
X68925Y782942D01*
X68800Y782567D01*
X68842Y782192D01*
X69008Y781817D01*
G01X71300Y785500D02*
X68800D01*
X69300Y785000D01*
G01X71300D02*
Y786000D01*
G01X70258Y787808D02*
X69967Y788100D01*
X69800Y788350D01*
X69717Y788683D01*
X69800Y788975D01*
X69967Y789183D01*
X70217Y789350D01*
X70508Y789392D01*
X70758Y789350D01*
X71008Y789183D01*
X71217Y788933D01*
X71300Y788642D01*
X71217Y788308D01*
X70967Y788017D01*
X70592Y787850D01*
X70175Y787808D01*
X69633Y787892D01*
X69342Y788017D01*
X69050Y788225D01*
X68842Y788517D01*
X68800Y788808D01*
X68883Y789100D01*
X69092Y789308D01*
G01X75800Y773867D02*
X73300D01*
Y774908D01*
X73425Y775242D01*
X73592Y775450D01*
X73925Y775533D01*
X74258Y775450D01*
X74467Y775200D01*
X74592Y774908D01*
Y773867D01*
G01Y774908D02*
X75800Y775533D01*
G01X75508Y777092D02*
X75717Y777383D01*
X75800Y777717D01*
X75717Y778050D01*
X75467Y778342D01*
X75092Y778550D01*
X74717Y778633D01*
X74258D01*
X73883Y778550D01*
X73550Y778342D01*
X73383Y778092D01*
X73300Y777800D01*
X73383Y777467D01*
X73550Y777217D01*
X73800Y777050D01*
X74133Y776967D01*
X74425Y777050D01*
X74717Y777258D01*
X74883Y777508D01*
X74925Y777800D01*
X74842Y778133D01*
X74633Y778383D01*
X74258Y778633D01*
G01X73300Y780900D02*
X73383Y780567D01*
X73592Y780317D01*
X73842Y780150D01*
X74175Y780025D01*
X74550Y779983D01*
X74925Y780025D01*
X75258Y780150D01*
X75508Y780317D01*
X75717Y780567D01*
X75800Y780900D01*
X75717Y781233D01*
X75508Y781483D01*
X75258Y781650D01*
X74925Y781775D01*
X74550Y781817D01*
X74175Y781775D01*
X73842Y781650D01*
X73592Y781483D01*
X73383Y781233D01*
X73300Y780900D01*
G01X73717Y783208D02*
X73467Y783458D01*
X73342Y783750D01*
X73300Y784083D01*
X73383Y784500D01*
X73592Y784792D01*
X73842Y784875D01*
X74092Y784833D01*
X74300Y784667D01*
X74717Y783833D01*
X75008Y783458D01*
X75425Y783208D01*
X75800Y783125D01*
Y784875D01*
G01Y787100D02*
X75758Y787392D01*
X75633Y787725D01*
X75425Y787933D01*
X75133Y788017D01*
X74842Y787933D01*
X74592Y787683D01*
X74467Y787308D01*
Y786892D01*
X74383Y786642D01*
X74175Y786433D01*
X73883Y786350D01*
X73592Y786475D01*
X73383Y786767D01*
X73300Y787100D01*
X73383Y787433D01*
X73592Y787725D01*
X73883Y787850D01*
X74175Y787767D01*
X74383Y787558D01*
X74467Y787308D01*
Y786892D01*
X74592Y786517D01*
X74842Y786267D01*
X75133Y786183D01*
X75425Y786267D01*
X75633Y786475D01*
X75758Y786808D01*
X75800Y787100D01*
G01X72300Y760700D02*
X76300D01*
Y768100D01*
G01X95967Y758167D02*
Y760667D01*
X97008D01*
X97342Y760542D01*
X97550Y760375D01*
X97633Y760042D01*
X97550Y759709D01*
X97300Y759500D01*
X97008Y759375D01*
X95967D01*
G01X97008D02*
X97633Y758167D01*
G01X99108Y760250D02*
X99358Y760500D01*
X99650Y760625D01*
X99983Y760667D01*
X100400Y760584D01*
X100692Y760375D01*
X100775Y760125D01*
X100733Y759875D01*
X100567Y759667D01*
X99733Y759250D01*
X99358Y758959D01*
X99108Y758542D01*
X99025Y758167D01*
X100775D01*
G01X103000D02*
Y760667D01*
X102500Y760167D01*
G01Y758167D02*
X103500D01*
G01X106100D02*
Y760667D01*
X105600Y760167D01*
G01Y758167D02*
X106600D01*
G01X109700D02*
Y760667D01*
X108158Y758875D01*
X110242D01*
G01X77600Y755700D02*
Y751700D01*
X85000D01*
G01X77600Y759900D02*
Y755900D01*
X85000D01*
G01Y764900D02*
Y768900D01*
X77600D01*
G01X78042Y778267D02*
X77917Y778017D01*
X77834Y777725D01*
Y777392D01*
X77959Y777017D01*
X78167Y776725D01*
X78417Y776517D01*
X78834Y776350D01*
X79209Y776308D01*
X79584Y776392D01*
X79834Y776517D01*
X80084Y776767D01*
X80251Y777058D01*
X80334Y777350D01*
Y777642D01*
X80251Y777933D01*
X80126Y778183D01*
X79959Y778392D01*
G01X80334Y780950D02*
X77834D01*
X79626Y779408D01*
Y781492D01*
G01X80334Y783550D02*
X77834D01*
X78334Y783050D01*
G01X80334D02*
Y784050D01*
G01X80042Y785942D02*
X80251Y786233D01*
X80334Y786567D01*
X80251Y786900D01*
X80001Y787192D01*
X79626Y787400D01*
X79251Y787483D01*
X78792D01*
X78417Y787400D01*
X78084Y787192D01*
X77917Y786942D01*
X77834Y786650D01*
X77917Y786317D01*
X78084Y786067D01*
X78334Y785900D01*
X78667Y785817D01*
X78959Y785900D01*
X79251Y786108D01*
X79417Y786358D01*
X79459Y786650D01*
X79376Y786983D01*
X79167Y787233D01*
X78792Y787483D01*
G01X83717Y776959D02*
X83467Y777084D01*
X83175Y777167D01*
X82842D01*
X82467Y777042D01*
X82175Y776834D01*
X81967Y776584D01*
X81800Y776167D01*
X81758Y775792D01*
X81842Y775417D01*
X81967Y775167D01*
X82217Y774917D01*
X82508Y774750D01*
X82800Y774667D01*
X83092D01*
X83383Y774750D01*
X83633Y774875D01*
X83842Y775042D01*
G01X85900Y774667D02*
X86192Y774709D01*
X86525Y774834D01*
X86733Y775042D01*
X86817Y775334D01*
X86733Y775625D01*
X86483Y775875D01*
X86108Y776000D01*
X85692D01*
X85442Y776084D01*
X85233Y776292D01*
X85150Y776584D01*
X85275Y776875D01*
X85567Y777084D01*
X85900Y777167D01*
X86233Y777084D01*
X86525Y776875D01*
X86650Y776584D01*
X86567Y776292D01*
X86358Y776084D01*
X86108Y776000D01*
X85692D01*
X85317Y775875D01*
X85067Y775625D01*
X84983Y775334D01*
X85067Y775042D01*
X85275Y774834D01*
X85608Y774709D01*
X85900Y774667D01*
G01X89000Y777167D02*
X88667Y777084D01*
X88417Y776875D01*
X88250Y776625D01*
X88125Y776292D01*
X88083Y775917D01*
X88125Y775542D01*
X88250Y775209D01*
X88417Y774959D01*
X88667Y774750D01*
X89000Y774667D01*
X89333Y774750D01*
X89583Y774959D01*
X89750Y775209D01*
X89875Y775542D01*
X89917Y775917D01*
X89875Y776292D01*
X89750Y776625D01*
X89583Y776875D01*
X89333Y777084D01*
X89000Y777167D01*
G01X91392Y774959D02*
X91683Y774750D01*
X92017Y774667D01*
X92350Y774750D01*
X92642Y775000D01*
X92850Y775375D01*
X92933Y775750D01*
Y776209D01*
X92850Y776584D01*
X92642Y776917D01*
X92392Y777084D01*
X92100Y777167D01*
X91767Y777084D01*
X91517Y776917D01*
X91350Y776667D01*
X91267Y776334D01*
X91350Y776042D01*
X91558Y775750D01*
X91808Y775584D01*
X92100Y775542D01*
X92433Y775625D01*
X92683Y775834D01*
X92933Y776209D01*
G01X94492Y774959D02*
X94783Y774750D01*
X95117Y774667D01*
X95450Y774750D01*
X95742Y775000D01*
X95950Y775375D01*
X96033Y775750D01*
Y776209D01*
X95950Y776584D01*
X95742Y776917D01*
X95492Y777084D01*
X95200Y777167D01*
X94867Y777084D01*
X94617Y776917D01*
X94450Y776667D01*
X94367Y776334D01*
X94450Y776042D01*
X94658Y775750D01*
X94908Y775584D01*
X95200Y775542D01*
X95533Y775625D01*
X95783Y775834D01*
X96033Y776209D01*
G01X110250Y823500D02*
Y810500D01*
X94750D01*
Y823500D01*
X110250D01*
G01X81967Y786167D02*
Y788667D01*
X83008D01*
X83342Y788542D01*
X83550Y788375D01*
X83633Y788042D01*
X83550Y787709D01*
X83300Y787500D01*
X83008Y787375D01*
X81967D01*
G01X83008D02*
X83633Y786167D01*
G01X85108Y788250D02*
X85358Y788500D01*
X85650Y788625D01*
X85983Y788667D01*
X86400Y788584D01*
X86692Y788375D01*
X86775Y788125D01*
X86733Y787875D01*
X86567Y787667D01*
X85733Y787250D01*
X85358Y786959D01*
X85108Y786542D01*
X85025Y786167D01*
X86775D01*
G01X89000D02*
Y788667D01*
X88500Y788167D01*
G01Y786167D02*
X89500D01*
G01X91308Y788250D02*
X91558Y788500D01*
X91850Y788625D01*
X92183Y788667D01*
X92600Y788584D01*
X92892Y788375D01*
X92975Y788125D01*
X92933Y787875D01*
X92767Y787667D01*
X91933Y787250D01*
X91558Y786959D01*
X91308Y786542D01*
X91225Y786167D01*
X92975D01*
G01X95200Y788667D02*
X94867Y788584D01*
X94617Y788375D01*
X94450Y788125D01*
X94325Y787792D01*
X94283Y787417D01*
X94325Y787042D01*
X94450Y786709D01*
X94617Y786459D01*
X94867Y786250D01*
X95200Y786167D01*
X95533Y786250D01*
X95783Y786459D01*
X95950Y786709D01*
X96075Y787042D01*
X96117Y787417D01*
X96075Y787792D01*
X95950Y788125D01*
X95783Y788375D01*
X95533Y788584D01*
X95200Y788667D01*
G01X77967Y795167D02*
Y797667D01*
X79008D01*
X79342Y797542D01*
X79550Y797375D01*
X79633Y797042D01*
X79550Y796709D01*
X79300Y796500D01*
X79008Y796375D01*
X77967D01*
G01X79008D02*
X79633Y795167D01*
G01X81108Y797250D02*
X81358Y797500D01*
X81650Y797625D01*
X81983Y797667D01*
X82400Y797584D01*
X82692Y797375D01*
X82775Y797125D01*
X82733Y796875D01*
X82567Y796667D01*
X81733Y796250D01*
X81358Y795959D01*
X81108Y795542D01*
X81025Y795167D01*
X82775D01*
G01X85000Y797667D02*
X84667Y797584D01*
X84417Y797375D01*
X84250Y797125D01*
X84125Y796792D01*
X84083Y796417D01*
X84125Y796042D01*
X84250Y795709D01*
X84417Y795459D01*
X84667Y795250D01*
X85000Y795167D01*
X85333Y795250D01*
X85583Y795459D01*
X85750Y795709D01*
X85875Y796042D01*
X85917Y796417D01*
X85875Y796792D01*
X85750Y797125D01*
X85583Y797375D01*
X85333Y797584D01*
X85000Y797667D01*
G01X87392Y795459D02*
X87683Y795250D01*
X88017Y795167D01*
X88350Y795250D01*
X88642Y795500D01*
X88850Y795875D01*
X88933Y796250D01*
Y796709D01*
X88850Y797084D01*
X88642Y797417D01*
X88392Y797584D01*
X88100Y797667D01*
X87767Y797584D01*
X87517Y797417D01*
X87350Y797167D01*
X87267Y796834D01*
X87350Y796542D01*
X87558Y796250D01*
X87808Y796084D01*
X88100Y796042D01*
X88433Y796125D01*
X88683Y796334D01*
X88933Y796709D01*
G01X91200Y795167D02*
X91492Y795209D01*
X91825Y795334D01*
X92033Y795542D01*
X92117Y795834D01*
X92033Y796125D01*
X91783Y796375D01*
X91408Y796500D01*
X90992D01*
X90742Y796584D01*
X90533Y796792D01*
X90450Y797084D01*
X90575Y797375D01*
X90867Y797584D01*
X91200Y797667D01*
X91533Y797584D01*
X91825Y797375D01*
X91950Y797084D01*
X91867Y796792D01*
X91658Y796584D01*
X91408Y796500D01*
X90992D01*
X90617Y796375D01*
X90367Y796125D01*
X90283Y795834D01*
X90367Y795542D01*
X90575Y795334D01*
X90908Y795209D01*
X91200Y795167D01*
G01X77917Y791167D02*
Y793667D01*
X78917D01*
X79250Y793542D01*
X79500Y793250D01*
X79583Y792917D01*
X79500Y792584D01*
X79292Y792334D01*
X78917Y792209D01*
X77917D01*
G01X82767Y793459D02*
X82517Y793584D01*
X82225Y793667D01*
X81892D01*
X81517Y793542D01*
X81225Y793334D01*
X81017Y793084D01*
X80850Y792667D01*
X80808Y792292D01*
X80892Y791917D01*
X81017Y791667D01*
X81267Y791417D01*
X81558Y791250D01*
X81850Y791167D01*
X82142D01*
X82433Y791250D01*
X82683Y791375D01*
X82892Y791542D01*
G01X84950Y791167D02*
Y793667D01*
X84450Y793167D01*
G01Y791167D02*
X85450D01*
G01X88050Y793667D02*
X87717Y793584D01*
X87467Y793375D01*
X87300Y793125D01*
X87175Y792792D01*
X87133Y792417D01*
X87175Y792042D01*
X87300Y791709D01*
X87467Y791459D01*
X87717Y791250D01*
X88050Y791167D01*
X88383Y791250D01*
X88633Y791459D01*
X88800Y791709D01*
X88925Y792042D01*
X88967Y792417D01*
X88925Y792792D01*
X88800Y793125D01*
X88633Y793375D01*
X88383Y793584D01*
X88050Y793667D01*
G01X91150Y791167D02*
X91442Y791209D01*
X91775Y791334D01*
X91983Y791542D01*
X92067Y791834D01*
X91983Y792125D01*
X91733Y792375D01*
X91358Y792500D01*
X90942D01*
X90692Y792584D01*
X90483Y792792D01*
X90400Y793084D01*
X90525Y793375D01*
X90817Y793584D01*
X91150Y793667D01*
X91483Y793584D01*
X91775Y793375D01*
X91900Y793084D01*
X91817Y792792D01*
X91608Y792584D01*
X91358Y792500D01*
X90942D01*
X90567Y792375D01*
X90317Y792125D01*
X90233Y791834D01*
X90317Y791542D01*
X90525Y791334D01*
X90858Y791209D01*
X91150Y791167D01*
G01X93333Y791667D02*
X93583Y791375D01*
X93917Y791209D01*
X94292Y791167D01*
X94625Y791209D01*
X94958Y791417D01*
X95167Y791667D01*
X95208Y791917D01*
X95125Y792209D01*
X94833Y792417D01*
X94542Y792500D01*
X94167D01*
G01X94542D02*
X94792Y792625D01*
X95000Y792834D01*
X95083Y793084D01*
X95000Y793334D01*
X94792Y793542D01*
X94417Y793667D01*
X94042Y793625D01*
X93667Y793459D01*
G01X64542Y799717D02*
X64417Y799467D01*
X64334Y799175D01*
Y798842D01*
X64459Y798467D01*
X64667Y798175D01*
X64917Y797967D01*
X65334Y797800D01*
X65709Y797758D01*
X66084Y797842D01*
X66334Y797967D01*
X66584Y798217D01*
X66751Y798508D01*
X66834Y798800D01*
Y799092D01*
X66751Y799383D01*
X66626Y799633D01*
X66459Y799842D01*
G01X66834Y801817D02*
X66292Y801900D01*
X65834Y802025D01*
X65417Y802192D01*
X64959Y802400D01*
X64334Y802733D01*
Y801067D01*
G01X64751Y804208D02*
X64501Y804458D01*
X64376Y804750D01*
X64334Y805083D01*
X64417Y805500D01*
X64626Y805792D01*
X64876Y805875D01*
X65126Y805833D01*
X65334Y805667D01*
X65751Y804833D01*
X66042Y804458D01*
X66459Y804208D01*
X66834Y804125D01*
Y805875D01*
G01Y808017D02*
X66292Y808100D01*
X65834Y808225D01*
X65417Y808392D01*
X64959Y808600D01*
X64334Y808933D01*
Y807267D01*
G01X66834Y811117D02*
X66292Y811200D01*
X65834Y811325D01*
X65417Y811492D01*
X64959Y811700D01*
X64334Y812033D01*
Y810367D01*
G01X79717Y805459D02*
X79467Y805584D01*
X79175Y805667D01*
X78842D01*
X78467Y805542D01*
X78175Y805334D01*
X77967Y805084D01*
X77800Y804667D01*
X77758Y804292D01*
X77842Y803917D01*
X77967Y803667D01*
X78217Y803417D01*
X78508Y803250D01*
X78800Y803167D01*
X79092D01*
X79383Y803250D01*
X79633Y803375D01*
X79842Y803542D01*
G01X81817Y803167D02*
X81900Y803709D01*
X82025Y804167D01*
X82192Y804584D01*
X82400Y805042D01*
X82733Y805667D01*
X81067D01*
G01X84208Y805250D02*
X84458Y805500D01*
X84750Y805625D01*
X85083Y805667D01*
X85500Y805584D01*
X85792Y805375D01*
X85875Y805125D01*
X85833Y804875D01*
X85667Y804667D01*
X84833Y804250D01*
X84458Y803959D01*
X84208Y803542D01*
X84125Y803167D01*
X85875D01*
G01X88017D02*
X88100Y803709D01*
X88225Y804167D01*
X88392Y804584D01*
X88600Y805042D01*
X88933Y805667D01*
X87267D01*
G01X90408Y804209D02*
X90700Y804500D01*
X90950Y804667D01*
X91283Y804750D01*
X91575Y804667D01*
X91783Y804500D01*
X91950Y804250D01*
X91992Y803959D01*
X91950Y803709D01*
X91783Y803459D01*
X91533Y803250D01*
X91242Y803167D01*
X90908Y803250D01*
X90617Y803500D01*
X90450Y803875D01*
X90408Y804292D01*
X90492Y804834D01*
X90617Y805125D01*
X90825Y805417D01*
X91117Y805625D01*
X91408Y805667D01*
X91700Y805584D01*
X91908Y805375D01*
G01X79717Y817459D02*
X79467Y817584D01*
X79175Y817667D01*
X78842D01*
X78467Y817542D01*
X78175Y817334D01*
X77967Y817084D01*
X77800Y816667D01*
X77758Y816292D01*
X77842Y815917D01*
X77967Y815667D01*
X78217Y815417D01*
X78508Y815250D01*
X78800Y815167D01*
X79092D01*
X79383Y815250D01*
X79633Y815375D01*
X79842Y815542D01*
G01X81817Y815167D02*
X81900Y815709D01*
X82025Y816167D01*
X82192Y816584D01*
X82400Y817042D01*
X82733Y817667D01*
X81067D01*
G01X84208Y817250D02*
X84458Y817500D01*
X84750Y817625D01*
X85083Y817667D01*
X85500Y817584D01*
X85792Y817375D01*
X85875Y817125D01*
X85833Y816875D01*
X85667Y816667D01*
X84833Y816250D01*
X84458Y815959D01*
X84208Y815542D01*
X84125Y815167D01*
X85875D01*
G01X88017D02*
X88100Y815709D01*
X88225Y816167D01*
X88392Y816584D01*
X88600Y817042D01*
X88933Y817667D01*
X87267D01*
G01X90283Y815542D02*
X90533Y815334D01*
X90825Y815209D01*
X91200Y815167D01*
X91575Y815250D01*
X91867Y815417D01*
X92075Y815709D01*
X92117Y816042D01*
X92033Y816375D01*
X91825Y816584D01*
X91533Y816750D01*
X91242Y816792D01*
X90950Y816750D01*
X90575Y816584D01*
X90700Y817667D01*
X91825D01*
G01X77967Y807167D02*
Y809667D01*
X79008D01*
X79342Y809542D01*
X79550Y809375D01*
X79633Y809042D01*
X79550Y808709D01*
X79300Y808500D01*
X79008Y808375D01*
X77967D01*
G01X79008D02*
X79633Y807167D01*
G01X81108Y809250D02*
X81358Y809500D01*
X81650Y809625D01*
X81983Y809667D01*
X82400Y809584D01*
X82692Y809375D01*
X82775Y809125D01*
X82733Y808875D01*
X82567Y808667D01*
X81733Y808250D01*
X81358Y807959D01*
X81108Y807542D01*
X81025Y807167D01*
X82775D01*
G01X85000D02*
Y809667D01*
X84500Y809167D01*
G01Y807167D02*
X85500D01*
G01X88100Y809667D02*
X87767Y809584D01*
X87517Y809375D01*
X87350Y809125D01*
X87225Y808792D01*
X87183Y808417D01*
X87225Y808042D01*
X87350Y807709D01*
X87517Y807459D01*
X87767Y807250D01*
X88100Y807167D01*
X88433Y807250D01*
X88683Y807459D01*
X88850Y807709D01*
X88975Y808042D01*
X89017Y808417D01*
X88975Y808792D01*
X88850Y809125D01*
X88683Y809375D01*
X88433Y809584D01*
X88100Y809667D01*
G01X90492Y807459D02*
X90783Y807250D01*
X91117Y807167D01*
X91450Y807250D01*
X91742Y807500D01*
X91950Y807875D01*
X92033Y808250D01*
Y808709D01*
X91950Y809084D01*
X91742Y809417D01*
X91492Y809584D01*
X91200Y809667D01*
X90867Y809584D01*
X90617Y809417D01*
X90450Y809167D01*
X90367Y808834D01*
X90450Y808542D01*
X90658Y808250D01*
X90908Y808084D01*
X91200Y808042D01*
X91533Y808125D01*
X91783Y808334D01*
X92033Y808709D01*
G01X77967Y811167D02*
Y813667D01*
X79008D01*
X79342Y813542D01*
X79550Y813375D01*
X79633Y813042D01*
X79550Y812709D01*
X79300Y812500D01*
X79008Y812375D01*
X77967D01*
G01X79008D02*
X79633Y811167D01*
G01X81108Y813250D02*
X81358Y813500D01*
X81650Y813625D01*
X81983Y813667D01*
X82400Y813584D01*
X82692Y813375D01*
X82775Y813125D01*
X82733Y812875D01*
X82567Y812667D01*
X81733Y812250D01*
X81358Y811959D01*
X81108Y811542D01*
X81025Y811167D01*
X82775D01*
G01X85000D02*
Y813667D01*
X84500Y813167D01*
G01Y811167D02*
X85500D01*
G01X88100Y813667D02*
X87767Y813584D01*
X87517Y813375D01*
X87350Y813125D01*
X87225Y812792D01*
X87183Y812417D01*
X87225Y812042D01*
X87350Y811709D01*
X87517Y811459D01*
X87767Y811250D01*
X88100Y811167D01*
X88433Y811250D01*
X88683Y811459D01*
X88850Y811709D01*
X88975Y812042D01*
X89017Y812417D01*
X88975Y812792D01*
X88850Y813125D01*
X88683Y813375D01*
X88433Y813584D01*
X88100Y813667D01*
G01X91200Y811167D02*
X91492Y811209D01*
X91825Y811334D01*
X92033Y811542D01*
X92117Y811834D01*
X92033Y812125D01*
X91783Y812375D01*
X91408Y812500D01*
X90992D01*
X90742Y812584D01*
X90533Y812792D01*
X90450Y813084D01*
X90575Y813375D01*
X90867Y813584D01*
X91200Y813667D01*
X91533Y813584D01*
X91825Y813375D01*
X91950Y813084D01*
X91867Y812792D01*
X91658Y812584D01*
X91408Y812500D01*
X90992D01*
X90617Y812375D01*
X90367Y812125D01*
X90283Y811834D01*
X90367Y811542D01*
X90575Y811334D01*
X90908Y811209D01*
X91200Y811167D01*
G01X77967Y799167D02*
Y801667D01*
X79008D01*
X79342Y801542D01*
X79550Y801375D01*
X79633Y801042D01*
X79550Y800709D01*
X79300Y800500D01*
X79008Y800375D01*
X77967D01*
G01X79008D02*
X79633Y799167D01*
G01X81108Y801250D02*
X81358Y801500D01*
X81650Y801625D01*
X81983Y801667D01*
X82400Y801584D01*
X82692Y801375D01*
X82775Y801125D01*
X82733Y800875D01*
X82567Y800667D01*
X81733Y800250D01*
X81358Y799959D01*
X81108Y799542D01*
X81025Y799167D01*
X82775D01*
G01X85000D02*
Y801667D01*
X84500Y801167D01*
G01Y799167D02*
X85500D01*
G01X88100Y801667D02*
X87767Y801584D01*
X87517Y801375D01*
X87350Y801125D01*
X87225Y800792D01*
X87183Y800417D01*
X87225Y800042D01*
X87350Y799709D01*
X87517Y799459D01*
X87767Y799250D01*
X88100Y799167D01*
X88433Y799250D01*
X88683Y799459D01*
X88850Y799709D01*
X88975Y800042D01*
X89017Y800417D01*
X88975Y800792D01*
X88850Y801125D01*
X88683Y801375D01*
X88433Y801584D01*
X88100Y801667D01*
G01X91117Y799167D02*
X91200Y799709D01*
X91325Y800167D01*
X91492Y800584D01*
X91700Y801042D01*
X92033Y801667D01*
X90367D01*
G01X78467Y819167D02*
Y821667D01*
X79508D01*
X79842Y821542D01*
X80050Y821375D01*
X80133Y821042D01*
X80050Y820709D01*
X79800Y820500D01*
X79508Y820375D01*
X78467D01*
G01X79508D02*
X80133Y819167D01*
G01X81608Y821250D02*
X81858Y821500D01*
X82150Y821625D01*
X82483Y821667D01*
X82900Y821584D01*
X83192Y821375D01*
X83275Y821125D01*
X83233Y820875D01*
X83067Y820667D01*
X82233Y820250D01*
X81858Y819959D01*
X81608Y819542D01*
X81525Y819167D01*
X83275D01*
G01X85500D02*
Y821667D01*
X85000Y821167D01*
G01Y819167D02*
X86000D01*
G01X88600Y821667D02*
X88267Y821584D01*
X88017Y821375D01*
X87850Y821125D01*
X87725Y820792D01*
X87683Y820417D01*
X87725Y820042D01*
X87850Y819709D01*
X88017Y819459D01*
X88267Y819250D01*
X88600Y819167D01*
X88933Y819250D01*
X89183Y819459D01*
X89350Y819709D01*
X89475Y820042D01*
X89517Y820417D01*
X89475Y820792D01*
X89350Y821125D01*
X89183Y821375D01*
X88933Y821584D01*
X88600Y821667D01*
G01X90908Y820209D02*
X91200Y820500D01*
X91450Y820667D01*
X91783Y820750D01*
X92075Y820667D01*
X92283Y820500D01*
X92450Y820250D01*
X92492Y819959D01*
X92450Y819709D01*
X92283Y819459D01*
X92033Y819250D01*
X91742Y819167D01*
X91408Y819250D01*
X91117Y819500D01*
X90950Y819875D01*
X90908Y820292D01*
X90992Y820834D01*
X91117Y821125D01*
X91325Y821417D01*
X91617Y821625D01*
X91908Y821667D01*
X92200Y821584D01*
X92408Y821375D01*
G01X116700Y108097D02*
X114200D01*
Y109138D01*
X114325Y109472D01*
X114492Y109680D01*
X114825Y109763D01*
X115158Y109680D01*
X115367Y109430D01*
X115492Y109138D01*
Y108097D01*
G01Y109138D02*
X116700Y109763D01*
G01Y112530D02*
X114200D01*
X115992Y110988D01*
Y113072D01*
G01X116700Y115630D02*
X114200D01*
X115992Y114088D01*
Y116172D01*
G01X115658Y117438D02*
X115367Y117730D01*
X115200Y117980D01*
X115117Y118313D01*
X115200Y118605D01*
X115367Y118813D01*
X115617Y118980D01*
X115908Y119022D01*
X116158Y118980D01*
X116408Y118813D01*
X116617Y118563D01*
X116700Y118272D01*
X116617Y117938D01*
X116367Y117647D01*
X115992Y117480D01*
X115575Y117438D01*
X115033Y117522D01*
X114742Y117647D01*
X114450Y117855D01*
X114242Y118147D01*
X114200Y118438D01*
X114283Y118730D01*
X114492Y118938D01*
G01X118681Y102402D02*
X177381D01*
G01Y101374D02*
X118681D01*
Y137124D01*
X115831D01*
Y148624D01*
X118681D01*
Y163474D01*
X177381D01*
Y148624D01*
X180231D01*
Y137124D01*
X177381D01*
Y101374D01*
G01X109384Y139477D02*
X106884D01*
Y140518D01*
X107009Y140852D01*
X107176Y141060D01*
X107509Y141143D01*
X107842Y141060D01*
X108051Y140810D01*
X108176Y140518D01*
Y139477D01*
G01Y140518D02*
X109384Y141143D01*
G01X109009Y142493D02*
X109217Y142743D01*
X109342Y143035D01*
X109384Y143410D01*
X109301Y143785D01*
X109134Y144077D01*
X108842Y144285D01*
X108509Y144327D01*
X108176Y144243D01*
X107967Y144035D01*
X107801Y143743D01*
X107759Y143452D01*
X107801Y143160D01*
X107967Y142785D01*
X106884Y142910D01*
Y144035D01*
G01X109384Y147010D02*
X106884D01*
X108676Y145468D01*
Y147552D01*
G01X106884Y149610D02*
X106967Y149277D01*
X107176Y149027D01*
X107426Y148860D01*
X107759Y148735D01*
X108134Y148693D01*
X108509Y148735D01*
X108842Y148860D01*
X109092Y149027D01*
X109301Y149277D01*
X109384Y149610D01*
X109301Y149943D01*
X109092Y150193D01*
X108842Y150360D01*
X108509Y150485D01*
X108134Y150527D01*
X107759Y150485D01*
X107426Y150360D01*
X107176Y150193D01*
X106967Y149943D01*
X106884Y149610D01*
G01X106050Y129760D02*
X110050D01*
Y137160D01*
G01X103092Y140727D02*
X102967Y140477D01*
X102884Y140185D01*
Y139852D01*
X103009Y139477D01*
X103217Y139185D01*
X103467Y138977D01*
X103884Y138810D01*
X104259Y138768D01*
X104634Y138852D01*
X104884Y138977D01*
X105134Y139227D01*
X105301Y139518D01*
X105384Y139810D01*
Y140102D01*
X105301Y140393D01*
X105176Y140643D01*
X105009Y140852D01*
G01X105384Y143410D02*
X102884D01*
X104676Y141868D01*
Y143952D01*
G01X103301Y145218D02*
X103051Y145468D01*
X102926Y145760D01*
X102884Y146093D01*
X102967Y146510D01*
X103176Y146802D01*
X103426Y146885D01*
X103676Y146843D01*
X103884Y146677D01*
X104301Y145843D01*
X104592Y145468D01*
X105009Y145218D01*
X105384Y145135D01*
Y146885D01*
G01X102884Y149110D02*
X102967Y148777D01*
X103176Y148527D01*
X103426Y148360D01*
X103759Y148235D01*
X104134Y148193D01*
X104509Y148235D01*
X104842Y148360D01*
X105092Y148527D01*
X105301Y148777D01*
X105384Y149110D01*
X105301Y149443D01*
X105092Y149693D01*
X104842Y149860D01*
X104509Y149985D01*
X104134Y150027D01*
X103759Y149985D01*
X103426Y149860D01*
X103176Y149693D01*
X102967Y149443D01*
X102884Y149110D01*
G01X111027Y169943D02*
Y166360D01*
X111360Y165610D01*
X112027Y165110D01*
X112860Y164943D01*
X113693Y165110D01*
X114360Y165610D01*
X114693Y166360D01*
Y169943D01*
G01X116710Y165610D02*
X117377Y165193D01*
X118127Y164943D01*
X118793D01*
X119460Y165193D01*
X119960Y165610D01*
X120210Y166193D01*
X120043Y166776D01*
X119627Y167276D01*
X118877Y167610D01*
X117877Y167776D01*
X117293Y168110D01*
X117043Y168693D01*
X117210Y169276D01*
X117627Y169693D01*
X118210Y169943D01*
X118793D01*
X119377Y169776D01*
X119877Y169360D01*
G01X124727Y167610D02*
X125060Y167860D01*
X125310Y168276D01*
X125477Y168860D01*
X125310Y169360D01*
X124977Y169693D01*
X124393Y169943D01*
X122143D01*
Y164943D01*
X124893D01*
X125477Y165276D01*
X125810Y165776D01*
X125977Y166360D01*
X125810Y166943D01*
X125310Y167443D01*
X124727Y167610D01*
X122143D01*
G01X128077Y169110D02*
X128577Y169610D01*
X129160Y169860D01*
X129827Y169943D01*
X130660Y169776D01*
X131243Y169360D01*
X131410Y168860D01*
X131327Y168360D01*
X130993Y167943D01*
X129327Y167110D01*
X128577Y166526D01*
X128077Y165693D01*
X127910Y164943D01*
X131410D01*
G01X135260Y164776D02*
X135093Y164860D01*
Y165026D01*
X135260Y165110D01*
X135427Y165026D01*
Y164860D01*
X135260Y164776D01*
G01X140860Y169943D02*
X140193Y169776D01*
X139693Y169360D01*
X139360Y168860D01*
X139110Y168193D01*
X139027Y167443D01*
X139110Y166693D01*
X139360Y166026D01*
X139693Y165526D01*
X140193Y165110D01*
X140860Y164943D01*
X141527Y165110D01*
X142027Y165526D01*
X142360Y166026D01*
X142610Y166693D01*
X142693Y167443D01*
X142610Y168193D01*
X142360Y168860D01*
X142027Y169360D01*
X141527Y169776D01*
X140860Y169943D01*
G01X104834Y158017D02*
X102334D01*
Y159058D01*
X102459Y159392D01*
X102626Y159600D01*
X102959Y159683D01*
X103292Y159600D01*
X103501Y159350D01*
X103626Y159058D01*
Y158017D01*
G01Y159058D02*
X104834Y159683D01*
G01X104459Y161033D02*
X104667Y161283D01*
X104792Y161575D01*
X104834Y161950D01*
X104751Y162325D01*
X104584Y162617D01*
X104292Y162825D01*
X103959Y162867D01*
X103626Y162783D01*
X103417Y162575D01*
X103251Y162283D01*
X103209Y161992D01*
X103251Y161700D01*
X103417Y161325D01*
X102334Y161450D01*
Y162575D01*
G01X104834Y165050D02*
X102334D01*
X102834Y164550D01*
G01X104834D02*
Y165550D01*
G01Y168650D02*
X102334D01*
X104126Y167108D01*
Y169192D01*
G01X108267Y174292D02*
X108017Y174417D01*
X107725Y174500D01*
X107392D01*
X107017Y174375D01*
X106725Y174167D01*
X106517Y173917D01*
X106350Y173500D01*
X106308Y173125D01*
X106392Y172750D01*
X106517Y172500D01*
X106767Y172250D01*
X107058Y172083D01*
X107350Y172000D01*
X107642D01*
X107933Y172083D01*
X108183Y172208D01*
X108392Y172375D01*
G01X109658Y174083D02*
X109908Y174333D01*
X110200Y174458D01*
X110533Y174500D01*
X110950Y174417D01*
X111242Y174208D01*
X111325Y173958D01*
X111283Y173708D01*
X111117Y173500D01*
X110283Y173083D01*
X109908Y172792D01*
X109658Y172375D01*
X109575Y172000D01*
X111325D01*
G01X112633Y172500D02*
X112883Y172208D01*
X113217Y172042D01*
X113592Y172000D01*
X113925Y172042D01*
X114258Y172250D01*
X114467Y172500D01*
X114508Y172750D01*
X114425Y173042D01*
X114133Y173250D01*
X113842Y173333D01*
X113467D01*
G01X113842D02*
X114092Y173458D01*
X114300Y173667D01*
X114383Y173917D01*
X114300Y174167D01*
X114092Y174375D01*
X113717Y174500D01*
X113342Y174458D01*
X112967Y174292D01*
G01X116650Y172000D02*
X116942Y172042D01*
X117275Y172167D01*
X117483Y172375D01*
X117567Y172667D01*
X117483Y172958D01*
X117233Y173208D01*
X116858Y173333D01*
X116442D01*
X116192Y173417D01*
X115983Y173625D01*
X115900Y173917D01*
X116025Y174208D01*
X116317Y174417D01*
X116650Y174500D01*
X116983Y174417D01*
X117275Y174208D01*
X117400Y173917D01*
X117317Y173625D01*
X117108Y173417D01*
X116858Y173333D01*
X116442D01*
X116067Y173208D01*
X115817Y172958D01*
X115733Y172667D01*
X115817Y172375D01*
X116025Y172167D01*
X116358Y172042D01*
X116650Y172000D01*
G01X108267Y178292D02*
X108017Y178417D01*
X107725Y178500D01*
X107392D01*
X107017Y178375D01*
X106725Y178167D01*
X106517Y177917D01*
X106350Y177500D01*
X106308Y177125D01*
X106392Y176750D01*
X106517Y176500D01*
X106767Y176250D01*
X107058Y176083D01*
X107350Y176000D01*
X107642D01*
X107933Y176083D01*
X108183Y176208D01*
X108392Y176375D01*
G01X109533Y176500D02*
X109783Y176208D01*
X110117Y176042D01*
X110492Y176000D01*
X110825Y176042D01*
X111158Y176250D01*
X111367Y176500D01*
X111408Y176750D01*
X111325Y177042D01*
X111033Y177250D01*
X110742Y177333D01*
X110367D01*
G01X110742D02*
X110992Y177458D01*
X111200Y177667D01*
X111283Y177917D01*
X111200Y178167D01*
X110992Y178375D01*
X110617Y178500D01*
X110242Y178458D01*
X109867Y178292D01*
G01X112633Y176500D02*
X112883Y176208D01*
X113217Y176042D01*
X113592Y176000D01*
X113925Y176042D01*
X114258Y176250D01*
X114467Y176500D01*
X114508Y176750D01*
X114425Y177042D01*
X114133Y177250D01*
X113842Y177333D01*
X113467D01*
G01X113842D02*
X114092Y177458D01*
X114300Y177667D01*
X114383Y177917D01*
X114300Y178167D01*
X114092Y178375D01*
X113717Y178500D01*
X113342Y178458D01*
X112967Y178292D01*
G01X115858Y177042D02*
X116150Y177333D01*
X116400Y177500D01*
X116733Y177583D01*
X117025Y177500D01*
X117233Y177333D01*
X117400Y177083D01*
X117442Y176792D01*
X117400Y176542D01*
X117233Y176292D01*
X116983Y176083D01*
X116692Y176000D01*
X116358Y176083D01*
X116067Y176333D01*
X115900Y176708D01*
X115858Y177125D01*
X115942Y177667D01*
X116067Y177958D01*
X116275Y178250D01*
X116567Y178458D01*
X116858Y178500D01*
X117150Y178417D01*
X117358Y178208D01*
G01X103042Y175767D02*
X102917Y175517D01*
X102834Y175225D01*
Y174892D01*
X102959Y174517D01*
X103167Y174225D01*
X103417Y174017D01*
X103834Y173850D01*
X104209Y173808D01*
X104584Y173892D01*
X104834Y174017D01*
X105084Y174267D01*
X105251Y174558D01*
X105334Y174850D01*
Y175142D01*
X105251Y175433D01*
X105126Y175683D01*
X104959Y175892D01*
G01X104834Y177033D02*
X105126Y177283D01*
X105292Y177617D01*
X105334Y177992D01*
X105292Y178325D01*
X105084Y178658D01*
X104834Y178867D01*
X104584Y178908D01*
X104292Y178825D01*
X104084Y178533D01*
X104001Y178242D01*
Y177867D01*
G01Y178242D02*
X103876Y178492D01*
X103667Y178700D01*
X103417Y178783D01*
X103167Y178700D01*
X102959Y178492D01*
X102834Y178117D01*
X102876Y177742D01*
X103042Y177367D01*
G01X104834Y180133D02*
X105126Y180383D01*
X105292Y180717D01*
X105334Y181092D01*
X105292Y181425D01*
X105084Y181758D01*
X104834Y181967D01*
X104584Y182008D01*
X104292Y181925D01*
X104084Y181633D01*
X104001Y181342D01*
Y180967D01*
G01Y181342D02*
X103876Y181592D01*
X103667Y181800D01*
X103417Y181883D01*
X103167Y181800D01*
X102959Y181592D01*
X102834Y181217D01*
X102876Y180842D01*
X103042Y180467D01*
G01X105334Y184650D02*
X102834D01*
X104626Y183108D01*
Y185192D01*
G01X108267Y186292D02*
X108017Y186417D01*
X107725Y186500D01*
X107392D01*
X107017Y186375D01*
X106725Y186167D01*
X106517Y185917D01*
X106350Y185500D01*
X106308Y185125D01*
X106392Y184750D01*
X106517Y184500D01*
X106767Y184250D01*
X107058Y184083D01*
X107350Y184000D01*
X107642D01*
X107933Y184083D01*
X108183Y184208D01*
X108392Y184375D01*
G01X109533Y184500D02*
X109783Y184208D01*
X110117Y184042D01*
X110492Y184000D01*
X110825Y184042D01*
X111158Y184250D01*
X111367Y184500D01*
X111408Y184750D01*
X111325Y185042D01*
X111033Y185250D01*
X110742Y185333D01*
X110367D01*
G01X110742D02*
X110992Y185458D01*
X111200Y185667D01*
X111283Y185917D01*
X111200Y186167D01*
X110992Y186375D01*
X110617Y186500D01*
X110242Y186458D01*
X109867Y186292D01*
G01X112633Y184500D02*
X112883Y184208D01*
X113217Y184042D01*
X113592Y184000D01*
X113925Y184042D01*
X114258Y184250D01*
X114467Y184500D01*
X114508Y184750D01*
X114425Y185042D01*
X114133Y185250D01*
X113842Y185333D01*
X113467D01*
G01X113842D02*
X114092Y185458D01*
X114300Y185667D01*
X114383Y185917D01*
X114300Y186167D01*
X114092Y186375D01*
X113717Y186500D01*
X113342Y186458D01*
X112967Y186292D01*
G01X116650Y184000D02*
X116942Y184042D01*
X117275Y184167D01*
X117483Y184375D01*
X117567Y184667D01*
X117483Y184958D01*
X117233Y185208D01*
X116858Y185333D01*
X116442D01*
X116192Y185417D01*
X115983Y185625D01*
X115900Y185917D01*
X116025Y186208D01*
X116317Y186417D01*
X116650Y186500D01*
X116983Y186417D01*
X117275Y186208D01*
X117400Y185917D01*
X117317Y185625D01*
X117108Y185417D01*
X116858Y185333D01*
X116442D01*
X116067Y185208D01*
X115817Y184958D01*
X115733Y184667D01*
X115817Y184375D01*
X116025Y184167D01*
X116358Y184042D01*
X116650Y184000D01*
G01X108267Y182292D02*
X108017Y182417D01*
X107725Y182500D01*
X107392D01*
X107017Y182375D01*
X106725Y182167D01*
X106517Y181917D01*
X106350Y181500D01*
X106308Y181125D01*
X106392Y180750D01*
X106517Y180500D01*
X106767Y180250D01*
X107058Y180083D01*
X107350Y180000D01*
X107642D01*
X107933Y180083D01*
X108183Y180208D01*
X108392Y180375D01*
G01X109533Y180500D02*
X109783Y180208D01*
X110117Y180042D01*
X110492Y180000D01*
X110825Y180042D01*
X111158Y180250D01*
X111367Y180500D01*
X111408Y180750D01*
X111325Y181042D01*
X111033Y181250D01*
X110742Y181333D01*
X110367D01*
G01X110742D02*
X110992Y181458D01*
X111200Y181667D01*
X111283Y181917D01*
X111200Y182167D01*
X110992Y182375D01*
X110617Y182500D01*
X110242Y182458D01*
X109867Y182292D01*
G01X112633Y180500D02*
X112883Y180208D01*
X113217Y180042D01*
X113592Y180000D01*
X113925Y180042D01*
X114258Y180250D01*
X114467Y180500D01*
X114508Y180750D01*
X114425Y181042D01*
X114133Y181250D01*
X113842Y181333D01*
X113467D01*
G01X113842D02*
X114092Y181458D01*
X114300Y181667D01*
X114383Y181917D01*
X114300Y182167D01*
X114092Y182375D01*
X113717Y182500D01*
X113342Y182458D01*
X112967Y182292D01*
G01X116567Y180000D02*
X116650Y180542D01*
X116775Y181000D01*
X116942Y181417D01*
X117150Y181875D01*
X117483Y182500D01*
X115817D01*
G01X108267Y190292D02*
X108017Y190417D01*
X107725Y190500D01*
X107392D01*
X107017Y190375D01*
X106725Y190167D01*
X106517Y189917D01*
X106350Y189500D01*
X106308Y189125D01*
X106392Y188750D01*
X106517Y188500D01*
X106767Y188250D01*
X107058Y188083D01*
X107350Y188000D01*
X107642D01*
X107933Y188083D01*
X108183Y188208D01*
X108392Y188375D01*
G01X109658Y190083D02*
X109908Y190333D01*
X110200Y190458D01*
X110533Y190500D01*
X110950Y190417D01*
X111242Y190208D01*
X111325Y189958D01*
X111283Y189708D01*
X111117Y189500D01*
X110283Y189083D01*
X109908Y188792D01*
X109658Y188375D01*
X109575Y188000D01*
X111325D01*
G01X114050D02*
Y190500D01*
X112508Y188708D01*
X114592D01*
G01X116650Y190500D02*
X116317Y190417D01*
X116067Y190208D01*
X115900Y189958D01*
X115775Y189625D01*
X115733Y189250D01*
X115775Y188875D01*
X115900Y188542D01*
X116067Y188292D01*
X116317Y188083D01*
X116650Y188000D01*
X116983Y188083D01*
X117233Y188292D01*
X117400Y188542D01*
X117525Y188875D01*
X117567Y189250D01*
X117525Y189625D01*
X117400Y189958D01*
X117233Y190208D01*
X116983Y190417D01*
X116650Y190500D01*
G01X103042Y188767D02*
X102917Y188517D01*
X102834Y188225D01*
Y187892D01*
X102959Y187517D01*
X103167Y187225D01*
X103417Y187017D01*
X103834Y186850D01*
X104209Y186808D01*
X104584Y186892D01*
X104834Y187017D01*
X105084Y187267D01*
X105251Y187558D01*
X105334Y187850D01*
Y188142D01*
X105251Y188433D01*
X105126Y188683D01*
X104959Y188892D01*
G01X104834Y190033D02*
X105126Y190283D01*
X105292Y190617D01*
X105334Y190992D01*
X105292Y191325D01*
X105084Y191658D01*
X104834Y191867D01*
X104584Y191908D01*
X104292Y191825D01*
X104084Y191533D01*
X104001Y191242D01*
Y190867D01*
G01Y191242D02*
X103876Y191492D01*
X103667Y191700D01*
X103417Y191783D01*
X103167Y191700D01*
X102959Y191492D01*
X102834Y191117D01*
X102876Y190742D01*
X103042Y190367D01*
G01X104834Y193133D02*
X105126Y193383D01*
X105292Y193717D01*
X105334Y194092D01*
X105292Y194425D01*
X105084Y194758D01*
X104834Y194967D01*
X104584Y195008D01*
X104292Y194925D01*
X104084Y194633D01*
X104001Y194342D01*
Y193967D01*
G01Y194342D02*
X103876Y194592D01*
X103667Y194800D01*
X103417Y194883D01*
X103167Y194800D01*
X102959Y194592D01*
X102834Y194217D01*
X102876Y193842D01*
X103042Y193467D01*
G01X104959Y196233D02*
X105167Y196483D01*
X105292Y196775D01*
X105334Y197150D01*
X105251Y197525D01*
X105084Y197817D01*
X104792Y198025D01*
X104459Y198067D01*
X104126Y197983D01*
X103917Y197775D01*
X103751Y197483D01*
X103709Y197192D01*
X103751Y196900D01*
X103917Y196525D01*
X102834Y196650D01*
Y197775D01*
G01X120350Y228500D02*
Y226000D01*
G01X119392Y228500D02*
X121308D01*
G01X124367Y228292D02*
X124117Y228417D01*
X123825Y228500D01*
X123492D01*
X123117Y228375D01*
X122825Y228167D01*
X122617Y227917D01*
X122450Y227500D01*
X122408Y227125D01*
X122492Y226750D01*
X122617Y226500D01*
X122867Y226250D01*
X123158Y226083D01*
X123450Y226000D01*
X123742D01*
X124033Y226083D01*
X124283Y226208D01*
X124492Y226375D01*
G01X126550Y226000D02*
Y228500D01*
X126050Y228000D01*
G01Y226000D02*
X127050D01*
G01X129650D02*
Y228500D01*
X129150Y228000D01*
G01Y226000D02*
X130150D01*
G01X120350Y224500D02*
Y222000D01*
G01X119392Y224500D02*
X121308D01*
G01X124367Y224292D02*
X124117Y224417D01*
X123825Y224500D01*
X123492D01*
X123117Y224375D01*
X122825Y224167D01*
X122617Y223917D01*
X122450Y223500D01*
X122408Y223125D01*
X122492Y222750D01*
X122617Y222500D01*
X122867Y222250D01*
X123158Y222083D01*
X123450Y222000D01*
X123742D01*
X124033Y222083D01*
X124283Y222208D01*
X124492Y222375D01*
G01X126550Y222000D02*
Y224500D01*
X126050Y224000D01*
G01Y222000D02*
X127050D01*
G01X129650Y224500D02*
X129317Y224417D01*
X129067Y224208D01*
X128900Y223958D01*
X128775Y223625D01*
X128733Y223250D01*
X128775Y222875D01*
X128900Y222542D01*
X129067Y222292D01*
X129317Y222083D01*
X129650Y222000D01*
X129983Y222083D01*
X130233Y222292D01*
X130400Y222542D01*
X130525Y222875D01*
X130567Y223250D01*
X130525Y223625D01*
X130400Y223958D01*
X130233Y224208D01*
X129983Y224417D01*
X129650Y224500D01*
G01X120350Y232500D02*
Y230000D01*
G01X119392Y232500D02*
X121308D01*
G01X124367Y232292D02*
X124117Y232417D01*
X123825Y232500D01*
X123492D01*
X123117Y232375D01*
X122825Y232167D01*
X122617Y231917D01*
X122450Y231500D01*
X122408Y231125D01*
X122492Y230750D01*
X122617Y230500D01*
X122867Y230250D01*
X123158Y230083D01*
X123450Y230000D01*
X123742D01*
X124033Y230083D01*
X124283Y230208D01*
X124492Y230375D01*
G01X126550Y230000D02*
Y232500D01*
X126050Y232000D01*
G01Y230000D02*
X127050D01*
G01X128858Y232083D02*
X129108Y232333D01*
X129400Y232458D01*
X129733Y232500D01*
X130150Y232417D01*
X130442Y232208D01*
X130525Y231958D01*
X130483Y231708D01*
X130317Y231500D01*
X129483Y231083D01*
X129108Y230792D01*
X128858Y230375D01*
X128775Y230000D01*
X130525D01*
G01X102972Y219625D02*
Y222125D01*
X104013D01*
X104347Y222000D01*
X104555Y221833D01*
X104638Y221500D01*
X104555Y221167D01*
X104305Y220958D01*
X104013Y220833D01*
X102972D01*
G01X104013D02*
X104638Y219625D01*
G01X105988Y220000D02*
X106238Y219792D01*
X106530Y219667D01*
X106905Y219625D01*
X107280Y219708D01*
X107572Y219875D01*
X107780Y220167D01*
X107822Y220500D01*
X107738Y220833D01*
X107530Y221042D01*
X107238Y221208D01*
X106947Y221250D01*
X106655Y221208D01*
X106280Y221042D01*
X106405Y222125D01*
X107530D01*
G01X109088Y220125D02*
X109338Y219833D01*
X109672Y219667D01*
X110047Y219625D01*
X110380Y219667D01*
X110713Y219875D01*
X110922Y220125D01*
X110963Y220375D01*
X110880Y220667D01*
X110588Y220875D01*
X110297Y220958D01*
X109922D01*
G01X110297D02*
X110547Y221083D01*
X110755Y221292D01*
X110838Y221542D01*
X110755Y221792D01*
X110547Y222000D01*
X110172Y222125D01*
X109797Y222083D01*
X109422Y221917D01*
G01X112397Y219917D02*
X112688Y219708D01*
X113022Y219625D01*
X113355Y219708D01*
X113647Y219958D01*
X113855Y220333D01*
X113938Y220708D01*
Y221167D01*
X113855Y221542D01*
X113647Y221875D01*
X113397Y222042D01*
X113105Y222125D01*
X112772Y222042D01*
X112522Y221875D01*
X112355Y221625D01*
X112272Y221292D01*
X112355Y221000D01*
X112563Y220708D01*
X112813Y220542D01*
X113105Y220500D01*
X113438Y220583D01*
X113688Y220792D01*
X113938Y221167D01*
G01X105100Y214200D02*
Y210200D01*
X112500D01*
G01X104080Y223700D02*
Y226200D01*
X105121D01*
X105455Y226075D01*
X105663Y225908D01*
X105746Y225575D01*
X105663Y225242D01*
X105413Y225033D01*
X105121Y224908D01*
X104080D01*
G01X105121D02*
X105746Y223700D01*
G01X107221Y225783D02*
X107471Y226033D01*
X107763Y226158D01*
X108096Y226200D01*
X108513Y226117D01*
X108805Y225908D01*
X108888Y225658D01*
X108846Y225408D01*
X108680Y225200D01*
X107846Y224783D01*
X107471Y224492D01*
X107221Y224075D01*
X107138Y223700D01*
X108888D01*
G01X110405Y223992D02*
X110696Y223783D01*
X111030Y223700D01*
X111363Y223783D01*
X111655Y224033D01*
X111863Y224408D01*
X111946Y224783D01*
Y225242D01*
X111863Y225617D01*
X111655Y225950D01*
X111405Y226117D01*
X111113Y226200D01*
X110780Y226117D01*
X110530Y225950D01*
X110363Y225700D01*
X110280Y225367D01*
X110363Y225075D01*
X110571Y224783D01*
X110821Y224617D01*
X111113Y224575D01*
X111446Y224658D01*
X111696Y224867D01*
X111946Y225242D01*
G01X114713Y223700D02*
Y226200D01*
X113171Y224408D01*
X115255D01*
G01X116605Y223992D02*
X116896Y223783D01*
X117230Y223700D01*
X117563Y223783D01*
X117855Y224033D01*
X118063Y224408D01*
X118146Y224783D01*
Y225242D01*
X118063Y225617D01*
X117855Y225950D01*
X117605Y226117D01*
X117313Y226200D01*
X116980Y226117D01*
X116730Y225950D01*
X116563Y225700D01*
X116480Y225367D01*
X116563Y225075D01*
X116771Y224783D01*
X117021Y224617D01*
X117313Y224575D01*
X117646Y224658D01*
X117896Y224867D01*
X118146Y225242D01*
G01X104100Y232100D02*
Y228100D01*
X111500D01*
G01X104722Y218417D02*
X104472Y218542D01*
X104180Y218625D01*
X103847D01*
X103472Y218500D01*
X103180Y218292D01*
X102972Y218042D01*
X102805Y217625D01*
X102763Y217250D01*
X102847Y216875D01*
X102972Y216625D01*
X103222Y216375D01*
X103513Y216208D01*
X103805Y216125D01*
X104097D01*
X104388Y216208D01*
X104638Y216333D01*
X104847Y216500D01*
G01X107405Y216125D02*
Y218625D01*
X105863Y216833D01*
X107947D01*
G01X110005Y216125D02*
Y218625D01*
X109505Y218125D01*
G01Y216125D02*
X110505D01*
G01X113605D02*
Y218625D01*
X112063Y216833D01*
X114147D01*
G01X111770Y290700D02*
Y272100D01*
G01X104500Y275200D02*
X108500D01*
Y282600D01*
G01X121367Y265492D02*
X121117Y265617D01*
X120825Y265700D01*
X120492D01*
X120117Y265575D01*
X119825Y265367D01*
X119617Y265117D01*
X119450Y264700D01*
X119408Y264325D01*
X119492Y263950D01*
X119617Y263700D01*
X119867Y263450D01*
X120158Y263283D01*
X120450Y263200D01*
X120742D01*
X121033Y263283D01*
X121283Y263408D01*
X121492Y263575D01*
G01X122633Y263700D02*
X122883Y263408D01*
X123217Y263242D01*
X123592Y263200D01*
X123925Y263242D01*
X124258Y263450D01*
X124467Y263700D01*
X124508Y263950D01*
X124425Y264242D01*
X124133Y264450D01*
X123842Y264533D01*
X123467D01*
G01X123842D02*
X124092Y264658D01*
X124300Y264867D01*
X124383Y265117D01*
X124300Y265367D01*
X124092Y265575D01*
X123717Y265700D01*
X123342Y265658D01*
X122967Y265492D01*
G01X125733Y263700D02*
X125983Y263408D01*
X126317Y263242D01*
X126692Y263200D01*
X127025Y263242D01*
X127358Y263450D01*
X127567Y263700D01*
X127608Y263950D01*
X127525Y264242D01*
X127233Y264450D01*
X126942Y264533D01*
X126567D01*
G01X126942D02*
X127192Y264658D01*
X127400Y264867D01*
X127483Y265117D01*
X127400Y265367D01*
X127192Y265575D01*
X126817Y265700D01*
X126442Y265658D01*
X126067Y265492D01*
G01X128958Y265283D02*
X129208Y265533D01*
X129500Y265658D01*
X129833Y265700D01*
X130250Y265617D01*
X130542Y265408D01*
X130625Y265158D01*
X130583Y264908D01*
X130417Y264700D01*
X129583Y264283D01*
X129208Y263992D01*
X128958Y263575D01*
X128875Y263200D01*
X130625D01*
G01X122967Y269092D02*
X122717Y269217D01*
X122425Y269300D01*
X122092D01*
X121717Y269175D01*
X121425Y268967D01*
X121217Y268717D01*
X121050Y268300D01*
X121008Y267925D01*
X121092Y267550D01*
X121217Y267300D01*
X121467Y267050D01*
X121758Y266883D01*
X122050Y266800D01*
X122342D01*
X122633Y266883D01*
X122883Y267008D01*
X123092Y267175D01*
G01X124358Y268883D02*
X124608Y269133D01*
X124900Y269258D01*
X125233Y269300D01*
X125650Y269217D01*
X125942Y269008D01*
X126025Y268758D01*
X125983Y268508D01*
X125817Y268300D01*
X124983Y267883D01*
X124608Y267592D01*
X124358Y267175D01*
X124275Y266800D01*
X126025D01*
G01X128250D02*
X128542Y266842D01*
X128875Y266967D01*
X129083Y267175D01*
X129167Y267467D01*
X129083Y267758D01*
X128833Y268008D01*
X128458Y268133D01*
X128042D01*
X127792Y268217D01*
X127583Y268425D01*
X127500Y268717D01*
X127625Y269008D01*
X127917Y269217D01*
X128250Y269300D01*
X128583Y269217D01*
X128875Y269008D01*
X129000Y268717D01*
X128917Y268425D01*
X128708Y268217D01*
X128458Y268133D01*
X128042D01*
X127667Y268008D01*
X127417Y267758D01*
X127333Y267467D01*
X127417Y267175D01*
X127625Y266967D01*
X127958Y266842D01*
X128250Y266800D01*
G01X130433Y267175D02*
X130683Y266967D01*
X130975Y266842D01*
X131350Y266800D01*
X131725Y266883D01*
X132017Y267050D01*
X132225Y267342D01*
X132267Y267675D01*
X132183Y268008D01*
X131975Y268217D01*
X131683Y268383D01*
X131392Y268425D01*
X131100Y268383D01*
X130725Y268217D01*
X130850Y269300D01*
X131975D01*
G01X111520Y338350D02*
X111770D01*
Y294300D01*
G01X117034Y282017D02*
X114534D01*
Y283017D01*
X114659Y283350D01*
X114951Y283600D01*
X115284Y283683D01*
X115617Y283600D01*
X115867Y283392D01*
X115992Y283017D01*
Y282017D01*
G01X114534Y285033D02*
X116326D01*
X116701Y285200D01*
X116951Y285533D01*
X117034Y285950D01*
X116951Y286367D01*
X116701Y286700D01*
X116326Y286867D01*
X114534D01*
G01X116659Y288133D02*
X116867Y288383D01*
X116992Y288675D01*
X117034Y289050D01*
X116951Y289425D01*
X116784Y289717D01*
X116492Y289925D01*
X116159Y289967D01*
X115826Y289883D01*
X115617Y289675D01*
X115451Y289383D01*
X115409Y289092D01*
X115451Y288800D01*
X115617Y288425D01*
X114534Y288550D01*
Y289675D01*
G01X117034Y292150D02*
X116992Y292442D01*
X116867Y292775D01*
X116659Y292983D01*
X116367Y293067D01*
X116076Y292983D01*
X115826Y292733D01*
X115701Y292358D01*
Y291942D01*
X115617Y291692D01*
X115409Y291483D01*
X115117Y291400D01*
X114826Y291525D01*
X114617Y291817D01*
X114534Y292150D01*
X114617Y292483D01*
X114826Y292775D01*
X115117Y292900D01*
X115409Y292817D01*
X115617Y292608D01*
X115701Y292358D01*
Y291942D01*
X115826Y291567D01*
X116076Y291317D01*
X116367Y291233D01*
X116659Y291317D01*
X116867Y291525D01*
X116992Y291858D01*
X117034Y292150D01*
G01X132850Y295100D02*
X118350D01*
G01D02*
Y290500D01*
G01D02*
X132850D01*
G01Y291200D02*
X131250Y292800D01*
G01D02*
X132850Y294400D01*
G01X115904Y310610D02*
X113404D01*
Y311610D01*
X113529Y311943D01*
X113821Y312193D01*
X114154Y312276D01*
X114487Y312193D01*
X114737Y311985D01*
X114862Y311610D01*
Y310610D01*
G01X113612Y315460D02*
X113487Y315210D01*
X113404Y314918D01*
Y314585D01*
X113529Y314210D01*
X113737Y313918D01*
X113987Y313710D01*
X114404Y313543D01*
X114779Y313501D01*
X115154Y313585D01*
X115404Y313710D01*
X115654Y313960D01*
X115821Y314251D01*
X115904Y314543D01*
Y314835D01*
X115821Y315126D01*
X115696Y315376D01*
X115529Y315585D01*
G01X115904Y317560D02*
X115362Y317643D01*
X114904Y317768D01*
X114487Y317935D01*
X114029Y318143D01*
X113404Y318476D01*
Y316810D01*
G01X115404Y319826D02*
X115696Y320076D01*
X115862Y320410D01*
X115904Y320785D01*
X115862Y321118D01*
X115654Y321451D01*
X115404Y321660D01*
X115154Y321701D01*
X114862Y321618D01*
X114654Y321326D01*
X114571Y321035D01*
Y320660D01*
G01Y321035D02*
X114446Y321285D01*
X114237Y321493D01*
X113987Y321576D01*
X113737Y321493D01*
X113529Y321285D01*
X113404Y320910D01*
X113446Y320535D01*
X113612Y320160D01*
G01X119017Y281800D02*
Y284300D01*
X120017D01*
X120350Y284175D01*
X120600Y283883D01*
X120683Y283550D01*
X120600Y283217D01*
X120392Y282967D01*
X120017Y282842D01*
X119017D01*
G01X123867Y284092D02*
X123617Y284217D01*
X123325Y284300D01*
X122992D01*
X122617Y284175D01*
X122325Y283967D01*
X122117Y283717D01*
X121950Y283300D01*
X121908Y282925D01*
X121992Y282550D01*
X122117Y282300D01*
X122367Y282050D01*
X122658Y281883D01*
X122950Y281800D01*
X123242D01*
X123533Y281883D01*
X123783Y282008D01*
X123992Y282175D01*
G01X125967Y281800D02*
X126050Y282342D01*
X126175Y282800D01*
X126342Y283217D01*
X126550Y283675D01*
X126883Y284300D01*
X125217D01*
G01X128358Y283883D02*
X128608Y284133D01*
X128900Y284258D01*
X129233Y284300D01*
X129650Y284217D01*
X129942Y284008D01*
X130025Y283758D01*
X129983Y283508D01*
X129817Y283300D01*
X128983Y282883D01*
X128608Y282592D01*
X128358Y282175D01*
X128275Y281800D01*
X130025D01*
G01X113268Y300696D02*
Y303196D01*
X114268D01*
X114601Y303071D01*
X114851Y302779D01*
X114934Y302446D01*
X114851Y302113D01*
X114643Y301863D01*
X114268Y301738D01*
X113268D01*
G01X116368Y300696D02*
Y303196D01*
X117409D01*
X117743Y303071D01*
X117951Y302904D01*
X118034Y302571D01*
X117951Y302238D01*
X117701Y302029D01*
X117409Y301904D01*
X116368D01*
G01X117409D02*
X118034Y300696D01*
G01X119509Y301738D02*
X119801Y302029D01*
X120051Y302196D01*
X120384Y302279D01*
X120676Y302196D01*
X120884Y302029D01*
X121051Y301779D01*
X121093Y301488D01*
X121051Y301238D01*
X120884Y300988D01*
X120634Y300779D01*
X120343Y300696D01*
X120009Y300779D01*
X119718Y301029D01*
X119551Y301404D01*
X119509Y301821D01*
X119593Y302363D01*
X119718Y302654D01*
X119926Y302946D01*
X120218Y303154D01*
X120509Y303196D01*
X120801Y303113D01*
X121009Y302904D01*
G01X122484Y301196D02*
X122734Y300904D01*
X123068Y300738D01*
X123443Y300696D01*
X123776Y300738D01*
X124109Y300946D01*
X124318Y301196D01*
X124359Y301446D01*
X124276Y301738D01*
X123984Y301946D01*
X123693Y302029D01*
X123318D01*
G01X123693D02*
X123943Y302154D01*
X124151Y302363D01*
X124234Y302613D01*
X124151Y302863D01*
X123943Y303071D01*
X123568Y303196D01*
X123193Y303154D01*
X122818Y302988D01*
G01X130480Y313214D02*
Y309214D01*
X137880D01*
G01X106500Y285200D02*
X110500D01*
Y292600D01*
G01Y300100D02*
X106500D01*
Y292700D01*
G01X106200Y296900D02*
Y300900D01*
X98800D01*
G01X106200D02*
Y304900D01*
X98800D01*
G01Y296900D02*
Y292900D01*
X106200D01*
G01X98800D02*
Y288900D01*
X106200D01*
G01X120204Y310610D02*
X117704D01*
Y311610D01*
X117829Y311943D01*
X118121Y312193D01*
X118454Y312276D01*
X118787Y312193D01*
X119037Y311985D01*
X119162Y311610D01*
Y310610D01*
G01X120204Y313710D02*
X117704D01*
Y314751D01*
X117829Y315085D01*
X117996Y315293D01*
X118329Y315376D01*
X118662Y315293D01*
X118871Y315043D01*
X118996Y314751D01*
Y313710D01*
G01Y314751D02*
X120204Y315376D01*
G01X119162Y316851D02*
X118871Y317143D01*
X118704Y317393D01*
X118621Y317726D01*
X118704Y318018D01*
X118871Y318226D01*
X119121Y318393D01*
X119412Y318435D01*
X119662Y318393D01*
X119912Y318226D01*
X120121Y317976D01*
X120204Y317685D01*
X120121Y317351D01*
X119871Y317060D01*
X119496Y316893D01*
X119079Y316851D01*
X118537Y316935D01*
X118246Y317060D01*
X117954Y317268D01*
X117746Y317560D01*
X117704Y317851D01*
X117787Y318143D01*
X117996Y318351D01*
G01X119829Y319826D02*
X120037Y320076D01*
X120162Y320368D01*
X120204Y320743D01*
X120121Y321118D01*
X119954Y321410D01*
X119662Y321618D01*
X119329Y321660D01*
X118996Y321576D01*
X118787Y321368D01*
X118621Y321076D01*
X118579Y320785D01*
X118621Y320493D01*
X118787Y320118D01*
X117704Y320243D01*
Y321368D01*
G01X130180Y316414D02*
X126180D01*
Y309014D01*
G01X98490Y321780D02*
Y317780D01*
X105890D01*
G01X98540Y317650D02*
Y313650D01*
X105940D01*
G01X98700Y326100D02*
Y322100D01*
X106100D01*
G01X98600Y330600D02*
Y326600D01*
X106000D01*
G01X105998Y346250D02*
X101998D01*
Y338850D01*
G01X101887Y346275D02*
X97887D01*
Y338875D01*
G01X105617Y338215D02*
X101617D01*
Y330815D01*
G01X124152Y326369D02*
X121652D01*
Y327410D01*
X121777Y327744D01*
X121944Y327952D01*
X122277Y328035D01*
X122610Y327952D01*
X122819Y327702D01*
X122944Y327410D01*
Y326369D01*
G01Y327410D02*
X124152Y328035D01*
G01Y330219D02*
X123610Y330302D01*
X123152Y330427D01*
X122735Y330594D01*
X122277Y330802D01*
X121652Y331135D01*
Y329469D01*
G01X123652Y332485D02*
X123944Y332735D01*
X124110Y333069D01*
X124152Y333444D01*
X124110Y333777D01*
X123902Y334110D01*
X123652Y334319D01*
X123402Y334360D01*
X123110Y334277D01*
X122902Y333985D01*
X122819Y333694D01*
Y333319D01*
G01Y333694D02*
X122694Y333944D01*
X122485Y334152D01*
X122235Y334235D01*
X121985Y334152D01*
X121777Y333944D01*
X121652Y333569D01*
X121694Y333194D01*
X121860Y332819D01*
G01X124152Y337002D02*
X121652D01*
X123444Y335460D01*
Y337544D01*
G01X133189Y321136D02*
X125189D01*
Y338736D01*
X133189D01*
Y321136D01*
G01X116834Y354762D02*
X118626D01*
X119001Y354929D01*
X119251Y355262D01*
X119334Y355679D01*
X119251Y356096D01*
X119001Y356429D01*
X118626Y356596D01*
X116834D01*
G01X119334Y358779D02*
X119292Y359071D01*
X119167Y359404D01*
X118959Y359612D01*
X118667Y359696D01*
X118376Y359612D01*
X118126Y359362D01*
X118001Y358987D01*
Y358571D01*
X117917Y358321D01*
X117709Y358112D01*
X117417Y358029D01*
X117126Y358154D01*
X116917Y358446D01*
X116834Y358779D01*
X116917Y359112D01*
X117126Y359404D01*
X117417Y359529D01*
X117709Y359446D01*
X117917Y359237D01*
X118001Y358987D01*
Y358571D01*
X118126Y358196D01*
X118376Y357946D01*
X118667Y357862D01*
X118959Y357946D01*
X119167Y358154D01*
X119292Y358487D01*
X119334Y358779D01*
G01X118834Y360962D02*
X119126Y361212D01*
X119292Y361546D01*
X119334Y361921D01*
X119292Y362254D01*
X119084Y362587D01*
X118834Y362796D01*
X118584Y362837D01*
X118292Y362754D01*
X118084Y362462D01*
X118001Y362171D01*
Y361796D01*
G01Y362171D02*
X117876Y362421D01*
X117667Y362629D01*
X117417Y362712D01*
X117167Y362629D01*
X116959Y362421D01*
X116834Y362046D01*
X116876Y361671D01*
X117042Y361296D01*
G01X115846Y354504D02*
X102446D01*
G01X115846Y364504D02*
Y354504D01*
G01X102446Y364504D02*
X115846D01*
G01X102446Y354504D02*
Y364504D01*
G01X127544Y367281D02*
X125044D01*
Y368322D01*
X125169Y368656D01*
X125336Y368864D01*
X125669Y368947D01*
X126002Y368864D01*
X126211Y368614D01*
X126336Y368322D01*
Y367281D01*
G01Y368322D02*
X127544Y368947D01*
G01X125461Y370422D02*
X125211Y370672D01*
X125086Y370964D01*
X125044Y371297D01*
X125127Y371714D01*
X125336Y372006D01*
X125586Y372089D01*
X125836Y372047D01*
X126044Y371881D01*
X126461Y371047D01*
X126752Y370672D01*
X127169Y370422D01*
X127544Y370339D01*
Y372089D01*
G01X127252Y373606D02*
X127461Y373897D01*
X127544Y374231D01*
X127461Y374564D01*
X127211Y374856D01*
X126836Y375064D01*
X126461Y375147D01*
X126002D01*
X125627Y375064D01*
X125294Y374856D01*
X125127Y374606D01*
X125044Y374314D01*
X125127Y373981D01*
X125294Y373731D01*
X125544Y373564D01*
X125877Y373481D01*
X126169Y373564D01*
X126461Y373772D01*
X126627Y374022D01*
X126669Y374314D01*
X126586Y374647D01*
X126377Y374897D01*
X126002Y375147D01*
G01X127544Y377914D02*
X125044D01*
X126836Y376372D01*
Y378456D01*
G01X127544Y381014D02*
X125044D01*
X126836Y379472D01*
Y381556D01*
G01X115761Y367106D02*
X119761D01*
Y374506D01*
G01X138214Y371985D02*
Y375985D01*
X130814D01*
G01X125377Y352888D02*
X125252Y352638D01*
X125169Y352346D01*
Y352013D01*
X125294Y351638D01*
X125502Y351346D01*
X125752Y351138D01*
X126169Y350971D01*
X126544Y350929D01*
X126919Y351013D01*
X127169Y351138D01*
X127419Y351388D01*
X127586Y351679D01*
X127669Y351971D01*
Y352263D01*
X127586Y352554D01*
X127461Y352804D01*
X127294Y353013D01*
G01X127169Y354154D02*
X127461Y354404D01*
X127627Y354738D01*
X127669Y355113D01*
X127627Y355446D01*
X127419Y355779D01*
X127169Y355988D01*
X126919Y356029D01*
X126627Y355946D01*
X126419Y355654D01*
X126336Y355363D01*
Y354988D01*
G01Y355363D02*
X126211Y355613D01*
X126002Y355821D01*
X125752Y355904D01*
X125502Y355821D01*
X125294Y355613D01*
X125169Y355238D01*
X125211Y354863D01*
X125377Y354488D01*
G01X125586Y357379D02*
X125336Y357629D01*
X125211Y357921D01*
X125169Y358254D01*
X125252Y358671D01*
X125461Y358963D01*
X125711Y359046D01*
X125961Y359004D01*
X126169Y358838D01*
X126586Y358004D01*
X126877Y357629D01*
X127294Y357379D01*
X127669Y357296D01*
Y359046D01*
G01Y361271D02*
X125169D01*
X125669Y360771D01*
G01X127669D02*
Y361771D01*
G01X126627Y363579D02*
X126336Y363871D01*
X126169Y364121D01*
X126086Y364454D01*
X126169Y364746D01*
X126336Y364954D01*
X126586Y365121D01*
X126877Y365163D01*
X127127Y365121D01*
X127377Y364954D01*
X127586Y364704D01*
X127669Y364413D01*
X127586Y364079D01*
X127336Y363788D01*
X126961Y363621D01*
X126544Y363579D01*
X126002Y363663D01*
X125711Y363788D01*
X125419Y363996D01*
X125211Y364288D01*
X125169Y364579D01*
X125252Y364871D01*
X125461Y365079D01*
G01X119400Y376100D02*
X119358Y375767D01*
X119192Y375475D01*
X118942Y375225D01*
X118650Y375058D01*
X118317Y374975D01*
X117983D01*
X117650Y375058D01*
X117358Y375225D01*
X117108Y375475D01*
X116942Y375767D01*
X116900Y376100D01*
X116942Y376433D01*
X117108Y376725D01*
X117358Y376975D01*
X117650Y377142D01*
X117983Y377225D01*
X118317D01*
X118650Y377142D01*
X118942Y376975D01*
X119192Y376725D01*
X119358Y376433D01*
X119400Y376100D01*
G01X118733Y376433D02*
X119400Y376933D01*
G01Y379700D02*
X116900D01*
X118692Y378158D01*
Y380242D01*
G01X119400Y382300D02*
X116900D01*
X117400Y381800D01*
G01X119400D02*
Y382800D01*
G01X101747Y381906D02*
Y367906D01*
G01D02*
X114747D01*
G01D02*
Y381906D01*
G01X100468Y367957D02*
Y381957D01*
G01X119683Y388380D02*
Y386588D01*
X119850Y386213D01*
X120183Y385963D01*
X120600Y385880D01*
X121017Y385963D01*
X121350Y386213D01*
X121517Y386588D01*
Y388380D01*
G01X122783Y386255D02*
X123033Y386047D01*
X123325Y385922D01*
X123700Y385880D01*
X124075Y385963D01*
X124367Y386130D01*
X124575Y386422D01*
X124617Y386755D01*
X124533Y387088D01*
X124325Y387297D01*
X124033Y387463D01*
X123742Y387505D01*
X123450Y387463D01*
X123075Y387297D01*
X123200Y388380D01*
X124325D01*
G01X126800D02*
X126467Y388297D01*
X126217Y388088D01*
X126050Y387838D01*
X125925Y387505D01*
X125883Y387130D01*
X125925Y386755D01*
X126050Y386422D01*
X126217Y386172D01*
X126467Y385963D01*
X126800Y385880D01*
X127133Y385963D01*
X127383Y386172D01*
X127550Y386422D01*
X127675Y386755D01*
X127717Y387130D01*
X127675Y387505D01*
X127550Y387838D01*
X127383Y388088D01*
X127133Y388297D01*
X126800Y388380D01*
G01X133000Y387016D02*
X131000D01*
G01X115244Y396896D02*
X117036D01*
X117411Y397063D01*
X117661Y397396D01*
X117744Y397813D01*
X117661Y398230D01*
X117411Y398563D01*
X117036Y398730D01*
X115244D01*
G01X117744Y401413D02*
X115244D01*
X117036Y399871D01*
Y401955D01*
G01X115661Y403221D02*
X115411Y403471D01*
X115286Y403763D01*
X115244Y404096D01*
X115327Y404513D01*
X115536Y404805D01*
X115786Y404888D01*
X116036Y404846D01*
X116244Y404680D01*
X116661Y403846D01*
X116952Y403471D01*
X117369Y403221D01*
X117744Y403138D01*
Y404888D01*
G01X99808Y408992D02*
X109808D01*
G01D02*
Y395592D01*
G01D02*
X99808D01*
G01D02*
Y408992D01*
G01X111430Y396577D02*
X113222D01*
X113597Y396744D01*
X113847Y397077D01*
X113930Y397494D01*
X113847Y397911D01*
X113597Y398244D01*
X113222Y398411D01*
X111430D01*
G01X111847Y399802D02*
X111597Y400052D01*
X111472Y400344D01*
X111430Y400677D01*
X111513Y401094D01*
X111722Y401386D01*
X111972Y401469D01*
X112222Y401427D01*
X112430Y401261D01*
X112847Y400427D01*
X113138Y400052D01*
X113555Y399802D01*
X113930Y399719D01*
Y401469D01*
G01X111430Y403694D02*
X111513Y403361D01*
X111722Y403111D01*
X111972Y402944D01*
X112305Y402819D01*
X112680Y402777D01*
X113055Y402819D01*
X113388Y402944D01*
X113638Y403111D01*
X113847Y403361D01*
X113930Y403694D01*
X113847Y404027D01*
X113638Y404277D01*
X113388Y404444D01*
X113055Y404569D01*
X112680Y404611D01*
X112305Y404569D01*
X111972Y404444D01*
X111722Y404277D01*
X111513Y404027D01*
X111430Y403694D01*
G01X113930Y407294D02*
X111430D01*
X113222Y405752D01*
Y407836D01*
G01X112005Y411180D02*
Y413680D01*
X113046D01*
X113380Y413555D01*
X113588Y413388D01*
X113671Y413055D01*
X113588Y412722D01*
X113338Y412513D01*
X113046Y412388D01*
X112005D01*
G01X113046D02*
X113671Y411180D01*
G01X115230Y411472D02*
X115521Y411263D01*
X115855Y411180D01*
X116188Y411263D01*
X116480Y411513D01*
X116688Y411888D01*
X116771Y412263D01*
Y412722D01*
X116688Y413097D01*
X116480Y413430D01*
X116230Y413597D01*
X115938Y413680D01*
X115605Y413597D01*
X115355Y413430D01*
X115188Y413180D01*
X115105Y412847D01*
X115188Y412555D01*
X115396Y412263D01*
X115646Y412097D01*
X115938Y412055D01*
X116271Y412138D01*
X116521Y412347D01*
X116771Y412722D01*
G01X119038Y413680D02*
X118705Y413597D01*
X118455Y413388D01*
X118288Y413138D01*
X118163Y412805D01*
X118121Y412430D01*
X118163Y412055D01*
X118288Y411722D01*
X118455Y411472D01*
X118705Y411263D01*
X119038Y411180D01*
X119371Y411263D01*
X119621Y411472D01*
X119788Y411722D01*
X119913Y412055D01*
X119955Y412430D01*
X119913Y412805D01*
X119788Y413138D01*
X119621Y413388D01*
X119371Y413597D01*
X119038Y413680D01*
G01X122638Y411180D02*
Y413680D01*
X121096Y411888D01*
X123180D01*
G01X124446Y412222D02*
X124738Y412513D01*
X124988Y412680D01*
X125321Y412763D01*
X125613Y412680D01*
X125821Y412513D01*
X125988Y412263D01*
X126030Y411972D01*
X125988Y411722D01*
X125821Y411472D01*
X125571Y411263D01*
X125280Y411180D01*
X124946Y411263D01*
X124655Y411513D01*
X124488Y411888D01*
X124446Y412305D01*
X124530Y412847D01*
X124655Y413138D01*
X124863Y413430D01*
X125155Y413638D01*
X125446Y413680D01*
X125738Y413597D01*
X125946Y413388D01*
G01X124635Y400440D02*
X122135D01*
Y401481D01*
X122260Y401815D01*
X122427Y402023D01*
X122760Y402106D01*
X123093Y402023D01*
X123302Y401773D01*
X123427Y401481D01*
Y400440D01*
G01Y401481D02*
X124635Y402106D01*
G01X124260Y403456D02*
X124468Y403706D01*
X124593Y403998D01*
X124635Y404373D01*
X124552Y404748D01*
X124385Y405040D01*
X124093Y405248D01*
X123760Y405290D01*
X123427Y405206D01*
X123218Y404998D01*
X123052Y404706D01*
X123010Y404415D01*
X123052Y404123D01*
X123218Y403748D01*
X122135Y403873D01*
Y404998D01*
G01X124135Y406556D02*
X124427Y406806D01*
X124593Y407140D01*
X124635Y407515D01*
X124593Y407848D01*
X124385Y408181D01*
X124135Y408390D01*
X123885Y408431D01*
X123593Y408348D01*
X123385Y408056D01*
X123302Y407765D01*
Y407390D01*
G01Y407765D02*
X123177Y408015D01*
X122968Y408223D01*
X122718Y408306D01*
X122468Y408223D01*
X122260Y408015D01*
X122135Y407640D01*
X122177Y407265D01*
X122343Y406890D01*
G01X117700Y386600D02*
Y390600D01*
X110300D01*
G01X118997Y395610D02*
Y398110D01*
X120038D01*
X120372Y397985D01*
X120580Y397818D01*
X120663Y397485D01*
X120580Y397152D01*
X120330Y396943D01*
X120038Y396818D01*
X118997D01*
G01X120038D02*
X120663Y395610D01*
G01X123430D02*
Y398110D01*
X121888Y396318D01*
X123972D01*
G01X125947Y395610D02*
X126030Y396152D01*
X126155Y396610D01*
X126322Y397027D01*
X126530Y397485D01*
X126863Y398110D01*
X125197D01*
G01X121000Y394300D02*
Y390300D01*
X128400D01*
G01X102507Y386734D02*
X106507D01*
Y394134D01*
G01X102200Y390300D02*
X98200D01*
Y382900D01*
G01X121200Y399399D02*
X118700D01*
Y400440D01*
X118825Y400774D01*
X118992Y400982D01*
X119325Y401065D01*
X119658Y400982D01*
X119867Y400732D01*
X119992Y400440D01*
Y399399D01*
G01Y400440D02*
X121200Y401065D01*
G01X120158Y402540D02*
X119867Y402832D01*
X119700Y403082D01*
X119617Y403415D01*
X119700Y403707D01*
X119867Y403915D01*
X120117Y404082D01*
X120408Y404124D01*
X120658Y404082D01*
X120908Y403915D01*
X121117Y403665D01*
X121200Y403374D01*
X121117Y403040D01*
X120867Y402749D01*
X120492Y402582D01*
X120075Y402540D01*
X119533Y402624D01*
X119242Y402749D01*
X118950Y402957D01*
X118742Y403249D01*
X118700Y403540D01*
X118783Y403832D01*
X118992Y404040D01*
G01X120908Y405724D02*
X121117Y406015D01*
X121200Y406349D01*
X121117Y406682D01*
X120867Y406974D01*
X120492Y407182D01*
X120117Y407265D01*
X119658D01*
X119283Y407182D01*
X118950Y406974D01*
X118783Y406724D01*
X118700Y406432D01*
X118783Y406099D01*
X118950Y405849D01*
X119200Y405682D01*
X119533Y405599D01*
X119825Y405682D01*
X120117Y405890D01*
X120283Y406140D01*
X120325Y406432D01*
X120242Y406765D01*
X120033Y407015D01*
X119658Y407265D01*
G01X120825Y408615D02*
X121033Y408865D01*
X121158Y409157D01*
X121200Y409532D01*
X121117Y409907D01*
X120950Y410199D01*
X120658Y410407D01*
X120325Y410449D01*
X119992Y410365D01*
X119783Y410157D01*
X119617Y409865D01*
X119575Y409574D01*
X119617Y409282D01*
X119783Y408907D01*
X118700Y409032D01*
Y410157D01*
G01X125400Y402900D02*
X129400D01*
Y410300D01*
G01X114747Y381906D02*
X101747D01*
G01X123217Y432143D02*
X125717D01*
G01X123217Y431185D02*
Y433101D01*
G01X125717Y434410D02*
X123217D01*
Y435410D01*
X123342Y435743D01*
X123634Y435993D01*
X123967Y436076D01*
X124300Y435993D01*
X124550Y435785D01*
X124675Y435410D01*
Y434410D01*
G01X125217Y437426D02*
X125509Y437676D01*
X125675Y438010D01*
X125717Y438385D01*
X125675Y438718D01*
X125467Y439051D01*
X125217Y439260D01*
X124967Y439301D01*
X124675Y439218D01*
X124467Y438926D01*
X124384Y438635D01*
Y438260D01*
G01Y438635D02*
X124259Y438885D01*
X124050Y439093D01*
X123800Y439176D01*
X123550Y439093D01*
X123342Y438885D01*
X123217Y438510D01*
X123259Y438135D01*
X123425Y437760D01*
G01X123217Y441443D02*
X123300Y441110D01*
X123509Y440860D01*
X123759Y440693D01*
X124092Y440568D01*
X124467Y440526D01*
X124842Y440568D01*
X125175Y440693D01*
X125425Y440860D01*
X125634Y441110D01*
X125717Y441443D01*
X125634Y441776D01*
X125425Y442026D01*
X125175Y442193D01*
X124842Y442318D01*
X124467Y442360D01*
X124092Y442318D01*
X123759Y442193D01*
X123509Y442026D01*
X123300Y441776D01*
X123217Y441443D01*
G01X125717Y444543D02*
X125675Y444835D01*
X125550Y445168D01*
X125342Y445376D01*
X125050Y445460D01*
X124759Y445376D01*
X124509Y445126D01*
X124384Y444751D01*
Y444335D01*
X124300Y444085D01*
X124092Y443876D01*
X123800Y443793D01*
X123509Y443918D01*
X123300Y444210D01*
X123217Y444543D01*
X123300Y444876D01*
X123509Y445168D01*
X123800Y445293D01*
X124092Y445210D01*
X124300Y445001D01*
X124384Y444751D01*
Y444335D01*
X124509Y443960D01*
X124759Y443710D01*
X125050Y443626D01*
X125342Y443710D01*
X125550Y443918D01*
X125675Y444251D01*
X125717Y444543D01*
G01X106200Y441300D02*
X108700D01*
G01X106200Y440342D02*
Y442258D01*
G01X108700Y443567D02*
X106200D01*
Y444567D01*
X106325Y444900D01*
X106617Y445150D01*
X106950Y445233D01*
X107283Y445150D01*
X107533Y444942D01*
X107658Y444567D01*
Y443567D01*
G01X106617Y446708D02*
X106367Y446958D01*
X106242Y447250D01*
X106200Y447583D01*
X106283Y448000D01*
X106492Y448292D01*
X106742Y448375D01*
X106992Y448333D01*
X107200Y448167D01*
X107617Y447333D01*
X107908Y446958D01*
X108325Y446708D01*
X108700Y446625D01*
Y448375D01*
G01Y451100D02*
X106200D01*
X107992Y449558D01*
Y451642D01*
G01X106617Y452908D02*
X106367Y453158D01*
X106242Y453450D01*
X106200Y453783D01*
X106283Y454200D01*
X106492Y454492D01*
X106742Y454575D01*
X106992Y454533D01*
X107200Y454367D01*
X107617Y453533D01*
X107908Y453158D01*
X108325Y452908D01*
X108700Y452825D01*
Y454575D01*
G01X101885Y441040D02*
X104385D01*
G01X101885Y440082D02*
Y441998D01*
G01X104385Y443307D02*
X101885D01*
Y444307D01*
X102010Y444640D01*
X102302Y444890D01*
X102635Y444973D01*
X102968Y444890D01*
X103218Y444682D01*
X103343Y444307D01*
Y443307D01*
G01X102302Y446448D02*
X102052Y446698D01*
X101927Y446990D01*
X101885Y447323D01*
X101968Y447740D01*
X102177Y448032D01*
X102427Y448115D01*
X102677Y448073D01*
X102885Y447907D01*
X103302Y447073D01*
X103593Y446698D01*
X104010Y446448D01*
X104385Y446365D01*
Y448115D01*
G01X103343Y449548D02*
X103052Y449840D01*
X102885Y450090D01*
X102802Y450423D01*
X102885Y450715D01*
X103052Y450923D01*
X103302Y451090D01*
X103593Y451132D01*
X103843Y451090D01*
X104093Y450923D01*
X104302Y450673D01*
X104385Y450382D01*
X104302Y450048D01*
X104052Y449757D01*
X103677Y449590D01*
X103260Y449548D01*
X102718Y449632D01*
X102427Y449757D01*
X102135Y449965D01*
X101927Y450257D01*
X101885Y450548D01*
X101968Y450840D01*
X102177Y451048D01*
G01X103343Y452648D02*
X103052Y452940D01*
X102885Y453190D01*
X102802Y453523D01*
X102885Y453815D01*
X103052Y454023D01*
X103302Y454190D01*
X103593Y454232D01*
X103843Y454190D01*
X104093Y454023D01*
X104302Y453773D01*
X104385Y453482D01*
X104302Y453148D01*
X104052Y452857D01*
X103677Y452690D01*
X103260Y452648D01*
X102718Y452732D01*
X102427Y452857D01*
X102135Y453065D01*
X101927Y453357D01*
X101885Y453648D01*
X101968Y453940D01*
X102177Y454148D01*
G01X118465Y419055D02*
X115965D01*
Y420096D01*
X116090Y420430D01*
X116257Y420638D01*
X116590Y420721D01*
X116923Y420638D01*
X117132Y420388D01*
X117257Y420096D01*
Y419055D01*
G01Y420096D02*
X118465Y420721D01*
G01X116382Y422196D02*
X116132Y422446D01*
X116007Y422738D01*
X115965Y423071D01*
X116048Y423488D01*
X116257Y423780D01*
X116507Y423863D01*
X116757Y423821D01*
X116965Y423655D01*
X117382Y422821D01*
X117673Y422446D01*
X118090Y422196D01*
X118465Y422113D01*
Y423863D01*
G01X118090Y425171D02*
X118298Y425421D01*
X118423Y425713D01*
X118465Y426088D01*
X118382Y426463D01*
X118215Y426755D01*
X117923Y426963D01*
X117590Y427005D01*
X117257Y426921D01*
X117048Y426713D01*
X116882Y426421D01*
X116840Y426130D01*
X116882Y425838D01*
X117048Y425463D01*
X115965Y425588D01*
Y426713D01*
G01X118465Y429188D02*
X118423Y429480D01*
X118298Y429813D01*
X118090Y430021D01*
X117798Y430105D01*
X117507Y430021D01*
X117257Y429771D01*
X117132Y429396D01*
Y428980D01*
X117048Y428730D01*
X116840Y428521D01*
X116548Y428438D01*
X116257Y428563D01*
X116048Y428855D01*
X115965Y429188D01*
X116048Y429521D01*
X116257Y429813D01*
X116548Y429938D01*
X116840Y429855D01*
X117048Y429646D01*
X117132Y429396D01*
Y428980D01*
X117257Y428605D01*
X117507Y428355D01*
X117798Y428271D01*
X118090Y428355D01*
X118298Y428563D01*
X118423Y428896D01*
X118465Y429188D01*
G01X125208Y418801D02*
X122708D01*
Y419842D01*
X122833Y420176D01*
X123000Y420384D01*
X123333Y420467D01*
X123666Y420384D01*
X123875Y420134D01*
X124000Y419842D01*
Y418801D01*
G01Y419842D02*
X125208Y420467D01*
G01X124166Y421942D02*
X123875Y422234D01*
X123708Y422484D01*
X123625Y422817D01*
X123708Y423109D01*
X123875Y423317D01*
X124125Y423484D01*
X124416Y423526D01*
X124666Y423484D01*
X124916Y423317D01*
X125125Y423067D01*
X125208Y422776D01*
X125125Y422442D01*
X124875Y422151D01*
X124500Y421984D01*
X124083Y421942D01*
X123541Y422026D01*
X123250Y422151D01*
X122958Y422359D01*
X122750Y422651D01*
X122708Y422942D01*
X122791Y423234D01*
X123000Y423442D01*
G01X122708Y425834D02*
X122791Y425501D01*
X123000Y425251D01*
X123250Y425084D01*
X123583Y424959D01*
X123958Y424917D01*
X124333Y424959D01*
X124666Y425084D01*
X124916Y425251D01*
X125125Y425501D01*
X125208Y425834D01*
X125125Y426167D01*
X124916Y426417D01*
X124666Y426584D01*
X124333Y426709D01*
X123958Y426751D01*
X123583Y426709D01*
X123250Y426584D01*
X123000Y426417D01*
X122791Y426167D01*
X122708Y425834D01*
G01X124833Y428017D02*
X125041Y428267D01*
X125166Y428559D01*
X125208Y428934D01*
X125125Y429309D01*
X124958Y429601D01*
X124666Y429809D01*
X124333Y429851D01*
X124000Y429767D01*
X123791Y429559D01*
X123625Y429267D01*
X123583Y428976D01*
X123625Y428684D01*
X123791Y428309D01*
X122708Y428434D01*
Y429559D01*
G01X132619Y423949D02*
X130119D01*
Y424990D01*
X130244Y425324D01*
X130411Y425532D01*
X130744Y425615D01*
X131077Y425532D01*
X131286Y425282D01*
X131411Y424990D01*
Y423949D01*
G01Y424990D02*
X132619Y425615D01*
G01X132244Y426965D02*
X132452Y427215D01*
X132577Y427507D01*
X132619Y427882D01*
X132536Y428257D01*
X132369Y428549D01*
X132077Y428757D01*
X131744Y428799D01*
X131411Y428715D01*
X131202Y428507D01*
X131036Y428215D01*
X130994Y427924D01*
X131036Y427632D01*
X131202Y427257D01*
X130119Y427382D01*
Y428507D01*
G01Y430982D02*
X130202Y430649D01*
X130411Y430399D01*
X130661Y430232D01*
X130994Y430107D01*
X131369Y430065D01*
X131744Y430107D01*
X132077Y430232D01*
X132327Y430399D01*
X132536Y430649D01*
X132619Y430982D01*
X132536Y431315D01*
X132327Y431565D01*
X132077Y431732D01*
X131744Y431857D01*
X131369Y431899D01*
X130994Y431857D01*
X130661Y431732D01*
X130411Y431565D01*
X130202Y431315D01*
X130119Y430982D01*
G01X132619Y433999D02*
X132077Y434082D01*
X131619Y434207D01*
X131202Y434374D01*
X130744Y434582D01*
X130119Y434915D01*
Y433249D01*
G01X114775Y422936D02*
X112275D01*
Y423977D01*
X112400Y424311D01*
X112567Y424519D01*
X112900Y424602D01*
X113233Y424519D01*
X113442Y424269D01*
X113567Y423977D01*
Y422936D01*
G01Y423977D02*
X114775Y424602D01*
G01X112692Y426077D02*
X112442Y426327D01*
X112317Y426619D01*
X112275Y426952D01*
X112358Y427369D01*
X112567Y427661D01*
X112817Y427744D01*
X113067Y427702D01*
X113275Y427536D01*
X113692Y426702D01*
X113983Y426327D01*
X114400Y426077D01*
X114775Y425994D01*
Y427744D01*
G01X114275Y429052D02*
X114567Y429302D01*
X114733Y429636D01*
X114775Y430011D01*
X114733Y430344D01*
X114525Y430677D01*
X114275Y430886D01*
X114025Y430927D01*
X113733Y430844D01*
X113525Y430552D01*
X113442Y430261D01*
Y429886D01*
G01Y430261D02*
X113317Y430511D01*
X113108Y430719D01*
X112858Y430802D01*
X112608Y430719D01*
X112400Y430511D01*
X112275Y430136D01*
X112317Y429761D01*
X112483Y429386D01*
G01X114275Y432152D02*
X114567Y432402D01*
X114733Y432736D01*
X114775Y433111D01*
X114733Y433444D01*
X114525Y433777D01*
X114275Y433986D01*
X114025Y434027D01*
X113733Y433944D01*
X113525Y433652D01*
X113442Y433361D01*
Y432986D01*
G01Y433361D02*
X113317Y433611D01*
X113108Y433819D01*
X112858Y433902D01*
X112608Y433819D01*
X112400Y433611D01*
X112275Y433236D01*
X112317Y432861D01*
X112483Y432486D01*
G01X108731Y413521D02*
X106231D01*
Y414562D01*
X106356Y414896D01*
X106523Y415104D01*
X106856Y415187D01*
X107189Y415104D01*
X107398Y414854D01*
X107523Y414562D01*
Y413521D01*
G01Y414562D02*
X108731Y415187D01*
G01X106648Y416662D02*
X106398Y416912D01*
X106273Y417204D01*
X106231Y417537D01*
X106314Y417954D01*
X106523Y418246D01*
X106773Y418329D01*
X107023Y418287D01*
X107231Y418121D01*
X107648Y417287D01*
X107939Y416912D01*
X108356Y416662D01*
X108731Y416579D01*
Y418329D01*
G01X108231Y419637D02*
X108523Y419887D01*
X108689Y420221D01*
X108731Y420596D01*
X108689Y420929D01*
X108481Y421262D01*
X108231Y421471D01*
X107981Y421512D01*
X107689Y421429D01*
X107481Y421137D01*
X107398Y420846D01*
Y420471D01*
G01Y420846D02*
X107273Y421096D01*
X107064Y421304D01*
X106814Y421387D01*
X106564Y421304D01*
X106356Y421096D01*
X106231Y420721D01*
X106273Y420346D01*
X106439Y419971D01*
G01X108356Y422737D02*
X108564Y422987D01*
X108689Y423279D01*
X108731Y423654D01*
X108648Y424029D01*
X108481Y424321D01*
X108189Y424529D01*
X107856Y424571D01*
X107523Y424487D01*
X107314Y424279D01*
X107148Y423987D01*
X107106Y423696D01*
X107148Y423404D01*
X107314Y423029D01*
X106231Y423154D01*
Y424279D01*
G01X121779Y418896D02*
X119279D01*
Y419937D01*
X119404Y420271D01*
X119571Y420479D01*
X119904Y420562D01*
X120237Y420479D01*
X120446Y420229D01*
X120571Y419937D01*
Y418896D01*
G01Y419937D02*
X121779Y420562D01*
G01X119696Y422037D02*
X119446Y422287D01*
X119321Y422579D01*
X119279Y422912D01*
X119362Y423329D01*
X119571Y423621D01*
X119821Y423704D01*
X120071Y423662D01*
X120279Y423496D01*
X120696Y422662D01*
X120987Y422287D01*
X121404Y422037D01*
X121779Y421954D01*
Y423704D01*
G01X121279Y425012D02*
X121571Y425262D01*
X121737Y425596D01*
X121779Y425971D01*
X121737Y426304D01*
X121529Y426637D01*
X121279Y426846D01*
X121029Y426887D01*
X120737Y426804D01*
X120529Y426512D01*
X120446Y426221D01*
Y425846D01*
G01Y426221D02*
X120321Y426471D01*
X120112Y426679D01*
X119862Y426762D01*
X119612Y426679D01*
X119404Y426471D01*
X119279Y426096D01*
X119321Y425721D01*
X119487Y425346D01*
G01X121779Y428946D02*
X121237Y429029D01*
X120779Y429154D01*
X120362Y429321D01*
X119904Y429529D01*
X119279Y429862D01*
Y428196D01*
G01X128707Y419055D02*
X126207D01*
Y420096D01*
X126332Y420430D01*
X126499Y420638D01*
X126832Y420721D01*
X127165Y420638D01*
X127374Y420388D01*
X127499Y420096D01*
Y419055D01*
G01Y420096D02*
X128707Y420721D01*
G01Y422905D02*
X128165Y422988D01*
X127707Y423113D01*
X127290Y423280D01*
X126832Y423488D01*
X126207Y423821D01*
Y422155D01*
G01X128207Y425171D02*
X128499Y425421D01*
X128665Y425755D01*
X128707Y426130D01*
X128665Y426463D01*
X128457Y426796D01*
X128207Y427005D01*
X127957Y427046D01*
X127665Y426963D01*
X127457Y426671D01*
X127374Y426380D01*
Y426005D01*
G01Y426380D02*
X127249Y426630D01*
X127040Y426838D01*
X126790Y426921D01*
X126540Y426838D01*
X126332Y426630D01*
X126207Y426255D01*
X126249Y425880D01*
X126415Y425505D01*
G01X128707Y429188D02*
X126207D01*
X126707Y428688D01*
G01X128707D02*
Y429688D01*
G01X118252Y438352D02*
X122252D01*
Y445752D01*
G01X129812Y419187D02*
Y421687D01*
X130853D01*
X131187Y421562D01*
X131395Y421395D01*
X131478Y421062D01*
X131395Y420729D01*
X131145Y420520D01*
X130853Y420395D01*
X129812D01*
G01X130853D02*
X131478Y419187D01*
G01X134245D02*
Y421687D01*
X132703Y419895D01*
X134787D01*
G01X136845Y419187D02*
Y421687D01*
X136345Y421187D01*
G01Y419187D02*
X137345D01*
G01X139862D02*
X139945Y419729D01*
X140070Y420187D01*
X140237Y420604D01*
X140445Y421062D01*
X140778Y421687D01*
X139112D01*
G01X102818Y436339D02*
Y438839D01*
X103859D01*
X104193Y438714D01*
X104401Y438547D01*
X104484Y438214D01*
X104401Y437881D01*
X104151Y437672D01*
X103859Y437547D01*
X102818D01*
G01X103859D02*
X104484Y436339D01*
G01X106668D02*
X106751Y436881D01*
X106876Y437339D01*
X107043Y437756D01*
X107251Y438214D01*
X107584Y438839D01*
X105918D01*
G01X109851D02*
X109518Y438756D01*
X109268Y438547D01*
X109101Y438297D01*
X108976Y437964D01*
X108934Y437589D01*
X108976Y437214D01*
X109101Y436881D01*
X109268Y436631D01*
X109518Y436422D01*
X109851Y436339D01*
X110184Y436422D01*
X110434Y436631D01*
X110601Y436881D01*
X110726Y437214D01*
X110768Y437589D01*
X110726Y437964D01*
X110601Y438297D01*
X110434Y438547D01*
X110184Y438756D01*
X109851Y438839D01*
G01X112243Y436631D02*
X112534Y436422D01*
X112868Y436339D01*
X113201Y436422D01*
X113493Y436672D01*
X113701Y437047D01*
X113784Y437422D01*
Y437881D01*
X113701Y438256D01*
X113493Y438589D01*
X113243Y438756D01*
X112951Y438839D01*
X112618Y438756D01*
X112368Y438589D01*
X112201Y438339D01*
X112118Y438006D01*
X112201Y437714D01*
X112409Y437422D01*
X112659Y437256D01*
X112951Y437214D01*
X113284Y437297D01*
X113534Y437506D01*
X113784Y437881D01*
G01X117634Y439150D02*
Y443150D01*
X110234D01*
G01X98079Y421317D02*
X102079D01*
Y428717D01*
G01X112005Y414679D02*
Y417179D01*
X113046D01*
X113380Y417054D01*
X113588Y416887D01*
X113671Y416554D01*
X113588Y416221D01*
X113338Y416012D01*
X113046Y415887D01*
X112005D01*
G01X113046D02*
X113671Y414679D01*
G01X115230Y414971D02*
X115521Y414762D01*
X115855Y414679D01*
X116188Y414762D01*
X116480Y415012D01*
X116688Y415387D01*
X116771Y415762D01*
Y416221D01*
X116688Y416596D01*
X116480Y416929D01*
X116230Y417096D01*
X115938Y417179D01*
X115605Y417096D01*
X115355Y416929D01*
X115188Y416679D01*
X115105Y416346D01*
X115188Y416054D01*
X115396Y415762D01*
X115646Y415596D01*
X115938Y415554D01*
X116271Y415637D01*
X116521Y415846D01*
X116771Y416221D01*
G01X119038Y417179D02*
X118705Y417096D01*
X118455Y416887D01*
X118288Y416637D01*
X118163Y416304D01*
X118121Y415929D01*
X118163Y415554D01*
X118288Y415221D01*
X118455Y414971D01*
X118705Y414762D01*
X119038Y414679D01*
X119371Y414762D01*
X119621Y414971D01*
X119788Y415221D01*
X119913Y415554D01*
X119955Y415929D01*
X119913Y416304D01*
X119788Y416637D01*
X119621Y416887D01*
X119371Y417096D01*
X119038Y417179D01*
G01X122638Y414679D02*
Y417179D01*
X121096Y415387D01*
X123180D01*
G01X125738Y414679D02*
Y417179D01*
X124196Y415387D01*
X126280D01*
G01X102076Y436130D02*
X98076D01*
Y428730D01*
G01X187421Y551122D02*
X112617D01*
Y476318D01*
X187421D01*
Y551122D01*
G01X133800Y447467D02*
X131300D01*
Y448508D01*
X131425Y448842D01*
X131592Y449050D01*
X131925Y449133D01*
X132258Y449050D01*
X132467Y448800D01*
X132592Y448508D01*
Y447467D01*
G01Y448508D02*
X133800Y449133D01*
G01X131717Y450608D02*
X131467Y450858D01*
X131342Y451150D01*
X131300Y451483D01*
X131383Y451900D01*
X131592Y452192D01*
X131842Y452275D01*
X132092Y452233D01*
X132300Y452067D01*
X132717Y451233D01*
X133008Y450858D01*
X133425Y450608D01*
X133800Y450525D01*
Y452275D01*
G01X131300Y454500D02*
X131383Y454167D01*
X131592Y453917D01*
X131842Y453750D01*
X132175Y453625D01*
X132550Y453583D01*
X132925Y453625D01*
X133258Y453750D01*
X133508Y453917D01*
X133717Y454167D01*
X133800Y454500D01*
X133717Y454833D01*
X133508Y455083D01*
X133258Y455250D01*
X132925Y455375D01*
X132550Y455417D01*
X132175Y455375D01*
X131842Y455250D01*
X131592Y455083D01*
X131383Y454833D01*
X131300Y454500D01*
G01X135000Y463200D02*
X131000D01*
Y455800D01*
G01X124890Y474446D02*
Y471946D01*
G01X123932Y474446D02*
X125848D01*
G01X127157Y471946D02*
Y474446D01*
X128157D01*
X128490Y474321D01*
X128740Y474029D01*
X128823Y473696D01*
X128740Y473363D01*
X128532Y473113D01*
X128157Y472988D01*
X127157D01*
G01X130298Y474029D02*
X130548Y474279D01*
X130840Y474404D01*
X131173Y474446D01*
X131590Y474363D01*
X131882Y474154D01*
X131965Y473904D01*
X131923Y473654D01*
X131757Y473446D01*
X130923Y473029D01*
X130548Y472738D01*
X130298Y472321D01*
X130215Y471946D01*
X131965D01*
G01X133398Y474029D02*
X133648Y474279D01*
X133940Y474404D01*
X134273Y474446D01*
X134690Y474363D01*
X134982Y474154D01*
X135065Y473904D01*
X135023Y473654D01*
X134857Y473446D01*
X134023Y473029D01*
X133648Y472738D01*
X133398Y472321D01*
X133315Y471946D01*
X135065D01*
G01X137207D02*
X137290Y472488D01*
X137415Y472946D01*
X137582Y473363D01*
X137790Y473821D01*
X138123Y474446D01*
X136457D01*
G01X131230Y470326D02*
Y467826D01*
G01X130272Y470326D02*
X132188D01*
G01X133497Y467826D02*
Y470326D01*
X134497D01*
X134830Y470201D01*
X135080Y469909D01*
X135163Y469576D01*
X135080Y469243D01*
X134872Y468993D01*
X134497Y468868D01*
X133497D01*
G01X136638Y469909D02*
X136888Y470159D01*
X137180Y470284D01*
X137513Y470326D01*
X137930Y470243D01*
X138222Y470034D01*
X138305Y469784D01*
X138263Y469534D01*
X138097Y469326D01*
X137263Y468909D01*
X136888Y468618D01*
X136638Y468201D01*
X136555Y467826D01*
X138305D01*
G01X139613Y468326D02*
X139863Y468034D01*
X140197Y467868D01*
X140572Y467826D01*
X140905Y467868D01*
X141238Y468076D01*
X141447Y468326D01*
X141488Y468576D01*
X141405Y468868D01*
X141113Y469076D01*
X140822Y469159D01*
X140447D01*
G01X140822D02*
X141072Y469284D01*
X141280Y469493D01*
X141363Y469743D01*
X141280Y469993D01*
X141072Y470201D01*
X140697Y470326D01*
X140322Y470284D01*
X139947Y470118D01*
G01X142713Y468326D02*
X142963Y468034D01*
X143297Y467868D01*
X143672Y467826D01*
X144005Y467868D01*
X144338Y468076D01*
X144547Y468326D01*
X144588Y468576D01*
X144505Y468868D01*
X144213Y469076D01*
X143922Y469159D01*
X143547D01*
G01X143922D02*
X144172Y469284D01*
X144380Y469493D01*
X144463Y469743D01*
X144380Y469993D01*
X144172Y470201D01*
X143797Y470326D01*
X143422Y470284D01*
X143047Y470118D01*
G01X115800Y470666D02*
Y468166D01*
G01X114842Y470666D02*
X116758D01*
G01X118067Y468166D02*
Y470666D01*
X119067D01*
X119400Y470541D01*
X119650Y470249D01*
X119733Y469916D01*
X119650Y469583D01*
X119442Y469333D01*
X119067Y469208D01*
X118067D01*
G01X121208Y470249D02*
X121458Y470499D01*
X121750Y470624D01*
X122083Y470666D01*
X122500Y470583D01*
X122792Y470374D01*
X122875Y470124D01*
X122833Y469874D01*
X122667Y469666D01*
X121833Y469249D01*
X121458Y468958D01*
X121208Y468541D01*
X121125Y468166D01*
X122875D01*
G01X125600D02*
Y470666D01*
X124058Y468874D01*
X126142D01*
G01X127283Y468666D02*
X127533Y468374D01*
X127867Y468208D01*
X128242Y468166D01*
X128575Y468208D01*
X128908Y468416D01*
X129117Y468666D01*
X129158Y468916D01*
X129075Y469208D01*
X128783Y469416D01*
X128492Y469499D01*
X128117D01*
G01X128492D02*
X128742Y469624D01*
X128950Y469833D01*
X129033Y470083D01*
X128950Y470333D01*
X128742Y470541D01*
X128367Y470666D01*
X127992Y470624D01*
X127617Y470458D01*
G01X122901Y450777D02*
X125401D01*
G01X122901Y449819D02*
Y451735D01*
G01X125401Y453044D02*
X122901D01*
Y454044D01*
X123026Y454377D01*
X123318Y454627D01*
X123651Y454710D01*
X123984Y454627D01*
X124234Y454419D01*
X124359Y454044D01*
Y453044D01*
G01X123318Y456185D02*
X123068Y456435D01*
X122943Y456727D01*
X122901Y457060D01*
X122984Y457477D01*
X123193Y457769D01*
X123443Y457852D01*
X123693Y457810D01*
X123901Y457644D01*
X124318Y456810D01*
X124609Y456435D01*
X125026Y456185D01*
X125401Y456102D01*
Y457852D01*
G01Y460577D02*
X122901D01*
X124693Y459035D01*
Y461119D01*
G01X125401Y463677D02*
X122901D01*
X124693Y462135D01*
Y464219D01*
G01X109300Y474500D02*
Y472000D01*
G01X108342Y474500D02*
X110258D01*
G01X111567Y472000D02*
Y474500D01*
X112567D01*
X112900Y474375D01*
X113150Y474083D01*
X113233Y473750D01*
X113150Y473417D01*
X112942Y473167D01*
X112567Y473042D01*
X111567D01*
G01X114583Y472500D02*
X114833Y472208D01*
X115167Y472042D01*
X115542Y472000D01*
X115875Y472042D01*
X116208Y472250D01*
X116417Y472500D01*
X116458Y472750D01*
X116375Y473042D01*
X116083Y473250D01*
X115792Y473333D01*
X115417D01*
G01X115792D02*
X116042Y473458D01*
X116250Y473667D01*
X116333Y473917D01*
X116250Y474167D01*
X116042Y474375D01*
X115667Y474500D01*
X115292Y474458D01*
X114917Y474292D01*
G01X118600Y474500D02*
X118267Y474417D01*
X118017Y474208D01*
X117850Y473958D01*
X117725Y473625D01*
X117683Y473250D01*
X117725Y472875D01*
X117850Y472542D01*
X118017Y472292D01*
X118267Y472083D01*
X118600Y472000D01*
X118933Y472083D01*
X119183Y472292D01*
X119350Y472542D01*
X119475Y472875D01*
X119517Y473250D01*
X119475Y473625D01*
X119350Y473958D01*
X119183Y474208D01*
X118933Y474417D01*
X118600Y474500D01*
G01X120783Y472375D02*
X121033Y472167D01*
X121325Y472042D01*
X121700Y472000D01*
X122075Y472083D01*
X122367Y472250D01*
X122575Y472542D01*
X122617Y472875D01*
X122533Y473208D01*
X122325Y473417D01*
X122033Y473583D01*
X121742Y473625D01*
X121450Y473583D01*
X121075Y473417D01*
X121200Y474500D01*
X122325D01*
G01X113500Y463200D02*
X109500D01*
Y455800D01*
G01X114235Y445835D02*
X118235D01*
Y453235D01*
G01X109500Y463200D02*
X105500D01*
Y455800D01*
G01X101500D02*
X105500D01*
Y463200D01*
G01X113500Y455800D02*
X117500D01*
Y463200D01*
G01X108834Y504166D02*
X111334D01*
G01X108834Y503208D02*
Y505124D01*
G01X111334Y506433D02*
X108834D01*
Y507433D01*
X108959Y507766D01*
X109251Y508016D01*
X109584Y508099D01*
X109917Y508016D01*
X110167Y507808D01*
X110292Y507433D01*
Y506433D01*
G01X109251Y509574D02*
X109001Y509824D01*
X108876Y510116D01*
X108834Y510449D01*
X108917Y510866D01*
X109126Y511158D01*
X109376Y511241D01*
X109626Y511199D01*
X109834Y511033D01*
X110251Y510199D01*
X110542Y509824D01*
X110959Y509574D01*
X111334Y509491D01*
Y511241D01*
G01X110834Y512549D02*
X111126Y512799D01*
X111292Y513133D01*
X111334Y513508D01*
X111292Y513841D01*
X111084Y514174D01*
X110834Y514383D01*
X110584Y514424D01*
X110292Y514341D01*
X110084Y514049D01*
X110001Y513758D01*
Y513383D01*
G01Y513758D02*
X109876Y514008D01*
X109667Y514216D01*
X109417Y514299D01*
X109167Y514216D01*
X108959Y514008D01*
X108834Y513633D01*
X108876Y513258D01*
X109042Y512883D01*
G01X110292Y515774D02*
X110001Y516066D01*
X109834Y516316D01*
X109751Y516649D01*
X109834Y516941D01*
X110001Y517149D01*
X110251Y517316D01*
X110542Y517358D01*
X110792Y517316D01*
X111042Y517149D01*
X111251Y516899D01*
X111334Y516608D01*
X111251Y516274D01*
X111001Y515983D01*
X110626Y515816D01*
X110209Y515774D01*
X109667Y515858D01*
X109376Y515983D01*
X109084Y516191D01*
X108876Y516483D01*
X108834Y516774D01*
X108917Y517066D01*
X109126Y517274D01*
G01X107975Y536420D02*
X109767D01*
X110142Y536587D01*
X110392Y536920D01*
X110475Y537337D01*
X110392Y537754D01*
X110142Y538087D01*
X109767Y538254D01*
X107975D01*
G01X110475Y540937D02*
X107975D01*
X109767Y539395D01*
Y541479D01*
G01X107975Y543537D02*
X108058Y543204D01*
X108267Y542954D01*
X108517Y542787D01*
X108850Y542662D01*
X109225Y542620D01*
X109600Y542662D01*
X109933Y542787D01*
X110183Y542954D01*
X110392Y543204D01*
X110475Y543537D01*
X110392Y543870D01*
X110183Y544120D01*
X109933Y544287D01*
X109600Y544412D01*
X109225Y544454D01*
X108850Y544412D01*
X108517Y544287D01*
X108267Y544120D01*
X108058Y543870D01*
X107975Y543537D01*
G01X106017Y569000D02*
Y571500D01*
X107058D01*
X107392Y571375D01*
X107600Y571208D01*
X107683Y570875D01*
X107600Y570542D01*
X107350Y570333D01*
X107058Y570208D01*
X106017D01*
G01X107058D02*
X107683Y569000D01*
G01X109158Y571083D02*
X109408Y571333D01*
X109700Y571458D01*
X110033Y571500D01*
X110450Y571417D01*
X110742Y571208D01*
X110825Y570958D01*
X110783Y570708D01*
X110617Y570500D01*
X109783Y570083D01*
X109408Y569792D01*
X109158Y569375D01*
X109075Y569000D01*
X110825D01*
G01X112342Y569292D02*
X112633Y569083D01*
X112967Y569000D01*
X113300Y569083D01*
X113592Y569333D01*
X113800Y569708D01*
X113883Y570083D01*
Y570542D01*
X113800Y570917D01*
X113592Y571250D01*
X113342Y571417D01*
X113050Y571500D01*
X112717Y571417D01*
X112467Y571250D01*
X112300Y571000D01*
X112217Y570667D01*
X112300Y570375D01*
X112508Y570083D01*
X112758Y569917D01*
X113050Y569875D01*
X113383Y569958D01*
X113633Y570167D01*
X113883Y570542D01*
G01X116150Y569000D02*
X116442Y569042D01*
X116775Y569167D01*
X116983Y569375D01*
X117067Y569667D01*
X116983Y569958D01*
X116733Y570208D01*
X116358Y570333D01*
X115942D01*
X115692Y570417D01*
X115483Y570625D01*
X115400Y570917D01*
X115525Y571208D01*
X115817Y571417D01*
X116150Y571500D01*
X116483Y571417D01*
X116775Y571208D01*
X116900Y570917D01*
X116817Y570625D01*
X116608Y570417D01*
X116358Y570333D01*
X115942D01*
X115567Y570208D01*
X115317Y569958D01*
X115233Y569667D01*
X115317Y569375D01*
X115525Y569167D01*
X115858Y569042D01*
X116150Y569000D01*
G01X127324Y574014D02*
X124824D01*
Y575055D01*
X124949Y575389D01*
X125116Y575597D01*
X125449Y575680D01*
X125782Y575597D01*
X125991Y575347D01*
X126116Y575055D01*
Y574014D01*
G01Y575055D02*
X127324Y575680D01*
G01X125241Y577155D02*
X124991Y577405D01*
X124866Y577697D01*
X124824Y578030D01*
X124907Y578447D01*
X125116Y578739D01*
X125366Y578822D01*
X125616Y578780D01*
X125824Y578614D01*
X126241Y577780D01*
X126532Y577405D01*
X126949Y577155D01*
X127324Y577072D01*
Y578822D01*
G01Y581547D02*
X124824D01*
X126616Y580005D01*
Y582089D01*
G01X127324Y584147D02*
X127282Y584439D01*
X127157Y584772D01*
X126949Y584980D01*
X126657Y585064D01*
X126366Y584980D01*
X126116Y584730D01*
X125991Y584355D01*
Y583939D01*
X125907Y583689D01*
X125699Y583480D01*
X125407Y583397D01*
X125116Y583522D01*
X124907Y583814D01*
X124824Y584147D01*
X124907Y584480D01*
X125116Y584772D01*
X125407Y584897D01*
X125699Y584814D01*
X125907Y584605D01*
X125991Y584355D01*
Y583939D01*
X126116Y583564D01*
X126366Y583314D01*
X126657Y583230D01*
X126949Y583314D01*
X127157Y583522D01*
X127282Y583855D01*
X127324Y584147D01*
G01X98978Y550434D02*
Y552934D01*
X100019D01*
X100353Y552809D01*
X100561Y552642D01*
X100644Y552309D01*
X100561Y551976D01*
X100311Y551767D01*
X100019Y551642D01*
X98978D01*
G01X100019D02*
X100644Y550434D01*
G01X103411D02*
Y552934D01*
X101869Y551142D01*
X103953D01*
G01X106511Y550434D02*
Y552934D01*
X104969Y551142D01*
X107053D01*
G01X108403Y550726D02*
X108694Y550517D01*
X109028Y550434D01*
X109361Y550517D01*
X109653Y550767D01*
X109861Y551142D01*
X109944Y551517D01*
Y551976D01*
X109861Y552351D01*
X109653Y552684D01*
X109403Y552851D01*
X109111Y552934D01*
X108778Y552851D01*
X108528Y552684D01*
X108361Y552434D01*
X108278Y552101D01*
X108361Y551809D01*
X108569Y551517D01*
X108819Y551351D01*
X109111Y551309D01*
X109444Y551392D01*
X109694Y551601D01*
X109944Y551976D01*
G01X112700Y559500D02*
Y563500D01*
X105300D01*
G01X120180Y557040D02*
X117680D01*
Y558081D01*
X117805Y558415D01*
X117972Y558623D01*
X118305Y558706D01*
X118638Y558623D01*
X118847Y558373D01*
X118972Y558081D01*
Y557040D01*
G01Y558081D02*
X120180Y558706D01*
G01Y561473D02*
X117680D01*
X119472Y559931D01*
Y562015D01*
G01X119805Y563156D02*
X120013Y563406D01*
X120138Y563698D01*
X120180Y564073D01*
X120097Y564448D01*
X119930Y564740D01*
X119638Y564948D01*
X119305Y564990D01*
X118972Y564906D01*
X118763Y564698D01*
X118597Y564406D01*
X118555Y564115D01*
X118597Y563823D01*
X118763Y563448D01*
X117680Y563573D01*
Y564698D01*
G01Y567173D02*
X117763Y566840D01*
X117972Y566590D01*
X118222Y566423D01*
X118555Y566298D01*
X118930Y566256D01*
X119305Y566298D01*
X119638Y566423D01*
X119888Y566590D01*
X120097Y566840D01*
X120180Y567173D01*
X120097Y567506D01*
X119888Y567756D01*
X119638Y567923D01*
X119305Y568048D01*
X118930Y568090D01*
X118555Y568048D01*
X118222Y567923D01*
X117972Y567756D01*
X117763Y567506D01*
X117680Y567173D01*
G01X112700Y563500D02*
Y567500D01*
X105300D01*
G01X120841Y575967D02*
X120716Y575717D01*
X120633Y575425D01*
Y575092D01*
X120758Y574717D01*
X120966Y574425D01*
X121216Y574217D01*
X121633Y574050D01*
X122008Y574008D01*
X122383Y574092D01*
X122633Y574217D01*
X122883Y574467D01*
X123050Y574758D01*
X123133Y575050D01*
Y575342D01*
X123050Y575633D01*
X122925Y575883D01*
X122758Y576092D01*
G01X123133Y578150D02*
X120633D01*
X121133Y577650D01*
G01X123133D02*
Y578650D01*
G01Y581250D02*
X123091Y581542D01*
X122966Y581875D01*
X122758Y582083D01*
X122466Y582167D01*
X122175Y582083D01*
X121925Y581833D01*
X121800Y581458D01*
Y581042D01*
X121716Y580792D01*
X121508Y580583D01*
X121216Y580500D01*
X120925Y580625D01*
X120716Y580917D01*
X120633Y581250D01*
X120716Y581583D01*
X120925Y581875D01*
X121216Y582000D01*
X121508Y581917D01*
X121716Y581708D01*
X121800Y581458D01*
Y581042D01*
X121925Y580667D01*
X122175Y580417D01*
X122466Y580333D01*
X122758Y580417D01*
X122966Y580625D01*
X123091Y580958D01*
X123133Y581250D01*
G01Y584850D02*
X120633D01*
X122425Y583308D01*
Y585392D01*
G01X109608Y576567D02*
X109483Y576317D01*
X109400Y576025D01*
Y575692D01*
X109525Y575317D01*
X109733Y575025D01*
X109983Y574817D01*
X110400Y574650D01*
X110775Y574608D01*
X111150Y574692D01*
X111400Y574817D01*
X111650Y575067D01*
X111817Y575358D01*
X111900Y575650D01*
Y575942D01*
X111817Y576233D01*
X111692Y576483D01*
X111525Y576692D01*
G01X111900Y578750D02*
X109400D01*
X109900Y578250D01*
G01X111900D02*
Y579250D01*
G01Y581767D02*
X111358Y581850D01*
X110900Y581975D01*
X110483Y582142D01*
X110025Y582350D01*
X109400Y582683D01*
Y581017D01*
G01X110858Y584158D02*
X110567Y584450D01*
X110400Y584700D01*
X110317Y585033D01*
X110400Y585325D01*
X110567Y585533D01*
X110817Y585700D01*
X111108Y585742D01*
X111358Y585700D01*
X111608Y585533D01*
X111817Y585283D01*
X111900Y584992D01*
X111817Y584658D01*
X111567Y584367D01*
X111192Y584200D01*
X110775Y584158D01*
X110233Y584242D01*
X109942Y584367D01*
X109650Y584575D01*
X109442Y584867D01*
X109400Y585158D01*
X109483Y585450D01*
X109692Y585658D01*
G01X105986Y576525D02*
X105861Y576275D01*
X105778Y575983D01*
Y575650D01*
X105903Y575275D01*
X106111Y574983D01*
X106361Y574775D01*
X106778Y574608D01*
X107153Y574566D01*
X107528Y574650D01*
X107778Y574775D01*
X108028Y575025D01*
X108195Y575316D01*
X108278Y575608D01*
Y575900D01*
X108195Y576191D01*
X108070Y576441D01*
X107903Y576650D01*
G01X108278Y578708D02*
X105778D01*
X106278Y578208D01*
G01X108278D02*
Y579208D01*
G01Y581808D02*
X108236Y582100D01*
X108111Y582433D01*
X107903Y582641D01*
X107611Y582725D01*
X107320Y582641D01*
X107070Y582391D01*
X106945Y582016D01*
Y581600D01*
X106861Y581350D01*
X106653Y581141D01*
X106361Y581058D01*
X106070Y581183D01*
X105861Y581475D01*
X105778Y581808D01*
X105861Y582141D01*
X106070Y582433D01*
X106361Y582558D01*
X106653Y582475D01*
X106861Y582266D01*
X106945Y582016D01*
Y581600D01*
X107070Y581225D01*
X107320Y580975D01*
X107611Y580891D01*
X107903Y580975D01*
X108111Y581183D01*
X108236Y581516D01*
X108278Y581808D01*
G01X107778Y583991D02*
X108070Y584241D01*
X108236Y584575D01*
X108278Y584950D01*
X108236Y585283D01*
X108028Y585616D01*
X107778Y585825D01*
X107528Y585866D01*
X107236Y585783D01*
X107028Y585491D01*
X106945Y585200D01*
Y584825D01*
G01Y585200D02*
X106820Y585450D01*
X106611Y585658D01*
X106361Y585741D01*
X106111Y585658D01*
X105903Y585450D01*
X105778Y585075D01*
X105820Y584700D01*
X105986Y584325D01*
G01X108475Y588066D02*
X105975D01*
Y589107D01*
X106100Y589441D01*
X106267Y589649D01*
X106600Y589732D01*
X106933Y589649D01*
X107142Y589399D01*
X107267Y589107D01*
Y588066D01*
G01Y589107D02*
X108475Y589732D01*
G01X106392Y591207D02*
X106142Y591457D01*
X106017Y591749D01*
X105975Y592082D01*
X106058Y592499D01*
X106267Y592791D01*
X106517Y592874D01*
X106767Y592832D01*
X106975Y592666D01*
X107392Y591832D01*
X107683Y591457D01*
X108100Y591207D01*
X108475Y591124D01*
Y592874D01*
G01X108183Y594391D02*
X108392Y594682D01*
X108475Y595016D01*
X108392Y595349D01*
X108142Y595641D01*
X107767Y595849D01*
X107392Y595932D01*
X106933D01*
X106558Y595849D01*
X106225Y595641D01*
X106058Y595391D01*
X105975Y595099D01*
X106058Y594766D01*
X106225Y594516D01*
X106475Y594349D01*
X106808Y594266D01*
X107100Y594349D01*
X107392Y594557D01*
X107558Y594807D01*
X107600Y595099D01*
X107517Y595432D01*
X107308Y595682D01*
X106933Y595932D01*
G01X108475Y598116D02*
X107933Y598199D01*
X107475Y598324D01*
X107058Y598491D01*
X106600Y598699D01*
X105975Y599032D01*
Y597366D01*
G01X99345Y610579D02*
X99220Y610329D01*
X99137Y610037D01*
Y609704D01*
X99262Y609329D01*
X99470Y609037D01*
X99720Y608829D01*
X100137Y608662D01*
X100512Y608620D01*
X100887Y608704D01*
X101137Y608829D01*
X101387Y609079D01*
X101554Y609370D01*
X101637Y609662D01*
Y609954D01*
X101554Y610245D01*
X101429Y610495D01*
X101262Y610704D01*
G01X101137Y611845D02*
X101429Y612095D01*
X101595Y612429D01*
X101637Y612804D01*
X101595Y613137D01*
X101387Y613470D01*
X101137Y613679D01*
X100887Y613720D01*
X100595Y613637D01*
X100387Y613345D01*
X100304Y613054D01*
Y612679D01*
G01Y613054D02*
X100179Y613304D01*
X99970Y613512D01*
X99720Y613595D01*
X99470Y613512D01*
X99262Y613304D01*
X99137Y612929D01*
X99179Y612554D01*
X99345Y612179D01*
G01X99554Y615070D02*
X99304Y615320D01*
X99179Y615612D01*
X99137Y615945D01*
X99220Y616362D01*
X99429Y616654D01*
X99679Y616737D01*
X99929Y616695D01*
X100137Y616529D01*
X100554Y615695D01*
X100845Y615320D01*
X101262Y615070D01*
X101637Y614987D01*
Y616737D01*
G01Y618962D02*
X99137D01*
X99637Y618462D01*
G01X101637D02*
Y619462D01*
G01Y621979D02*
X101095Y622062D01*
X100637Y622187D01*
X100220Y622354D01*
X99762Y622562D01*
X99137Y622895D01*
Y621229D01*
G01X114638Y620984D02*
Y591456D01*
X167000D01*
Y620984D01*
X114638D01*
G01X100348Y638449D02*
X97848D01*
Y639490D01*
X97973Y639824D01*
X98140Y640032D01*
X98473Y640115D01*
X98806Y640032D01*
X99015Y639782D01*
X99140Y639490D01*
Y638449D01*
G01Y639490D02*
X100348Y640115D01*
G01X99973Y641465D02*
X100181Y641715D01*
X100306Y642007D01*
X100348Y642382D01*
X100265Y642757D01*
X100098Y643049D01*
X99806Y643257D01*
X99473Y643299D01*
X99140Y643215D01*
X98931Y643007D01*
X98765Y642715D01*
X98723Y642424D01*
X98765Y642132D01*
X98931Y641757D01*
X97848Y641882D01*
Y643007D01*
G01Y645482D02*
X97931Y645149D01*
X98140Y644899D01*
X98390Y644732D01*
X98723Y644607D01*
X99098Y644565D01*
X99473Y644607D01*
X99806Y644732D01*
X100056Y644899D01*
X100265Y645149D01*
X100348Y645482D01*
X100265Y645815D01*
X100056Y646065D01*
X99806Y646232D01*
X99473Y646357D01*
X99098Y646399D01*
X98723Y646357D01*
X98390Y646232D01*
X98140Y646065D01*
X97931Y645815D01*
X97848Y645482D01*
G01X100348Y649082D02*
X97848D01*
X99640Y647540D01*
Y649624D01*
G01X107767Y643292D02*
X107517Y643417D01*
X107225Y643500D01*
X106892D01*
X106517Y643375D01*
X106225Y643167D01*
X106017Y642917D01*
X105850Y642500D01*
X105808Y642125D01*
X105892Y641750D01*
X106017Y641500D01*
X106267Y641250D01*
X106558Y641083D01*
X106850Y641000D01*
X107142D01*
X107433Y641083D01*
X107683Y641208D01*
X107892Y641375D01*
G01X109158Y643083D02*
X109408Y643333D01*
X109700Y643458D01*
X110033Y643500D01*
X110450Y643417D01*
X110742Y643208D01*
X110825Y642958D01*
X110783Y642708D01*
X110617Y642500D01*
X109783Y642083D01*
X109408Y641792D01*
X109158Y641375D01*
X109075Y641000D01*
X110825D01*
G01X112967D02*
X113050Y641542D01*
X113175Y642000D01*
X113342Y642417D01*
X113550Y642875D01*
X113883Y643500D01*
X112217D01*
G01X115358Y643083D02*
X115608Y643333D01*
X115900Y643458D01*
X116233Y643500D01*
X116650Y643417D01*
X116942Y643208D01*
X117025Y642958D01*
X116983Y642708D01*
X116817Y642500D01*
X115983Y642083D01*
X115608Y641792D01*
X115358Y641375D01*
X115275Y641000D01*
X117025D01*
G01X122808Y660667D02*
X122683Y660417D01*
X122600Y660125D01*
Y659792D01*
X122725Y659417D01*
X122933Y659125D01*
X123183Y658917D01*
X123600Y658750D01*
X123975Y658708D01*
X124350Y658792D01*
X124600Y658917D01*
X124850Y659167D01*
X125017Y659458D01*
X125100Y659750D01*
Y660042D01*
X125017Y660333D01*
X124892Y660583D01*
X124725Y660792D01*
G01X125100Y662850D02*
X122600D01*
X123100Y662350D01*
G01X125100D02*
Y663350D01*
G01Y665867D02*
X124558Y665950D01*
X124100Y666075D01*
X123683Y666242D01*
X123225Y666450D01*
X122600Y666783D01*
Y665117D01*
G01Y669050D02*
X122683Y668717D01*
X122892Y668467D01*
X123142Y668300D01*
X123475Y668175D01*
X123850Y668133D01*
X124225Y668175D01*
X124558Y668300D01*
X124808Y668467D01*
X125017Y668717D01*
X125100Y669050D01*
X125017Y669383D01*
X124808Y669633D01*
X124558Y669800D01*
X124225Y669925D01*
X123850Y669967D01*
X123475Y669925D01*
X123142Y669800D01*
X122892Y669633D01*
X122683Y669383D01*
X122600Y669050D01*
G01X99597Y675806D02*
Y678306D01*
X100597D01*
X100930Y678181D01*
X101180Y677889D01*
X101263Y677556D01*
X101180Y677223D01*
X100972Y676973D01*
X100597Y676848D01*
X99597D01*
G01X102697Y675806D02*
Y678306D01*
X103738D01*
X104072Y678181D01*
X104280Y678014D01*
X104363Y677681D01*
X104280Y677348D01*
X104030Y677139D01*
X103738Y677014D01*
X102697D01*
G01X103738D02*
X104363Y675806D01*
G01X105713Y676306D02*
X105963Y676014D01*
X106297Y675848D01*
X106672Y675806D01*
X107005Y675848D01*
X107338Y676056D01*
X107547Y676306D01*
X107588Y676556D01*
X107505Y676848D01*
X107213Y677056D01*
X106922Y677139D01*
X106547D01*
G01X106922D02*
X107172Y677264D01*
X107380Y677473D01*
X107463Y677723D01*
X107380Y677973D01*
X107172Y678181D01*
X106797Y678306D01*
X106422Y678264D01*
X106047Y678098D01*
G01X110230Y675806D02*
Y678306D01*
X108688Y676514D01*
X110772D01*
G01X107900Y679900D02*
Y683900D01*
X100500D01*
G01X127708Y660267D02*
X127583Y660017D01*
X127500Y659725D01*
Y659392D01*
X127625Y659017D01*
X127833Y658725D01*
X128083Y658517D01*
X128500Y658350D01*
X128875Y658308D01*
X129250Y658392D01*
X129500Y658517D01*
X129750Y658767D01*
X129917Y659058D01*
X130000Y659350D01*
Y659642D01*
X129917Y659933D01*
X129792Y660183D01*
X129625Y660392D01*
G01X130000Y662450D02*
X127500D01*
X128000Y661950D01*
G01X130000D02*
Y662950D01*
G01Y665467D02*
X129458Y665550D01*
X129000Y665675D01*
X128583Y665842D01*
X128125Y666050D01*
X127500Y666383D01*
Y664717D01*
G01X127917Y667858D02*
X127667Y668108D01*
X127542Y668400D01*
X127500Y668733D01*
X127583Y669150D01*
X127792Y669442D01*
X128042Y669525D01*
X128292Y669483D01*
X128500Y669317D01*
X128917Y668483D01*
X129208Y668108D01*
X129625Y667858D01*
X130000Y667775D01*
Y669525D01*
G01X101334Y706467D02*
X98834D01*
Y707508D01*
X98959Y707842D01*
X99126Y708050D01*
X99459Y708133D01*
X99792Y708050D01*
X100001Y707800D01*
X100126Y707508D01*
Y706467D01*
G01Y707508D02*
X101334Y708133D01*
G01X101042Y709692D02*
X101251Y709983D01*
X101334Y710317D01*
X101251Y710650D01*
X101001Y710942D01*
X100626Y711150D01*
X100251Y711233D01*
X99792D01*
X99417Y711150D01*
X99084Y710942D01*
X98917Y710692D01*
X98834Y710400D01*
X98917Y710067D01*
X99084Y709817D01*
X99334Y709650D01*
X99667Y709567D01*
X99959Y709650D01*
X100251Y709858D01*
X100417Y710108D01*
X100459Y710400D01*
X100376Y710733D01*
X100167Y710983D01*
X99792Y711233D01*
G01X98834Y713500D02*
X98917Y713167D01*
X99126Y712917D01*
X99376Y712750D01*
X99709Y712625D01*
X100084Y712583D01*
X100459Y712625D01*
X100792Y712750D01*
X101042Y712917D01*
X101251Y713167D01*
X101334Y713500D01*
X101251Y713833D01*
X101042Y714083D01*
X100792Y714250D01*
X100459Y714375D01*
X100084Y714417D01*
X99709Y714375D01*
X99376Y714250D01*
X99126Y714083D01*
X98917Y713833D01*
X98834Y713500D01*
G01X99251Y715808D02*
X99001Y716058D01*
X98876Y716350D01*
X98834Y716683D01*
X98917Y717100D01*
X99126Y717392D01*
X99376Y717475D01*
X99626Y717433D01*
X99834Y717267D01*
X100251Y716433D01*
X100542Y716058D01*
X100959Y715808D01*
X101334Y715725D01*
Y717475D01*
G01X100292Y718908D02*
X100001Y719200D01*
X99834Y719450D01*
X99751Y719783D01*
X99834Y720075D01*
X100001Y720283D01*
X100251Y720450D01*
X100542Y720492D01*
X100792Y720450D01*
X101042Y720283D01*
X101251Y720033D01*
X101334Y719742D01*
X101251Y719408D01*
X101001Y719117D01*
X100626Y718950D01*
X100209Y718908D01*
X99667Y718992D01*
X99376Y719117D01*
X99084Y719325D01*
X98876Y719617D01*
X98834Y719908D01*
X98917Y720200D01*
X99126Y720408D01*
G01X108042Y706767D02*
X107917Y706517D01*
X107834Y706225D01*
Y705892D01*
X107959Y705517D01*
X108167Y705225D01*
X108417Y705017D01*
X108834Y704850D01*
X109209Y704808D01*
X109584Y704892D01*
X109834Y705017D01*
X110084Y705267D01*
X110251Y705558D01*
X110334Y705850D01*
Y706142D01*
X110251Y706433D01*
X110126Y706683D01*
X109959Y706892D01*
G01X108251Y708158D02*
X108001Y708408D01*
X107876Y708700D01*
X107834Y709033D01*
X107917Y709450D01*
X108126Y709742D01*
X108376Y709825D01*
X108626Y709783D01*
X108834Y709617D01*
X109251Y708783D01*
X109542Y708408D01*
X109959Y708158D01*
X110334Y708075D01*
Y709825D01*
G01X109292Y711258D02*
X109001Y711550D01*
X108834Y711800D01*
X108751Y712133D01*
X108834Y712425D01*
X109001Y712633D01*
X109251Y712800D01*
X109542Y712842D01*
X109792Y712800D01*
X110042Y712633D01*
X110251Y712383D01*
X110334Y712092D01*
X110251Y711758D01*
X110001Y711467D01*
X109626Y711300D01*
X109209Y711258D01*
X108667Y711342D01*
X108376Y711467D01*
X108084Y711675D01*
X107876Y711967D01*
X107834Y712258D01*
X107917Y712550D01*
X108126Y712758D01*
G01X110334Y715150D02*
X107834D01*
X108334Y714650D01*
G01X110334D02*
Y715650D01*
G01X109017Y700500D02*
Y703000D01*
X110058D01*
X110392Y702875D01*
X110600Y702708D01*
X110683Y702375D01*
X110600Y702042D01*
X110350Y701833D01*
X110058Y701708D01*
X109017D01*
G01X110058D02*
X110683Y700500D01*
G01X112033Y700875D02*
X112283Y700667D01*
X112575Y700542D01*
X112950Y700500D01*
X113325Y700583D01*
X113617Y700750D01*
X113825Y701042D01*
X113867Y701375D01*
X113783Y701708D01*
X113575Y701917D01*
X113283Y702083D01*
X112992Y702125D01*
X112700Y702083D01*
X112325Y701917D01*
X112450Y703000D01*
X113575D01*
G01X116050D02*
X115717Y702917D01*
X115467Y702708D01*
X115300Y702458D01*
X115175Y702125D01*
X115133Y701750D01*
X115175Y701375D01*
X115300Y701042D01*
X115467Y700792D01*
X115717Y700583D01*
X116050Y700500D01*
X116383Y700583D01*
X116633Y700792D01*
X116800Y701042D01*
X116925Y701375D01*
X116967Y701750D01*
X116925Y702125D01*
X116800Y702458D01*
X116633Y702708D01*
X116383Y702917D01*
X116050Y703000D01*
G01X118233Y701000D02*
X118483Y700708D01*
X118817Y700542D01*
X119192Y700500D01*
X119525Y700542D01*
X119858Y700750D01*
X120067Y701000D01*
X120108Y701250D01*
X120025Y701542D01*
X119733Y701750D01*
X119442Y701833D01*
X119067D01*
G01X119442D02*
X119692Y701958D01*
X119900Y702167D01*
X119983Y702417D01*
X119900Y702667D01*
X119692Y702875D01*
X119317Y703000D01*
X118942Y702958D01*
X118567Y702792D01*
G01X121600Y712300D02*
Y716300D01*
X114200D01*
G01X105834Y708017D02*
X103334D01*
Y709058D01*
X103459Y709392D01*
X103626Y709600D01*
X103959Y709683D01*
X104292Y709600D01*
X104501Y709350D01*
X104626Y709058D01*
Y708017D01*
G01Y709058D02*
X105834Y709683D01*
G01Y712450D02*
X103334D01*
X105126Y710908D01*
Y712992D01*
G01X104792Y714258D02*
X104501Y714550D01*
X104334Y714800D01*
X104251Y715133D01*
X104334Y715425D01*
X104501Y715633D01*
X104751Y715800D01*
X105042Y715842D01*
X105292Y715800D01*
X105542Y715633D01*
X105751Y715383D01*
X105834Y715092D01*
X105751Y714758D01*
X105501Y714467D01*
X105126Y714300D01*
X104709Y714258D01*
X104167Y714342D01*
X103876Y714467D01*
X103584Y714675D01*
X103376Y714967D01*
X103334Y715258D01*
X103417Y715550D01*
X103626Y715758D01*
G01X105834Y718150D02*
X105792Y718442D01*
X105667Y718775D01*
X105459Y718983D01*
X105167Y719067D01*
X104876Y718983D01*
X104626Y718733D01*
X104501Y718358D01*
Y717942D01*
X104417Y717692D01*
X104209Y717483D01*
X103917Y717400D01*
X103626Y717525D01*
X103417Y717817D01*
X103334Y718150D01*
X103417Y718483D01*
X103626Y718775D01*
X103917Y718900D01*
X104209Y718817D01*
X104417Y718608D01*
X104501Y718358D01*
Y717942D01*
X104626Y717567D01*
X104876Y717317D01*
X105167Y717233D01*
X105459Y717317D01*
X105667Y717525D01*
X105792Y717858D01*
X105834Y718150D01*
G01X124767Y703459D02*
X124517Y703584D01*
X124225Y703667D01*
X123892D01*
X123517Y703542D01*
X123225Y703334D01*
X123017Y703084D01*
X122850Y702667D01*
X122808Y702292D01*
X122892Y701917D01*
X123017Y701667D01*
X123267Y701417D01*
X123558Y701250D01*
X123850Y701167D01*
X124142D01*
X124433Y701250D01*
X124683Y701375D01*
X124892Y701542D01*
G01X126158Y703250D02*
X126408Y703500D01*
X126700Y703625D01*
X127033Y703667D01*
X127450Y703584D01*
X127742Y703375D01*
X127825Y703125D01*
X127783Y702875D01*
X127617Y702667D01*
X126783Y702250D01*
X126408Y701959D01*
X126158Y701542D01*
X126075Y701167D01*
X127825D01*
G01X130550D02*
Y703667D01*
X129008Y701875D01*
X131092D01*
G01X133650Y701167D02*
Y703667D01*
X132108Y701875D01*
X134192D01*
G01X124767Y699959D02*
X124517Y700084D01*
X124225Y700167D01*
X123892D01*
X123517Y700042D01*
X123225Y699834D01*
X123017Y699584D01*
X122850Y699167D01*
X122808Y698792D01*
X122892Y698417D01*
X123017Y698167D01*
X123267Y697917D01*
X123558Y697750D01*
X123850Y697667D01*
X124142D01*
X124433Y697750D01*
X124683Y697875D01*
X124892Y698042D01*
G01X126158Y699750D02*
X126408Y700000D01*
X126700Y700125D01*
X127033Y700167D01*
X127450Y700084D01*
X127742Y699875D01*
X127825Y699625D01*
X127783Y699375D01*
X127617Y699167D01*
X126783Y698750D01*
X126408Y698459D01*
X126158Y698042D01*
X126075Y697667D01*
X127825D01*
G01X130550D02*
Y700167D01*
X129008Y698375D01*
X131092D01*
G01X132233Y698167D02*
X132483Y697875D01*
X132817Y697709D01*
X133192Y697667D01*
X133525Y697709D01*
X133858Y697917D01*
X134067Y698167D01*
X134108Y698417D01*
X134025Y698709D01*
X133733Y698917D01*
X133442Y699000D01*
X133067D01*
G01X133442D02*
X133692Y699125D01*
X133900Y699334D01*
X133983Y699584D01*
X133900Y699834D01*
X133692Y700042D01*
X133317Y700167D01*
X132942Y700125D01*
X132567Y699959D01*
G01X111834Y688900D02*
X111792Y688567D01*
X111626Y688275D01*
X111376Y688025D01*
X111084Y687858D01*
X110751Y687775D01*
X110417D01*
X110084Y687858D01*
X109792Y688025D01*
X109542Y688275D01*
X109376Y688567D01*
X109334Y688900D01*
X109376Y689233D01*
X109542Y689525D01*
X109792Y689775D01*
X110084Y689942D01*
X110417Y690025D01*
X110751D01*
X111084Y689942D01*
X111376Y689775D01*
X111626Y689525D01*
X111792Y689233D01*
X111834Y688900D01*
G01X111167Y689233D02*
X111834Y689733D01*
G01X111542Y691292D02*
X111751Y691583D01*
X111834Y691917D01*
X111751Y692250D01*
X111501Y692542D01*
X111126Y692750D01*
X110751Y692833D01*
X110292D01*
X109917Y692750D01*
X109584Y692542D01*
X109417Y692292D01*
X109334Y692000D01*
X109417Y691667D01*
X109584Y691417D01*
X109834Y691250D01*
X110167Y691167D01*
X110459Y691250D01*
X110751Y691458D01*
X110917Y691708D01*
X110959Y692000D01*
X110876Y692333D01*
X110667Y692583D01*
X110292Y692833D01*
G01X111834Y695600D02*
X109334D01*
X111126Y694058D01*
Y696142D01*
G01X106450Y684650D02*
Y698650D01*
G01X114983Y749667D02*
Y747875D01*
X115150Y747500D01*
X115483Y747250D01*
X115900Y747167D01*
X116317Y747250D01*
X116650Y747500D01*
X116817Y747875D01*
Y749667D01*
G01X118083Y747667D02*
X118333Y747375D01*
X118667Y747209D01*
X119042Y747167D01*
X119375Y747209D01*
X119708Y747417D01*
X119917Y747667D01*
X119958Y747917D01*
X119875Y748209D01*
X119583Y748417D01*
X119292Y748500D01*
X118917D01*
G01X119292D02*
X119542Y748625D01*
X119750Y748834D01*
X119833Y749084D01*
X119750Y749334D01*
X119542Y749542D01*
X119167Y749667D01*
X118792Y749625D01*
X118417Y749459D01*
G01X122600Y747167D02*
Y749667D01*
X121058Y747875D01*
X123142D01*
G01X117600Y733800D02*
X129500D01*
G01X117600Y725800D02*
Y733800D01*
G01X129500Y725800D02*
X117600D01*
G01X129500Y733800D02*
Y725800D01*
G01X127900Y729800D02*
X129500Y728200D01*
G01X127900Y729800D02*
X129500Y731400D01*
G01X107542Y743267D02*
X107417Y743017D01*
X107334Y742725D01*
Y742392D01*
X107459Y742017D01*
X107667Y741725D01*
X107917Y741517D01*
X108334Y741350D01*
X108709Y741308D01*
X109084Y741392D01*
X109334Y741517D01*
X109584Y741767D01*
X109751Y742058D01*
X109834Y742350D01*
Y742642D01*
X109751Y742933D01*
X109626Y743183D01*
X109459Y743392D01*
G01X107751Y744658D02*
X107501Y744908D01*
X107376Y745200D01*
X107334Y745533D01*
X107417Y745950D01*
X107626Y746242D01*
X107876Y746325D01*
X108126Y746283D01*
X108334Y746117D01*
X108751Y745283D01*
X109042Y744908D01*
X109459Y744658D01*
X109834Y744575D01*
Y746325D01*
G01X109459Y747633D02*
X109667Y747883D01*
X109792Y748175D01*
X109834Y748550D01*
X109751Y748925D01*
X109584Y749217D01*
X109292Y749425D01*
X108959Y749467D01*
X108626Y749383D01*
X108417Y749175D01*
X108251Y748883D01*
X108209Y748592D01*
X108251Y748300D01*
X108417Y747925D01*
X107334Y748050D01*
Y749175D01*
G01X109542Y750942D02*
X109751Y751233D01*
X109834Y751567D01*
X109751Y751900D01*
X109501Y752192D01*
X109126Y752400D01*
X108751Y752483D01*
X108292D01*
X107917Y752400D01*
X107584Y752192D01*
X107417Y751942D01*
X107334Y751650D01*
X107417Y751317D01*
X107584Y751067D01*
X107834Y750900D01*
X108167Y750817D01*
X108459Y750900D01*
X108751Y751108D01*
X108917Y751358D01*
X108959Y751650D01*
X108876Y751983D01*
X108667Y752233D01*
X108292Y752483D01*
G01X104834Y744017D02*
X102334D01*
Y745058D01*
X102459Y745392D01*
X102626Y745600D01*
X102959Y745683D01*
X103292Y745600D01*
X103501Y745350D01*
X103626Y745058D01*
Y744017D01*
G01Y745058D02*
X104834Y745683D01*
G01X104459Y747033D02*
X104667Y747283D01*
X104792Y747575D01*
X104834Y747950D01*
X104751Y748325D01*
X104584Y748617D01*
X104292Y748825D01*
X103959Y748867D01*
X103626Y748783D01*
X103417Y748575D01*
X103251Y748283D01*
X103209Y747992D01*
X103251Y747700D01*
X103417Y747325D01*
X102334Y747450D01*
Y748575D01*
G01Y751050D02*
X102417Y750717D01*
X102626Y750467D01*
X102876Y750300D01*
X103209Y750175D01*
X103584Y750133D01*
X103959Y750175D01*
X104292Y750300D01*
X104542Y750467D01*
X104751Y750717D01*
X104834Y751050D01*
X104751Y751383D01*
X104542Y751633D01*
X104292Y751800D01*
X103959Y751925D01*
X103584Y751967D01*
X103209Y751925D01*
X102876Y751800D01*
X102626Y751633D01*
X102417Y751383D01*
X102334Y751050D01*
G01X102751Y753358D02*
X102501Y753608D01*
X102376Y753900D01*
X102334Y754233D01*
X102417Y754650D01*
X102626Y754942D01*
X102876Y755025D01*
X103126Y754983D01*
X103334Y754817D01*
X103751Y753983D01*
X104042Y753608D01*
X104459Y753358D01*
X104834Y753275D01*
Y755025D01*
G01X108900Y737500D02*
X104900D01*
Y730100D01*
G01X126017Y748667D02*
Y751167D01*
X127058D01*
X127392Y751042D01*
X127600Y750875D01*
X127683Y750542D01*
X127600Y750209D01*
X127350Y750000D01*
X127058Y749875D01*
X126017D01*
G01X127058D02*
X127683Y748667D01*
G01X130450D02*
Y751167D01*
X128908Y749375D01*
X130992D01*
G01X133050Y748667D02*
X133342Y748709D01*
X133675Y748834D01*
X133883Y749042D01*
X133967Y749334D01*
X133883Y749625D01*
X133633Y749875D01*
X133258Y750000D01*
X132842D01*
X132592Y750084D01*
X132383Y750292D01*
X132300Y750584D01*
X132425Y750875D01*
X132717Y751084D01*
X133050Y751167D01*
X133383Y751084D01*
X133675Y750875D01*
X133800Y750584D01*
X133717Y750292D01*
X133508Y750084D01*
X133258Y750000D01*
X132842D01*
X132467Y749875D01*
X132217Y749625D01*
X132133Y749334D01*
X132217Y749042D01*
X132425Y748834D01*
X132758Y748709D01*
X133050Y748667D01*
G01X135358Y749709D02*
X135650Y750000D01*
X135900Y750167D01*
X136233Y750250D01*
X136525Y750167D01*
X136733Y750000D01*
X136900Y749750D01*
X136942Y749459D01*
X136900Y749209D01*
X136733Y748959D01*
X136483Y748750D01*
X136192Y748667D01*
X135858Y748750D01*
X135567Y749000D01*
X135400Y749375D01*
X135358Y749792D01*
X135442Y750334D01*
X135567Y750625D01*
X135775Y750917D01*
X136067Y751125D01*
X136358Y751167D01*
X136650Y751084D01*
X136858Y750875D01*
G01X134400Y743200D02*
Y747200D01*
X127000D01*
G01X104900Y722600D02*
X108900D01*
Y730000D01*
G01X121550Y778100D02*
Y808100D01*
G01X99850Y778100D02*
X121550D01*
G01X99850Y808100D02*
Y778100D01*
G01X132500Y765000D02*
X116400D01*
G01Y772000D02*
X132500D01*
G01X116400Y765000D02*
Y772000D01*
G01X132334Y778467D02*
X129834D01*
Y779508D01*
X129959Y779842D01*
X130126Y780050D01*
X130459Y780133D01*
X130792Y780050D01*
X131001Y779800D01*
X131126Y779508D01*
Y778467D01*
G01Y779508D02*
X132334Y780133D01*
G01X130251Y781608D02*
X130001Y781858D01*
X129876Y782150D01*
X129834Y782483D01*
X129917Y782900D01*
X130126Y783192D01*
X130376Y783275D01*
X130626Y783233D01*
X130834Y783067D01*
X131251Y782233D01*
X131542Y781858D01*
X131959Y781608D01*
X132334Y781525D01*
Y783275D01*
G01Y785500D02*
X129834D01*
X130334Y785000D01*
G01X132334D02*
Y786000D01*
G01Y788600D02*
X129834D01*
X130334Y788100D01*
G01X132334D02*
Y789100D01*
G01Y791700D02*
X129834D01*
X130334Y791200D01*
G01X132334D02*
Y792200D01*
G01X128000Y782700D02*
X124000D01*
Y775300D01*
G01X128467Y773667D02*
Y776167D01*
X129508D01*
X129842Y776042D01*
X130050Y775875D01*
X130133Y775542D01*
X130050Y775209D01*
X129800Y775000D01*
X129508Y774875D01*
X128467D01*
G01X129508D02*
X130133Y773667D01*
G01X131608Y775750D02*
X131858Y776000D01*
X132150Y776125D01*
X132483Y776167D01*
X132900Y776084D01*
X133192Y775875D01*
X133275Y775625D01*
X133233Y775375D01*
X133067Y775167D01*
X132233Y774750D01*
X131858Y774459D01*
X131608Y774042D01*
X131525Y773667D01*
X133275D01*
G01X135500D02*
Y776167D01*
X135000Y775667D01*
G01Y773667D02*
X136000D01*
G01X138600D02*
Y776167D01*
X138100Y775667D01*
G01Y773667D02*
X139100D01*
G01X140783Y774042D02*
X141033Y773834D01*
X141325Y773709D01*
X141700Y773667D01*
X142075Y773750D01*
X142367Y773917D01*
X142575Y774209D01*
X142617Y774542D01*
X142533Y774875D01*
X142325Y775084D01*
X142033Y775250D01*
X141742Y775292D01*
X141450Y775250D01*
X141075Y775084D01*
X141200Y776167D01*
X142325D01*
G01X123700Y773000D02*
Y777000D01*
X116300D01*
G01X112800Y758000D02*
Y754000D01*
X120200D01*
G01X114834Y809967D02*
X112334D01*
Y811008D01*
X112459Y811342D01*
X112626Y811550D01*
X112959Y811633D01*
X113292Y811550D01*
X113501Y811300D01*
X113626Y811008D01*
Y809967D01*
G01Y811008D02*
X114834Y811633D01*
G01X114542Y813192D02*
X114751Y813483D01*
X114834Y813817D01*
X114751Y814150D01*
X114501Y814442D01*
X114126Y814650D01*
X113751Y814733D01*
X113292D01*
X112917Y814650D01*
X112584Y814442D01*
X112417Y814192D01*
X112334Y813900D01*
X112417Y813567D01*
X112584Y813317D01*
X112834Y813150D01*
X113167Y813067D01*
X113459Y813150D01*
X113751Y813358D01*
X113917Y813608D01*
X113959Y813900D01*
X113876Y814233D01*
X113667Y814483D01*
X113292Y814733D01*
G01X112334Y817000D02*
X112417Y816667D01*
X112626Y816417D01*
X112876Y816250D01*
X113209Y816125D01*
X113584Y816083D01*
X113959Y816125D01*
X114292Y816250D01*
X114542Y816417D01*
X114751Y816667D01*
X114834Y817000D01*
X114751Y817333D01*
X114542Y817583D01*
X114292Y817750D01*
X113959Y817875D01*
X113584Y817917D01*
X113209Y817875D01*
X112876Y817750D01*
X112626Y817583D01*
X112417Y817333D01*
X112334Y817000D01*
G01X112751Y819308D02*
X112501Y819558D01*
X112376Y819850D01*
X112334Y820183D01*
X112417Y820600D01*
X112626Y820892D01*
X112876Y820975D01*
X113126Y820933D01*
X113334Y820767D01*
X113751Y819933D01*
X114042Y819558D01*
X114459Y819308D01*
X114834Y819225D01*
Y820975D01*
G01X112334Y823200D02*
X112417Y822867D01*
X112626Y822617D01*
X112876Y822450D01*
X113209Y822325D01*
X113584Y822283D01*
X113959Y822325D01*
X114292Y822450D01*
X114542Y822617D01*
X114751Y822867D01*
X114834Y823200D01*
X114751Y823533D01*
X114542Y823783D01*
X114292Y823950D01*
X113959Y824075D01*
X113584Y824117D01*
X113209Y824075D01*
X112876Y823950D01*
X112626Y823783D01*
X112417Y823533D01*
X112334Y823200D01*
G01X126834Y792400D02*
X126792Y792067D01*
X126626Y791775D01*
X126376Y791525D01*
X126084Y791358D01*
X125751Y791275D01*
X125417D01*
X125084Y791358D01*
X124792Y791525D01*
X124542Y791775D01*
X124376Y792067D01*
X124334Y792400D01*
X124376Y792733D01*
X124542Y793025D01*
X124792Y793275D01*
X125084Y793442D01*
X125417Y793525D01*
X125751D01*
X126084Y793442D01*
X126376Y793275D01*
X126626Y793025D01*
X126792Y792733D01*
X126834Y792400D01*
G01X126167Y792733D02*
X126834Y793233D01*
G01X124751Y794708D02*
X124501Y794958D01*
X124376Y795250D01*
X124334Y795583D01*
X124417Y796000D01*
X124626Y796292D01*
X124876Y796375D01*
X125126Y796333D01*
X125334Y796167D01*
X125751Y795333D01*
X126042Y794958D01*
X126459Y794708D01*
X126834Y794625D01*
Y796375D01*
G01X126334Y797683D02*
X126626Y797933D01*
X126792Y798267D01*
X126834Y798642D01*
X126792Y798975D01*
X126584Y799308D01*
X126334Y799517D01*
X126084Y799558D01*
X125792Y799475D01*
X125584Y799183D01*
X125501Y798892D01*
Y798517D01*
G01Y798892D02*
X125376Y799142D01*
X125167Y799350D01*
X124917Y799433D01*
X124667Y799350D01*
X124459Y799142D01*
X124334Y798767D01*
X124376Y798392D01*
X124542Y798017D01*
G01X121550Y808100D02*
X99850D01*
G01X126483Y839667D02*
Y842167D01*
X127317D01*
X127650Y842042D01*
X127900Y841875D01*
X128108Y841625D01*
X128275Y841334D01*
X128317Y840917D01*
X128275Y840500D01*
X128108Y840209D01*
X127900Y839959D01*
X127650Y839792D01*
X127317Y839667D01*
X126483D01*
G01X129583Y840167D02*
X129833Y839875D01*
X130167Y839709D01*
X130542Y839667D01*
X130875Y839709D01*
X131208Y839917D01*
X131417Y840167D01*
X131458Y840417D01*
X131375Y840709D01*
X131083Y840917D01*
X130792Y841000D01*
X130417D01*
G01X130792D02*
X131042Y841125D01*
X131250Y841334D01*
X131333Y841584D01*
X131250Y841834D01*
X131042Y842042D01*
X130667Y842167D01*
X130292Y842125D01*
X129917Y841959D01*
G01X133517Y839667D02*
X133600Y840209D01*
X133725Y840667D01*
X133892Y841084D01*
X134100Y841542D01*
X134433Y842167D01*
X132767D01*
G01X117500Y831550D02*
Y822450D01*
X139300D01*
Y831550D01*
X117500D01*
G01X126217Y846459D02*
X125967Y846584D01*
X125675Y846667D01*
X125342D01*
X124967Y846542D01*
X124675Y846334D01*
X124467Y846084D01*
X124300Y845667D01*
X124258Y845292D01*
X124342Y844917D01*
X124467Y844667D01*
X124717Y844417D01*
X125008Y844250D01*
X125300Y844167D01*
X125592D01*
X125883Y844250D01*
X126133Y844375D01*
X126342Y844542D01*
G01X128317Y844167D02*
X128400Y844709D01*
X128525Y845167D01*
X128692Y845584D01*
X128900Y846042D01*
X129233Y846667D01*
X127567D01*
G01X130708Y846250D02*
X130958Y846500D01*
X131250Y846625D01*
X131583Y846667D01*
X132000Y846584D01*
X132292Y846375D01*
X132375Y846125D01*
X132333Y845875D01*
X132167Y845667D01*
X131333Y845250D01*
X130958Y844959D01*
X130708Y844542D01*
X130625Y844167D01*
X132375D01*
G01X134517D02*
X134600Y844709D01*
X134725Y845167D01*
X134892Y845584D01*
X135100Y846042D01*
X135433Y846667D01*
X133767D01*
G01X138200Y844167D02*
Y846667D01*
X136658Y844875D01*
X138742D01*
G01X136904Y173443D02*
X138696D01*
X139071Y173610D01*
X139321Y173943D01*
X139404Y174360D01*
X139321Y174777D01*
X139071Y175110D01*
X138696Y175277D01*
X136904D01*
G01X137321Y176668D02*
X137071Y176918D01*
X136946Y177210D01*
X136904Y177543D01*
X136987Y177960D01*
X137196Y178252D01*
X137446Y178335D01*
X137696Y178293D01*
X137904Y178127D01*
X138321Y177293D01*
X138612Y176918D01*
X139029Y176668D01*
X139404Y176585D01*
Y178335D01*
G01X137321Y179768D02*
X137071Y180018D01*
X136946Y180310D01*
X136904Y180643D01*
X136987Y181060D01*
X137196Y181352D01*
X137446Y181435D01*
X137696Y181393D01*
X137904Y181227D01*
X138321Y180393D01*
X138612Y180018D01*
X139029Y179768D01*
X139404Y179685D01*
Y181435D01*
G01X142630Y178131D02*
Y173531D01*
G01D02*
X157130D01*
G01D02*
Y178131D01*
G01Y174231D02*
X155530Y175831D01*
G01X165311Y173770D02*
Y176270D01*
X166352D01*
X166686Y176145D01*
X166894Y175978D01*
X166977Y175645D01*
X166894Y175312D01*
X166644Y175103D01*
X166352Y174978D01*
X165311D01*
G01X166352D02*
X166977Y173770D01*
G01X169744D02*
Y176270D01*
X168202Y174478D01*
X170286D01*
G01X172344Y176270D02*
X172011Y176187D01*
X171761Y175978D01*
X171594Y175728D01*
X171469Y175395D01*
X171427Y175020D01*
X171469Y174645D01*
X171594Y174312D01*
X171761Y174062D01*
X172011Y173853D01*
X172344Y173770D01*
X172677Y173853D01*
X172927Y174062D01*
X173094Y174312D01*
X173219Y174645D01*
X173261Y175020D01*
X173219Y175395D01*
X173094Y175728D01*
X172927Y175978D01*
X172677Y176187D01*
X172344Y176270D01*
G01X174736Y174062D02*
X175027Y173853D01*
X175361Y173770D01*
X175694Y173853D01*
X175986Y174103D01*
X176194Y174478D01*
X176277Y174853D01*
Y175312D01*
X176194Y175687D01*
X175986Y176020D01*
X175736Y176187D01*
X175444Y176270D01*
X175111Y176187D01*
X174861Y176020D01*
X174694Y175770D01*
X174611Y175437D01*
X174694Y175145D01*
X174902Y174853D01*
X175152Y174687D01*
X175444Y174645D01*
X175777Y174728D01*
X176027Y174937D01*
X176277Y175312D01*
G01X160705Y165790D02*
X161038Y165582D01*
X161413Y165457D01*
X161747D01*
X162080Y165582D01*
X162330Y165790D01*
X162455Y166082D01*
X162372Y166374D01*
X162163Y166624D01*
X161788Y166790D01*
X161288Y166874D01*
X160997Y167040D01*
X160872Y167332D01*
X160955Y167624D01*
X161163Y167832D01*
X161455Y167957D01*
X161747D01*
X162038Y167874D01*
X162288Y167665D01*
G01X163763Y165457D02*
Y167957D01*
G01X165347D02*
X163763Y166415D01*
G01X165597Y165457D02*
X164472Y167124D01*
G01X167780Y167957D02*
Y165457D01*
G01X166822Y167957D02*
X168738D01*
G01X170880Y165457D02*
Y167957D01*
X170380Y167457D01*
G01Y165457D02*
X171380D01*
G01X136350Y193167D02*
Y190667D01*
G01X135392Y193167D02*
X137308D01*
G01X140367Y192959D02*
X140117Y193084D01*
X139825Y193167D01*
X139492D01*
X139117Y193042D01*
X138825Y192834D01*
X138617Y192584D01*
X138450Y192167D01*
X138408Y191792D01*
X138492Y191417D01*
X138617Y191167D01*
X138867Y190917D01*
X139158Y190750D01*
X139450Y190667D01*
X139742D01*
X140033Y190750D01*
X140283Y190875D01*
X140492Y191042D01*
G01X142550Y190667D02*
Y193167D01*
X142050Y192667D01*
G01Y190667D02*
X143050D01*
G01X145567D02*
X145650Y191209D01*
X145775Y191667D01*
X145942Y192084D01*
X146150Y192542D01*
X146483Y193167D01*
X144817D01*
G01X171200Y195500D02*
X160000D01*
G01X132800Y213500D02*
Y195500D01*
G01D02*
X144000D01*
G01X157130Y178131D02*
X142630D01*
G01X155530Y175831D02*
X157130Y177431D01*
G01X164684Y179986D02*
Y188386D01*
X176884D01*
Y179986D01*
X164684D01*
G01X165217Y189967D02*
Y192467D01*
X166258D01*
X166592Y192342D01*
X166800Y192175D01*
X166883Y191842D01*
X166800Y191509D01*
X166550Y191300D01*
X166258Y191175D01*
X165217D01*
G01X166258D02*
X166883Y189967D01*
G01X169650D02*
Y192467D01*
X168108Y190675D01*
X170192D01*
G01X172250Y189967D02*
Y192467D01*
X171750Y191967D01*
G01Y189967D02*
X172750D01*
G01X175350Y192467D02*
X175017Y192384D01*
X174767Y192175D01*
X174600Y191925D01*
X174475Y191592D01*
X174433Y191217D01*
X174475Y190842D01*
X174600Y190509D01*
X174767Y190259D01*
X175017Y190050D01*
X175350Y189967D01*
X175683Y190050D01*
X175933Y190259D01*
X176100Y190509D01*
X176225Y190842D01*
X176267Y191217D01*
X176225Y191592D01*
X176100Y191925D01*
X175933Y192175D01*
X175683Y192384D01*
X175350Y192467D01*
G01X160000Y213500D02*
X171200D01*
G01X144000D02*
X132800D01*
G01X148112Y236538D02*
Y234746D01*
X148279Y234371D01*
X148612Y234121D01*
X149029Y234038D01*
X149446Y234121D01*
X149779Y234371D01*
X149946Y234746D01*
Y236538D01*
G01X152129Y234038D02*
Y236538D01*
X151629Y236038D01*
G01Y234038D02*
X152629D01*
G01X154521Y234330D02*
X154812Y234121D01*
X155146Y234038D01*
X155479Y234121D01*
X155771Y234371D01*
X155979Y234746D01*
X156062Y235121D01*
Y235580D01*
X155979Y235955D01*
X155771Y236288D01*
X155521Y236455D01*
X155229Y236538D01*
X154896Y236455D01*
X154646Y236288D01*
X154479Y236038D01*
X154396Y235705D01*
X154479Y235413D01*
X154687Y235121D01*
X154937Y234955D01*
X155229Y234913D01*
X155562Y234996D01*
X155812Y235205D01*
X156062Y235580D01*
G01X158829Y234038D02*
Y236538D01*
X157287Y234746D01*
X159371D01*
G01X160000Y215000D02*
Y233000D01*
G01D02*
X146000D01*
G01D02*
Y215000D01*
G01D02*
X160000D01*
G01X146000D02*
X152000D01*
G01D02*
X160000D01*
G01X135834Y234158D02*
X133334D01*
Y235742D01*
G01X134542Y235158D02*
Y234158D01*
G01X135834Y238050D02*
X133334D01*
X133834Y237550D01*
G01X135834D02*
Y238550D01*
G01X143750Y232850D02*
X134250D01*
Y215150D01*
X143750D01*
Y232850D01*
G01X165000Y215800D02*
X167500D01*
G01X165000Y214842D02*
Y216758D01*
G01X167500Y218067D02*
X165000D01*
Y219067D01*
X165125Y219400D01*
X165417Y219650D01*
X165750Y219733D01*
X166083Y219650D01*
X166333Y219442D01*
X166458Y219067D01*
Y218067D01*
G01X167500Y222000D02*
X165000D01*
X165500Y221500D01*
G01X167500D02*
Y222500D01*
G01Y225600D02*
X165000D01*
X166792Y224058D01*
Y226142D01*
G01X167500Y228117D02*
X166958Y228200D01*
X166500Y228325D01*
X166083Y228492D01*
X165625Y228700D01*
X165000Y229033D01*
Y227367D01*
G01X163254Y225821D02*
X160754D01*
Y226862D01*
X160879Y227196D01*
X161046Y227404D01*
X161379Y227487D01*
X161712Y227404D01*
X161921Y227154D01*
X162046Y226862D01*
Y225821D01*
G01Y226862D02*
X163254Y227487D01*
G01Y230254D02*
X160754D01*
X162546Y228712D01*
Y230796D01*
G01X162212Y232062D02*
X161921Y232354D01*
X161754Y232604D01*
X161671Y232937D01*
X161754Y233229D01*
X161921Y233437D01*
X162171Y233604D01*
X162462Y233646D01*
X162712Y233604D01*
X162962Y233437D01*
X163171Y233187D01*
X163254Y232896D01*
X163171Y232562D01*
X162921Y232271D01*
X162546Y232104D01*
X162129Y232062D01*
X161587Y232146D01*
X161296Y232271D01*
X161004Y232479D01*
X160796Y232771D01*
X160754Y233062D01*
X160837Y233354D01*
X161046Y233562D01*
G01X160900Y235590D02*
X164900D01*
Y242990D01*
G01X155894Y238373D02*
X137194D01*
Y248673D01*
X155894D01*
Y238373D01*
G01X160569Y275833D02*
X133869D01*
Y296533D01*
X160569D01*
Y275833D01*
G01X162117Y268000D02*
Y265500D01*
X163783D01*
G01X165967D02*
X166050Y266042D01*
X166175Y266500D01*
X166342Y266917D01*
X166550Y267375D01*
X166883Y268000D01*
X165217D01*
G01X153500Y262500D02*
Y269700D01*
G01D02*
X140100D01*
G01D02*
Y262500D01*
G01D02*
X153500D01*
G01X158990Y249836D02*
Y247336D01*
G01X158032Y249836D02*
X159948D01*
G01X163007Y249628D02*
X162757Y249753D01*
X162465Y249836D01*
X162132D01*
X161757Y249711D01*
X161465Y249503D01*
X161257Y249253D01*
X161090Y248836D01*
X161048Y248461D01*
X161132Y248086D01*
X161257Y247836D01*
X161507Y247586D01*
X161798Y247419D01*
X162090Y247336D01*
X162382D01*
X162673Y247419D01*
X162923Y247544D01*
X163132Y247711D01*
G01X165190Y247336D02*
Y249836D01*
X164690Y249336D01*
G01Y247336D02*
X165690D01*
G01X167373Y247711D02*
X167623Y247503D01*
X167915Y247378D01*
X168290Y247336D01*
X168665Y247419D01*
X168957Y247586D01*
X169165Y247878D01*
X169207Y248211D01*
X169123Y248544D01*
X168915Y248753D01*
X168623Y248919D01*
X168332Y248961D01*
X168040Y248919D01*
X167665Y248753D01*
X167790Y249836D01*
X168915D01*
G01X158990Y253836D02*
Y251336D01*
G01X158032Y253836D02*
X159948D01*
G01X163007Y253628D02*
X162757Y253753D01*
X162465Y253836D01*
X162132D01*
X161757Y253711D01*
X161465Y253503D01*
X161257Y253253D01*
X161090Y252836D01*
X161048Y252461D01*
X161132Y252086D01*
X161257Y251836D01*
X161507Y251586D01*
X161798Y251419D01*
X162090Y251336D01*
X162382D01*
X162673Y251419D01*
X162923Y251544D01*
X163132Y251711D01*
G01X165190Y251336D02*
Y253836D01*
X164690Y253336D01*
G01Y251336D02*
X165690D01*
G01X168790D02*
Y253836D01*
X167248Y252044D01*
X169332D01*
G01X155741Y250830D02*
X137041D01*
Y261130D01*
X155741D01*
Y250830D01*
G01X164662Y276290D02*
X162162D01*
Y277290D01*
X162287Y277623D01*
X162579Y277873D01*
X162912Y277956D01*
X163245Y277873D01*
X163495Y277665D01*
X163620Y277290D01*
Y276290D01*
G01X163412Y280473D02*
Y281306D01*
X164162D01*
X164412Y281056D01*
X164579Y280765D01*
X164662Y280348D01*
X164579Y279931D01*
X164412Y279640D01*
X164162Y279390D01*
X163870Y279223D01*
X163537Y279140D01*
X163245D01*
X162995Y279223D01*
X162704Y279390D01*
X162454Y279640D01*
X162287Y279890D01*
X162162Y280223D01*
Y280515D01*
X162245Y280848D01*
X162412Y281098D01*
G01X162579Y282531D02*
X162329Y282781D01*
X162204Y283073D01*
X162162Y283406D01*
X162245Y283823D01*
X162454Y284115D01*
X162704Y284198D01*
X162954Y284156D01*
X163162Y283990D01*
X163579Y283156D01*
X163870Y282781D01*
X164287Y282531D01*
X164662Y282448D01*
Y284198D01*
G01X132850Y290500D02*
Y295100D01*
G01X162567Y286500D02*
Y289000D01*
X163567D01*
X163900Y288875D01*
X164150Y288583D01*
X164233Y288250D01*
X164150Y287917D01*
X163942Y287667D01*
X163567Y287542D01*
X162567D01*
G01X165667Y289000D02*
Y286500D01*
X167333D01*
G01X169600D02*
Y289000D01*
X169100Y288500D01*
G01Y286500D02*
X170100D01*
G01X137217Y297700D02*
Y300200D01*
X138217D01*
X138550Y300075D01*
X138800Y299783D01*
X138883Y299450D01*
X138800Y299117D01*
X138592Y298867D01*
X138217Y298742D01*
X137217D01*
G01X142067Y299992D02*
X141817Y300117D01*
X141525Y300200D01*
X141192D01*
X140817Y300075D01*
X140525Y299867D01*
X140317Y299617D01*
X140150Y299200D01*
X140108Y298825D01*
X140192Y298450D01*
X140317Y298200D01*
X140567Y297950D01*
X140858Y297783D01*
X141150Y297700D01*
X141442D01*
X141733Y297783D01*
X141983Y297908D01*
X142192Y298075D01*
G01X144167Y297700D02*
X144250Y298242D01*
X144375Y298700D01*
X144542Y299117D01*
X144750Y299575D01*
X145083Y300200D01*
X143417D01*
G01X147350Y297700D02*
Y300200D01*
X146850Y299700D01*
G01Y297700D02*
X147850D01*
G01X138967Y313400D02*
Y315900D01*
X139967D01*
X140300Y315775D01*
X140550Y315483D01*
X140633Y315150D01*
X140550Y314817D01*
X140342Y314567D01*
X139967Y314442D01*
X138967D01*
G01X142067Y313400D02*
Y315900D01*
X143108D01*
X143442Y315775D01*
X143650Y315608D01*
X143733Y315275D01*
X143650Y314942D01*
X143400Y314733D01*
X143108Y314608D01*
X142067D01*
G01X143108D02*
X143733Y313400D01*
G01X146000D02*
Y315900D01*
X145500Y315400D01*
G01Y313400D02*
X146500D01*
G01X155014Y320277D02*
Y324277D01*
X147614D01*
G01X157049Y320984D02*
Y323484D01*
X158090D01*
X158424Y323359D01*
X158632Y323192D01*
X158715Y322859D01*
X158632Y322526D01*
X158382Y322317D01*
X158090Y322192D01*
X157049D01*
G01X158090D02*
X158715Y320984D01*
G01X160899D02*
X160982Y321526D01*
X161107Y321984D01*
X161274Y322401D01*
X161482Y322859D01*
X161815Y323484D01*
X160149D01*
G01X163165Y321484D02*
X163415Y321192D01*
X163749Y321026D01*
X164124Y320984D01*
X164457Y321026D01*
X164790Y321234D01*
X164999Y321484D01*
X165040Y321734D01*
X164957Y322026D01*
X164665Y322234D01*
X164374Y322317D01*
X163999D01*
G01X164374D02*
X164624Y322442D01*
X164832Y322651D01*
X164915Y322901D01*
X164832Y323151D01*
X164624Y323359D01*
X164249Y323484D01*
X163874Y323442D01*
X163499Y323276D01*
G01X166265Y321359D02*
X166515Y321151D01*
X166807Y321026D01*
X167182Y320984D01*
X167557Y321067D01*
X167849Y321234D01*
X168057Y321526D01*
X168099Y321859D01*
X168015Y322192D01*
X167807Y322401D01*
X167515Y322567D01*
X167224Y322609D01*
X166932Y322567D01*
X166557Y322401D01*
X166682Y323484D01*
X167807D01*
G01X147513Y320350D02*
Y324350D01*
X140113D01*
G01X151203Y340897D02*
X150870Y340939D01*
X150578Y341105D01*
X150328Y341355D01*
X150161Y341647D01*
X150078Y341980D01*
Y342314D01*
X150161Y342647D01*
X150328Y342939D01*
X150578Y343189D01*
X150870Y343355D01*
X151203Y343397D01*
X151536Y343355D01*
X151828Y343189D01*
X152078Y342939D01*
X152245Y342647D01*
X152328Y342314D01*
Y341980D01*
X152245Y341647D01*
X152078Y341355D01*
X151828Y341105D01*
X151536Y340939D01*
X151203Y340897D01*
G01X151536Y341564D02*
X152036Y340897D01*
G01X154803D02*
Y343397D01*
X153261Y341605D01*
X155345D01*
G01X156486Y341272D02*
X156736Y341064D01*
X157028Y340939D01*
X157403Y340897D01*
X157778Y340980D01*
X158070Y341147D01*
X158278Y341439D01*
X158320Y341772D01*
X158236Y342105D01*
X158028Y342314D01*
X157736Y342480D01*
X157445Y342522D01*
X157153Y342480D01*
X156778Y342314D01*
X156903Y343397D01*
X158028D01*
G01X149185Y325311D02*
X163185D01*
G01X149185Y338311D02*
Y325311D01*
G01X163185Y338311D02*
X149185D01*
G01X163185Y325311D02*
Y338311D01*
G01X134557Y342844D02*
X134224Y342886D01*
X133932Y343052D01*
X133682Y343302D01*
X133515Y343594D01*
X133432Y343927D01*
Y344261D01*
X133515Y344594D01*
X133682Y344886D01*
X133932Y345136D01*
X134224Y345302D01*
X134557Y345344D01*
X134890Y345302D01*
X135182Y345136D01*
X135432Y344886D01*
X135599Y344594D01*
X135682Y344261D01*
Y343927D01*
X135599Y343594D01*
X135432Y343302D01*
X135182Y343052D01*
X134890Y342886D01*
X134557Y342844D01*
G01X134890Y343511D02*
X135390Y342844D01*
G01X138157D02*
Y345344D01*
X136615Y343552D01*
X138699D01*
G01X139965Y343886D02*
X140257Y344177D01*
X140507Y344344D01*
X140840Y344427D01*
X141132Y344344D01*
X141340Y344177D01*
X141507Y343927D01*
X141549Y343636D01*
X141507Y343386D01*
X141340Y343136D01*
X141090Y342927D01*
X140799Y342844D01*
X140465Y342927D01*
X140174Y343177D01*
X140007Y343552D01*
X139965Y343969D01*
X140049Y344511D01*
X140174Y344802D01*
X140382Y345094D01*
X140674Y345302D01*
X140965Y345344D01*
X141257Y345261D01*
X141465Y345052D01*
G01X133917Y326765D02*
X147917D01*
G01X133917Y339765D02*
Y326765D01*
G01X147917Y339765D02*
X133917D01*
G01X147917Y326765D02*
Y339765D01*
G01X137100Y376150D02*
X132100D01*
Y381150D01*
G01X148900Y376150D02*
X153900D01*
Y381150D01*
G01X143180Y365297D02*
X140680D01*
Y366338D01*
X140805Y366672D01*
X140972Y366880D01*
X141305Y366963D01*
X141638Y366880D01*
X141847Y366630D01*
X141972Y366338D01*
Y365297D01*
G01Y366338D02*
X143180Y366963D01*
G01Y369730D02*
X140680D01*
X142472Y368188D01*
Y370272D01*
G01X142888Y371622D02*
X143097Y371913D01*
X143180Y372247D01*
X143097Y372580D01*
X142847Y372872D01*
X142472Y373080D01*
X142097Y373163D01*
X141638D01*
X141263Y373080D01*
X140930Y372872D01*
X140763Y372622D01*
X140680Y372330D01*
X140763Y371997D01*
X140930Y371747D01*
X141180Y371580D01*
X141513Y371497D01*
X141805Y371580D01*
X142097Y371788D01*
X142263Y372038D01*
X142305Y372330D01*
X142222Y372663D01*
X142013Y372913D01*
X141638Y373163D01*
G01X144000Y365300D02*
X148000D01*
Y372700D01*
G01X165267Y378000D02*
Y380500D01*
X166308D01*
X166642Y380375D01*
X166850Y380208D01*
X166933Y379875D01*
X166850Y379542D01*
X166600Y379333D01*
X166308Y379208D01*
X165267D01*
G01X166308D02*
X166933Y378000D01*
G01X168283Y378375D02*
X168533Y378167D01*
X168825Y378042D01*
X169200Y378000D01*
X169575Y378083D01*
X169867Y378250D01*
X170075Y378542D01*
X170117Y378875D01*
X170033Y379208D01*
X169825Y379417D01*
X169533Y379583D01*
X169242Y379625D01*
X168950Y379583D01*
X168575Y379417D01*
X168700Y380500D01*
X169825D01*
G01X172300D02*
X171967Y380417D01*
X171717Y380208D01*
X171550Y379958D01*
X171425Y379625D01*
X171383Y379250D01*
X171425Y378875D01*
X171550Y378542D01*
X171717Y378292D01*
X171967Y378083D01*
X172300Y378000D01*
X172633Y378083D01*
X172883Y378292D01*
X173050Y378542D01*
X173175Y378875D01*
X173217Y379250D01*
X173175Y379625D01*
X173050Y379958D01*
X172883Y380208D01*
X172633Y380417D01*
X172300Y380500D01*
G01X162800Y377200D02*
Y381200D01*
X155400D01*
G01X135710Y363471D02*
X133210D01*
Y364512D01*
X133335Y364846D01*
X133502Y365054D01*
X133835Y365137D01*
X134168Y365054D01*
X134377Y364804D01*
X134502Y364512D01*
Y363471D01*
G01Y364512D02*
X135710Y365137D01*
G01Y367904D02*
X133210D01*
X135002Y366362D01*
Y368446D01*
G01X135710Y370504D02*
X135668Y370796D01*
X135543Y371129D01*
X135335Y371337D01*
X135043Y371421D01*
X134752Y371337D01*
X134502Y371087D01*
X134377Y370712D01*
Y370296D01*
X134293Y370046D01*
X134085Y369837D01*
X133793Y369754D01*
X133502Y369879D01*
X133293Y370171D01*
X133210Y370504D01*
X133293Y370837D01*
X133502Y371129D01*
X133793Y371254D01*
X134085Y371171D01*
X134293Y370962D01*
X134377Y370712D01*
Y370296D01*
X134502Y369921D01*
X134752Y369671D01*
X135043Y369587D01*
X135335Y369671D01*
X135543Y369879D01*
X135668Y370212D01*
X135710Y370504D01*
G01X153000Y383079D02*
X156000D01*
G01X153000Y392921D02*
X155000D01*
G01X148900Y399850D02*
X153900D01*
Y394850D01*
G01X164100Y406497D02*
X161600D01*
Y407538D01*
X161725Y407872D01*
X161892Y408080D01*
X162225Y408163D01*
X162558Y408080D01*
X162767Y407830D01*
X162892Y407538D01*
Y406497D01*
G01Y407538D02*
X164100Y408163D01*
G01X163058Y409638D02*
X162767Y409930D01*
X162600Y410180D01*
X162517Y410513D01*
X162600Y410805D01*
X162767Y411013D01*
X163017Y411180D01*
X163308Y411222D01*
X163558Y411180D01*
X163808Y411013D01*
X164017Y410763D01*
X164100Y410472D01*
X164017Y410138D01*
X163767Y409847D01*
X163392Y409680D01*
X162975Y409638D01*
X162433Y409722D01*
X162142Y409847D01*
X161850Y410055D01*
X161642Y410347D01*
X161600Y410638D01*
X161683Y410930D01*
X161892Y411138D01*
G01X163725Y412613D02*
X163933Y412863D01*
X164058Y413155D01*
X164100Y413530D01*
X164017Y413905D01*
X163850Y414197D01*
X163558Y414405D01*
X163225Y414447D01*
X162892Y414363D01*
X162683Y414155D01*
X162517Y413863D01*
X162475Y413572D01*
X162517Y413280D01*
X162683Y412905D01*
X161600Y413030D01*
Y414155D01*
G01X163058Y415838D02*
X162767Y416130D01*
X162600Y416380D01*
X162517Y416713D01*
X162600Y417005D01*
X162767Y417213D01*
X163017Y417380D01*
X163308Y417422D01*
X163558Y417380D01*
X163808Y417213D01*
X164017Y416963D01*
X164100Y416672D01*
X164017Y416338D01*
X163767Y416047D01*
X163392Y415880D01*
X162975Y415838D01*
X162433Y415922D01*
X162142Y416047D01*
X161850Y416255D01*
X161642Y416547D01*
X161600Y416838D01*
X161683Y417130D01*
X161892Y417338D01*
G01X153600Y411700D02*
X149600D01*
Y404300D01*
G01X153700D02*
X157700D01*
Y411700D01*
G01X160780Y400936D02*
Y403436D01*
X161821D01*
X162155Y403311D01*
X162363Y403144D01*
X162446Y402811D01*
X162363Y402478D01*
X162113Y402269D01*
X161821Y402144D01*
X160780D01*
G01X161821D02*
X162446Y400936D01*
G01X163921Y401978D02*
X164213Y402269D01*
X164463Y402436D01*
X164796Y402519D01*
X165088Y402436D01*
X165296Y402269D01*
X165463Y402019D01*
X165505Y401728D01*
X165463Y401478D01*
X165296Y401228D01*
X165046Y401019D01*
X164755Y400936D01*
X164421Y401019D01*
X164130Y401269D01*
X163963Y401644D01*
X163921Y402061D01*
X164005Y402603D01*
X164130Y402894D01*
X164338Y403186D01*
X164630Y403394D01*
X164921Y403436D01*
X165213Y403353D01*
X165421Y403144D01*
G01X167813Y403436D02*
X167480Y403353D01*
X167230Y403144D01*
X167063Y402894D01*
X166938Y402561D01*
X166896Y402186D01*
X166938Y401811D01*
X167063Y401478D01*
X167230Y401228D01*
X167480Y401019D01*
X167813Y400936D01*
X168146Y401019D01*
X168396Y401228D01*
X168563Y401478D01*
X168688Y401811D01*
X168730Y402186D01*
X168688Y402561D01*
X168563Y402894D01*
X168396Y403144D01*
X168146Y403353D01*
X167813Y403436D01*
G01X170121Y403019D02*
X170371Y403269D01*
X170663Y403394D01*
X170996Y403436D01*
X171413Y403353D01*
X171705Y403144D01*
X171788Y402894D01*
X171746Y402644D01*
X171580Y402436D01*
X170746Y402019D01*
X170371Y401728D01*
X170121Y401311D01*
X170038Y400936D01*
X171788D01*
G01X152100Y404200D02*
Y400200D01*
X159500D01*
G01X132571Y404396D02*
X136571D01*
Y411796D01*
G01X161162Y427300D02*
X163662D01*
G01X161162Y426342D02*
Y428258D01*
G01X163662Y429567D02*
X161162D01*
Y430567D01*
X161287Y430900D01*
X161579Y431150D01*
X161912Y431233D01*
X162245Y431150D01*
X162495Y430942D01*
X162620Y430567D01*
Y429567D01*
G01X163662Y433500D02*
X161162D01*
X161662Y433000D01*
G01X163662D02*
Y434000D01*
G01X163287Y435683D02*
X163495Y435933D01*
X163620Y436225D01*
X163662Y436600D01*
X163579Y436975D01*
X163412Y437267D01*
X163120Y437475D01*
X162787Y437517D01*
X162454Y437433D01*
X162245Y437225D01*
X162079Y436933D01*
X162037Y436642D01*
X162079Y436350D01*
X162245Y435975D01*
X161162Y436100D01*
Y437225D01*
G01X162620Y438908D02*
X162329Y439200D01*
X162162Y439450D01*
X162079Y439783D01*
X162162Y440075D01*
X162329Y440283D01*
X162579Y440450D01*
X162870Y440492D01*
X163120Y440450D01*
X163370Y440283D01*
X163579Y440033D01*
X163662Y439742D01*
X163579Y439408D01*
X163329Y439117D01*
X162954Y438950D01*
X162537Y438908D01*
X161995Y438992D01*
X161704Y439117D01*
X161412Y439325D01*
X161204Y439617D01*
X161162Y439908D01*
X161245Y440200D01*
X161454Y440408D01*
G01X140800Y437400D02*
X143300D01*
G01X140800Y436442D02*
Y438358D01*
G01X143300Y439667D02*
X140800D01*
Y440667D01*
X140925Y441000D01*
X141217Y441250D01*
X141550Y441333D01*
X141883Y441250D01*
X142133Y441042D01*
X142258Y440667D01*
Y439667D01*
G01X141217Y442808D02*
X140967Y443058D01*
X140842Y443350D01*
X140800Y443683D01*
X140883Y444100D01*
X141092Y444392D01*
X141342Y444475D01*
X141592Y444433D01*
X141800Y444267D01*
X142217Y443433D01*
X142508Y443058D01*
X142925Y442808D01*
X143300Y442725D01*
Y444475D01*
G01Y447200D02*
X140800D01*
X142592Y445658D01*
Y447742D01*
G01X143300Y449800D02*
X140800D01*
X141300Y449300D01*
G01X143300D02*
Y450300D01*
G01X154289Y427376D02*
X156789D01*
G01X154289Y426418D02*
Y428334D01*
G01X156789Y429643D02*
X154289D01*
Y430643D01*
X154414Y430976D01*
X154706Y431226D01*
X155039Y431309D01*
X155372Y431226D01*
X155622Y431018D01*
X155747Y430643D01*
Y429643D01*
G01X154706Y432784D02*
X154456Y433034D01*
X154331Y433326D01*
X154289Y433659D01*
X154372Y434076D01*
X154581Y434368D01*
X154831Y434451D01*
X155081Y434409D01*
X155289Y434243D01*
X155706Y433409D01*
X155997Y433034D01*
X156414Y432784D01*
X156789Y432701D01*
Y434451D01*
G01X156497Y435968D02*
X156706Y436259D01*
X156789Y436593D01*
X156706Y436926D01*
X156456Y437218D01*
X156081Y437426D01*
X155706Y437509D01*
X155247D01*
X154872Y437426D01*
X154539Y437218D01*
X154372Y436968D01*
X154289Y436676D01*
X154372Y436343D01*
X154539Y436093D01*
X154789Y435926D01*
X155122Y435843D01*
X155414Y435926D01*
X155706Y436134D01*
X155872Y436384D01*
X155914Y436676D01*
X155831Y437009D01*
X155622Y437259D01*
X155247Y437509D01*
G01X154706Y438984D02*
X154456Y439234D01*
X154331Y439526D01*
X154289Y439859D01*
X154372Y440276D01*
X154581Y440568D01*
X154831Y440651D01*
X155081Y440609D01*
X155289Y440443D01*
X155706Y439609D01*
X155997Y439234D01*
X156414Y438984D01*
X156789Y438901D01*
Y440651D01*
G01X157662Y427300D02*
X160162D01*
G01X157662Y426342D02*
Y428258D01*
G01X160162Y429567D02*
X157662D01*
Y430567D01*
X157787Y430900D01*
X158079Y431150D01*
X158412Y431233D01*
X158745Y431150D01*
X158995Y430942D01*
X159120Y430567D01*
Y429567D01*
G01X158079Y432708D02*
X157829Y432958D01*
X157704Y433250D01*
X157662Y433583D01*
X157745Y434000D01*
X157954Y434292D01*
X158204Y434375D01*
X158454Y434333D01*
X158662Y434167D01*
X159079Y433333D01*
X159370Y432958D01*
X159787Y432708D01*
X160162Y432625D01*
Y434375D01*
G01X159870Y435892D02*
X160079Y436183D01*
X160162Y436517D01*
X160079Y436850D01*
X159829Y437142D01*
X159454Y437350D01*
X159079Y437433D01*
X158620D01*
X158245Y437350D01*
X157912Y437142D01*
X157745Y436892D01*
X157662Y436600D01*
X157745Y436267D01*
X157912Y436017D01*
X158162Y435850D01*
X158495Y435767D01*
X158787Y435850D01*
X159079Y436058D01*
X159245Y436308D01*
X159287Y436600D01*
X159204Y436933D01*
X158995Y437183D01*
X158620Y437433D01*
G01X159787Y438783D02*
X159995Y439033D01*
X160120Y439325D01*
X160162Y439700D01*
X160079Y440075D01*
X159912Y440367D01*
X159620Y440575D01*
X159287Y440617D01*
X158954Y440533D01*
X158745Y440325D01*
X158579Y440033D01*
X158537Y439742D01*
X158579Y439450D01*
X158745Y439075D01*
X157662Y439200D01*
Y440325D01*
G01X154300Y444300D02*
X156800D01*
G01X154300Y443342D02*
Y445258D01*
G01X156800Y446567D02*
X154300D01*
Y447567D01*
X154425Y447900D01*
X154717Y448150D01*
X155050Y448233D01*
X155383Y448150D01*
X155633Y447942D01*
X155758Y447567D01*
Y446567D01*
G01X156300Y449583D02*
X156592Y449833D01*
X156758Y450167D01*
X156800Y450542D01*
X156758Y450875D01*
X156550Y451208D01*
X156300Y451417D01*
X156050Y451458D01*
X155758Y451375D01*
X155550Y451083D01*
X155467Y450792D01*
Y450417D01*
G01Y450792D02*
X155342Y451042D01*
X155133Y451250D01*
X154883Y451333D01*
X154633Y451250D01*
X154425Y451042D01*
X154300Y450667D01*
X154342Y450292D01*
X154508Y449917D01*
G01X154717Y452808D02*
X154467Y453058D01*
X154342Y453350D01*
X154300Y453683D01*
X154383Y454100D01*
X154592Y454392D01*
X154842Y454475D01*
X155092Y454433D01*
X155300Y454267D01*
X155717Y453433D01*
X156008Y453058D01*
X156425Y452808D01*
X156800Y452725D01*
Y454475D01*
G01X156425Y455783D02*
X156633Y456033D01*
X156758Y456325D01*
X156800Y456700D01*
X156717Y457075D01*
X156550Y457367D01*
X156258Y457575D01*
X155925Y457617D01*
X155592Y457533D01*
X155383Y457325D01*
X155217Y457033D01*
X155175Y456742D01*
X155217Y456450D01*
X155383Y456075D01*
X154300Y456200D01*
Y457325D01*
G01X164662Y427600D02*
X167162D01*
G01X164662Y426642D02*
Y428558D01*
G01X167162Y429867D02*
X164662D01*
Y430867D01*
X164787Y431200D01*
X165079Y431450D01*
X165412Y431533D01*
X165745Y431450D01*
X165995Y431242D01*
X166120Y430867D01*
Y429867D01*
G01X166662Y432883D02*
X166954Y433133D01*
X167120Y433467D01*
X167162Y433842D01*
X167120Y434175D01*
X166912Y434508D01*
X166662Y434717D01*
X166412Y434758D01*
X166120Y434675D01*
X165912Y434383D01*
X165829Y434092D01*
Y433717D01*
G01Y434092D02*
X165704Y434342D01*
X165495Y434550D01*
X165245Y434633D01*
X164995Y434550D01*
X164787Y434342D01*
X164662Y433967D01*
X164704Y433592D01*
X164870Y433217D01*
G01X164662Y436900D02*
X164745Y436567D01*
X164954Y436317D01*
X165204Y436150D01*
X165537Y436025D01*
X165912Y435983D01*
X166287Y436025D01*
X166620Y436150D01*
X166870Y436317D01*
X167079Y436567D01*
X167162Y436900D01*
X167079Y437233D01*
X166870Y437483D01*
X166620Y437650D01*
X166287Y437775D01*
X165912Y437817D01*
X165537Y437775D01*
X165204Y437650D01*
X164954Y437483D01*
X164745Y437233D01*
X164662Y436900D01*
G01X165079Y439208D02*
X164829Y439458D01*
X164704Y439750D01*
X164662Y440083D01*
X164745Y440500D01*
X164954Y440792D01*
X165204Y440875D01*
X165454Y440833D01*
X165662Y440667D01*
X166079Y439833D01*
X166370Y439458D01*
X166787Y439208D01*
X167162Y439125D01*
Y440875D01*
G01X150048Y417261D02*
Y419761D01*
X151089D01*
X151423Y419636D01*
X151631Y419469D01*
X151714Y419136D01*
X151631Y418803D01*
X151381Y418594D01*
X151089Y418469D01*
X150048D01*
G01X151089D02*
X151714Y417261D01*
G01X153064Y417761D02*
X153314Y417469D01*
X153648Y417303D01*
X154023Y417261D01*
X154356Y417303D01*
X154689Y417511D01*
X154898Y417761D01*
X154939Y418011D01*
X154856Y418303D01*
X154564Y418511D01*
X154273Y418594D01*
X153898D01*
G01X154273D02*
X154523Y418719D01*
X154731Y418928D01*
X154814Y419178D01*
X154731Y419428D01*
X154523Y419636D01*
X154148Y419761D01*
X153773Y419719D01*
X153398Y419553D01*
G01X156164Y417761D02*
X156414Y417469D01*
X156748Y417303D01*
X157123Y417261D01*
X157456Y417303D01*
X157789Y417511D01*
X157998Y417761D01*
X158039Y418011D01*
X157956Y418303D01*
X157664Y418511D01*
X157373Y418594D01*
X156998D01*
G01X157373D02*
X157623Y418719D01*
X157831Y418928D01*
X157914Y419178D01*
X157831Y419428D01*
X157623Y419636D01*
X157248Y419761D01*
X156873Y419719D01*
X156498Y419553D01*
G01X154917Y422700D02*
Y425200D01*
X155958D01*
X156292Y425075D01*
X156500Y424908D01*
X156583Y424575D01*
X156500Y424242D01*
X156250Y424033D01*
X155958Y423908D01*
X154917D01*
G01X155958D02*
X156583Y422700D01*
G01X158850D02*
Y425200D01*
X158350Y424700D01*
G01Y422700D02*
X159350D01*
G01X161033Y423075D02*
X161283Y422867D01*
X161575Y422742D01*
X161950Y422700D01*
X162325Y422783D01*
X162617Y422950D01*
X162825Y423242D01*
X162867Y423575D01*
X162783Y423908D01*
X162575Y424117D01*
X162283Y424283D01*
X161992Y424325D01*
X161700Y424283D01*
X161325Y424117D01*
X161450Y425200D01*
X162575D01*
G01X164258Y423742D02*
X164550Y424033D01*
X164800Y424200D01*
X165133Y424283D01*
X165425Y424200D01*
X165633Y424033D01*
X165800Y423783D01*
X165842Y423492D01*
X165800Y423242D01*
X165633Y422992D01*
X165383Y422783D01*
X165092Y422700D01*
X164758Y422783D01*
X164467Y423033D01*
X164300Y423408D01*
X164258Y423825D01*
X164342Y424367D01*
X164467Y424658D01*
X164675Y424950D01*
X164967Y425158D01*
X165258Y425200D01*
X165550Y425117D01*
X165758Y424908D01*
G01X147900Y436317D02*
X145400D01*
Y437358D01*
X145525Y437692D01*
X145692Y437900D01*
X146025Y437983D01*
X146358Y437900D01*
X146567Y437650D01*
X146692Y437358D01*
Y436317D01*
G01Y437358D02*
X147900Y437983D01*
G01X145817Y439458D02*
X145567Y439708D01*
X145442Y440000D01*
X145400Y440333D01*
X145483Y440750D01*
X145692Y441042D01*
X145942Y441125D01*
X146192Y441083D01*
X146400Y440917D01*
X146817Y440083D01*
X147108Y439708D01*
X147525Y439458D01*
X147900Y439375D01*
Y441125D01*
G01Y443350D02*
X147858Y443642D01*
X147733Y443975D01*
X147525Y444183D01*
X147233Y444267D01*
X146942Y444183D01*
X146692Y443933D01*
X146567Y443558D01*
Y443142D01*
X146483Y442892D01*
X146275Y442683D01*
X145983Y442600D01*
X145692Y442725D01*
X145483Y443017D01*
X145400Y443350D01*
X145483Y443683D01*
X145692Y443975D01*
X145983Y444100D01*
X146275Y444017D01*
X146483Y443808D01*
X146567Y443558D01*
Y443142D01*
X146692Y442767D01*
X146942Y442517D01*
X147233Y442433D01*
X147525Y442517D01*
X147733Y442725D01*
X147858Y443058D01*
X147900Y443350D01*
G01Y446450D02*
X145400D01*
X145900Y445950D01*
G01X147900D02*
Y446950D01*
G01X152032Y423872D02*
X149532D01*
Y424913D01*
X149657Y425247D01*
X149824Y425455D01*
X150157Y425538D01*
X150490Y425455D01*
X150699Y425205D01*
X150824Y424913D01*
Y423872D01*
G01Y424913D02*
X152032Y425538D01*
G01X149949Y427013D02*
X149699Y427263D01*
X149574Y427555D01*
X149532Y427888D01*
X149615Y428305D01*
X149824Y428597D01*
X150074Y428680D01*
X150324Y428638D01*
X150532Y428472D01*
X150949Y427638D01*
X151240Y427263D01*
X151657Y427013D01*
X152032Y426930D01*
Y428680D01*
G01Y430905D02*
X151990Y431197D01*
X151865Y431530D01*
X151657Y431738D01*
X151365Y431822D01*
X151074Y431738D01*
X150824Y431488D01*
X150699Y431113D01*
Y430697D01*
X150615Y430447D01*
X150407Y430238D01*
X150115Y430155D01*
X149824Y430280D01*
X149615Y430572D01*
X149532Y430905D01*
X149615Y431238D01*
X149824Y431530D01*
X150115Y431655D01*
X150407Y431572D01*
X150615Y431363D01*
X150699Y431113D01*
Y430697D01*
X150824Y430322D01*
X151074Y430072D01*
X151365Y429988D01*
X151657Y430072D01*
X151865Y430280D01*
X151990Y430613D01*
X152032Y430905D01*
G01X150990Y433213D02*
X150699Y433505D01*
X150532Y433755D01*
X150449Y434088D01*
X150532Y434380D01*
X150699Y434588D01*
X150949Y434755D01*
X151240Y434797D01*
X151490Y434755D01*
X151740Y434588D01*
X151949Y434338D01*
X152032Y434047D01*
X151949Y433713D01*
X151699Y433422D01*
X151324Y433255D01*
X150907Y433213D01*
X150365Y433297D01*
X150074Y433422D01*
X149782Y433630D01*
X149574Y433922D01*
X149532Y434213D01*
X149615Y434505D01*
X149824Y434713D01*
G01X141200Y424217D02*
X138700D01*
Y425258D01*
X138825Y425592D01*
X138992Y425800D01*
X139325Y425883D01*
X139658Y425800D01*
X139867Y425550D01*
X139992Y425258D01*
Y424217D01*
G01Y425258D02*
X141200Y425883D01*
G01X140158Y427358D02*
X139867Y427650D01*
X139700Y427900D01*
X139617Y428233D01*
X139700Y428525D01*
X139867Y428733D01*
X140117Y428900D01*
X140408Y428942D01*
X140658Y428900D01*
X140908Y428733D01*
X141117Y428483D01*
X141200Y428192D01*
X141117Y427858D01*
X140867Y427567D01*
X140492Y427400D01*
X140075Y427358D01*
X139533Y427442D01*
X139242Y427567D01*
X138950Y427775D01*
X138742Y428067D01*
X138700Y428358D01*
X138783Y428650D01*
X138992Y428858D01*
G01X140700Y430333D02*
X140992Y430583D01*
X141158Y430917D01*
X141200Y431292D01*
X141158Y431625D01*
X140950Y431958D01*
X140700Y432167D01*
X140450Y432208D01*
X140158Y432125D01*
X139950Y431833D01*
X139867Y431542D01*
Y431167D01*
G01Y431542D02*
X139742Y431792D01*
X139533Y432000D01*
X139283Y432083D01*
X139033Y432000D01*
X138825Y431792D01*
X138700Y431417D01*
X138742Y431042D01*
X138908Y430667D01*
G01X138700Y434350D02*
X138783Y434017D01*
X138992Y433767D01*
X139242Y433600D01*
X139575Y433475D01*
X139950Y433433D01*
X140325Y433475D01*
X140658Y433600D01*
X140908Y433767D01*
X141117Y434017D01*
X141200Y434350D01*
X141117Y434683D01*
X140908Y434933D01*
X140658Y435100D01*
X140325Y435225D01*
X139950Y435267D01*
X139575Y435225D01*
X139242Y435100D01*
X138992Y434933D01*
X138783Y434683D01*
X138700Y434350D01*
G01X133250Y438290D02*
X137250D01*
Y445690D01*
G01X148698Y418306D02*
Y422306D01*
X141298D01*
G01X147831Y423795D02*
X145331D01*
Y424836D01*
X145456Y425170D01*
X145623Y425378D01*
X145956Y425461D01*
X146289Y425378D01*
X146498Y425128D01*
X146623Y424836D01*
Y423795D01*
G01Y424836D02*
X147831Y425461D01*
G01X147456Y426811D02*
X147664Y427061D01*
X147789Y427353D01*
X147831Y427728D01*
X147748Y428103D01*
X147581Y428395D01*
X147289Y428603D01*
X146956Y428645D01*
X146623Y428561D01*
X146414Y428353D01*
X146248Y428061D01*
X146206Y427770D01*
X146248Y427478D01*
X146414Y427103D01*
X145331Y427228D01*
Y428353D01*
G01X147456Y429911D02*
X147664Y430161D01*
X147789Y430453D01*
X147831Y430828D01*
X147748Y431203D01*
X147581Y431495D01*
X147289Y431703D01*
X146956Y431745D01*
X146623Y431661D01*
X146414Y431453D01*
X146248Y431161D01*
X146206Y430870D01*
X146248Y430578D01*
X146414Y430203D01*
X145331Y430328D01*
Y431453D01*
G01X146789Y433136D02*
X146498Y433428D01*
X146331Y433678D01*
X146248Y434011D01*
X146331Y434303D01*
X146498Y434511D01*
X146748Y434678D01*
X147039Y434720D01*
X147289Y434678D01*
X147539Y434511D01*
X147748Y434261D01*
X147831Y433970D01*
X147748Y433636D01*
X147498Y433345D01*
X147123Y433178D01*
X146706Y433136D01*
X146164Y433220D01*
X145873Y433345D01*
X145581Y433553D01*
X145373Y433845D01*
X145331Y434136D01*
X145414Y434428D01*
X145623Y434636D01*
G01X151184Y415456D02*
X150934Y415581D01*
X150642Y415664D01*
X150309D01*
X149934Y415539D01*
X149642Y415331D01*
X149434Y415081D01*
X149267Y414664D01*
X149225Y414289D01*
X149309Y413914D01*
X149434Y413664D01*
X149684Y413414D01*
X149975Y413247D01*
X150267Y413164D01*
X150559D01*
X150850Y413247D01*
X151100Y413372D01*
X151309Y413539D01*
G01X152450Y413664D02*
X152700Y413372D01*
X153034Y413206D01*
X153409Y413164D01*
X153742Y413206D01*
X154075Y413414D01*
X154284Y413664D01*
X154325Y413914D01*
X154242Y414206D01*
X153950Y414414D01*
X153659Y414497D01*
X153284D01*
G01X153659D02*
X153909Y414622D01*
X154117Y414831D01*
X154200Y415081D01*
X154117Y415331D01*
X153909Y415539D01*
X153534Y415664D01*
X153159Y415622D01*
X152784Y415456D01*
G01X156384Y413164D02*
X156467Y413706D01*
X156592Y414164D01*
X156759Y414581D01*
X156967Y415039D01*
X157300Y415664D01*
X155634D01*
G01X159567Y413164D02*
Y415664D01*
X159067Y415164D01*
G01Y413164D02*
X160067D01*
G01X157300Y475167D02*
Y472667D01*
G01X156342Y475167D02*
X158258D01*
G01X159567Y472667D02*
Y475167D01*
X160567D01*
X160900Y475042D01*
X161150Y474750D01*
X161233Y474417D01*
X161150Y474084D01*
X160942Y473834D01*
X160567Y473709D01*
X159567D01*
G01X162708Y474750D02*
X162958Y475000D01*
X163250Y475125D01*
X163583Y475167D01*
X164000Y475084D01*
X164292Y474875D01*
X164375Y474625D01*
X164333Y474375D01*
X164167Y474167D01*
X163333Y473750D01*
X162958Y473459D01*
X162708Y473042D01*
X162625Y472667D01*
X164375D01*
G01X166600D02*
Y475167D01*
X166100Y474667D01*
G01Y472667D02*
X167100D01*
G01X169700D02*
X169992Y472709D01*
X170325Y472834D01*
X170533Y473042D01*
X170617Y473334D01*
X170533Y473625D01*
X170283Y473875D01*
X169908Y474000D01*
X169492D01*
X169242Y474084D01*
X169033Y474292D01*
X168950Y474584D01*
X169075Y474875D01*
X169367Y475084D01*
X169700Y475167D01*
X170033Y475084D01*
X170325Y474875D01*
X170450Y474584D01*
X170367Y474292D01*
X170158Y474084D01*
X169908Y474000D01*
X169492D01*
X169117Y473875D01*
X168867Y473625D01*
X168783Y473334D01*
X168867Y473042D01*
X169075Y472834D01*
X169408Y472709D01*
X169700Y472667D01*
G01X147800Y471667D02*
Y469167D01*
G01X146842Y471667D02*
X148758D01*
G01X150067Y469167D02*
Y471667D01*
X151067D01*
X151400Y471542D01*
X151650Y471250D01*
X151733Y470917D01*
X151650Y470584D01*
X151442Y470334D01*
X151067Y470209D01*
X150067D01*
G01X153208Y471250D02*
X153458Y471500D01*
X153750Y471625D01*
X154083Y471667D01*
X154500Y471584D01*
X154792Y471375D01*
X154875Y471125D01*
X154833Y470875D01*
X154667Y470667D01*
X153833Y470250D01*
X153458Y469959D01*
X153208Y469542D01*
X153125Y469167D01*
X154875D01*
G01X156392Y469459D02*
X156683Y469250D01*
X157017Y469167D01*
X157350Y469250D01*
X157642Y469500D01*
X157850Y469875D01*
X157933Y470250D01*
Y470709D01*
X157850Y471084D01*
X157642Y471417D01*
X157392Y471584D01*
X157100Y471667D01*
X156767Y471584D01*
X156517Y471417D01*
X156350Y471167D01*
X156267Y470834D01*
X156350Y470542D01*
X156558Y470250D01*
X156808Y470084D01*
X157100Y470042D01*
X157433Y470125D01*
X157683Y470334D01*
X157933Y470709D01*
G01X159283Y469667D02*
X159533Y469375D01*
X159867Y469209D01*
X160242Y469167D01*
X160575Y469209D01*
X160908Y469417D01*
X161117Y469667D01*
X161158Y469917D01*
X161075Y470209D01*
X160783Y470417D01*
X160492Y470500D01*
X160117D01*
G01X160492D02*
X160742Y470625D01*
X160950Y470834D01*
X161033Y471084D01*
X160950Y471334D01*
X160742Y471542D01*
X160367Y471667D01*
X159992Y471625D01*
X159617Y471459D01*
G01X142300Y475167D02*
Y472667D01*
G01X141342Y475167D02*
X143258D01*
G01X144567Y472667D02*
Y475167D01*
X145567D01*
X145900Y475042D01*
X146150Y474750D01*
X146233Y474417D01*
X146150Y474084D01*
X145942Y473834D01*
X145567Y473709D01*
X144567D01*
G01X147583Y473167D02*
X147833Y472875D01*
X148167Y472709D01*
X148542Y472667D01*
X148875Y472709D01*
X149208Y472917D01*
X149417Y473167D01*
X149458Y473417D01*
X149375Y473709D01*
X149083Y473917D01*
X148792Y474000D01*
X148417D01*
G01X148792D02*
X149042Y474125D01*
X149250Y474334D01*
X149333Y474584D01*
X149250Y474834D01*
X149042Y475042D01*
X148667Y475167D01*
X148292Y475125D01*
X147917Y474959D01*
G01X150808Y474750D02*
X151058Y475000D01*
X151350Y475125D01*
X151683Y475167D01*
X152100Y475084D01*
X152392Y474875D01*
X152475Y474625D01*
X152433Y474375D01*
X152267Y474167D01*
X151433Y473750D01*
X151058Y473459D01*
X150808Y473042D01*
X150725Y472667D01*
X152475D01*
G01X153908Y473709D02*
X154200Y474000D01*
X154450Y474167D01*
X154783Y474250D01*
X155075Y474167D01*
X155283Y474000D01*
X155450Y473750D01*
X155492Y473459D01*
X155450Y473209D01*
X155283Y472959D01*
X155033Y472750D01*
X154742Y472667D01*
X154408Y472750D01*
X154117Y473000D01*
X153950Y473375D01*
X153908Y473792D01*
X153992Y474334D01*
X154117Y474625D01*
X154325Y474917D01*
X154617Y475125D01*
X154908Y475167D01*
X155200Y475084D01*
X155408Y474875D01*
G01X160627Y449721D02*
Y445721D01*
X168027D01*
G01X144200Y455800D02*
X148200D01*
Y463200D01*
G01X148632Y448155D02*
X152632D01*
Y455555D01*
G01X137800Y447467D02*
X135300D01*
Y448508D01*
X135425Y448842D01*
X135592Y449050D01*
X135925Y449133D01*
X136258Y449050D01*
X136467Y448800D01*
X136592Y448508D01*
Y447467D01*
G01Y448508D02*
X137800Y449133D01*
G01X135717Y450608D02*
X135467Y450858D01*
X135342Y451150D01*
X135300Y451483D01*
X135383Y451900D01*
X135592Y452192D01*
X135842Y452275D01*
X136092Y452233D01*
X136300Y452067D01*
X136717Y451233D01*
X137008Y450858D01*
X137425Y450608D01*
X137800Y450525D01*
Y452275D01*
G01X137300Y453583D02*
X137592Y453833D01*
X137758Y454167D01*
X137800Y454542D01*
X137758Y454875D01*
X137550Y455208D01*
X137300Y455417D01*
X137050Y455458D01*
X136758Y455375D01*
X136550Y455083D01*
X136467Y454792D01*
Y454417D01*
G01Y454792D02*
X136342Y455042D01*
X136133Y455250D01*
X135883Y455333D01*
X135633Y455250D01*
X135425Y455042D01*
X135300Y454667D01*
X135342Y454292D01*
X135508Y453917D01*
G01X139000Y463200D02*
X135000D01*
Y455800D01*
G01X144000Y458700D02*
X140000D01*
Y451300D01*
G01X144431Y448078D02*
X148431D01*
Y455478D01*
G01X166000Y574517D02*
X163500D01*
Y575558D01*
X163625Y575892D01*
X163792Y576100D01*
X164125Y576183D01*
X164458Y576100D01*
X164667Y575850D01*
X164792Y575558D01*
Y574517D01*
G01Y575558D02*
X166000Y576183D01*
G01X163917Y577658D02*
X163667Y577908D01*
X163542Y578200D01*
X163500Y578533D01*
X163583Y578950D01*
X163792Y579242D01*
X164042Y579325D01*
X164292Y579283D01*
X164500Y579117D01*
X164917Y578283D01*
X165208Y577908D01*
X165625Y577658D01*
X166000Y577575D01*
Y579325D01*
G01X163917Y580758D02*
X163667Y581008D01*
X163542Y581300D01*
X163500Y581633D01*
X163583Y582050D01*
X163792Y582342D01*
X164042Y582425D01*
X164292Y582383D01*
X164500Y582217D01*
X164917Y581383D01*
X165208Y581008D01*
X165625Y580758D01*
X166000Y580675D01*
Y582425D01*
G01Y584650D02*
X165958Y584942D01*
X165833Y585275D01*
X165625Y585483D01*
X165333Y585567D01*
X165042Y585483D01*
X164792Y585233D01*
X164667Y584858D01*
Y584442D01*
X164583Y584192D01*
X164375Y583983D01*
X164083Y583900D01*
X163792Y584025D01*
X163583Y584317D01*
X163500Y584650D01*
X163583Y584983D01*
X163792Y585275D01*
X164083Y585400D01*
X164375Y585317D01*
X164583Y585108D01*
X164667Y584858D01*
Y584442D01*
X164792Y584067D01*
X165042Y583817D01*
X165333Y583733D01*
X165625Y583817D01*
X165833Y584025D01*
X165958Y584358D01*
X166000Y584650D01*
G01X136769Y573020D02*
X140769D01*
Y580420D01*
G01X148208Y581267D02*
X148083Y581017D01*
X148000Y580725D01*
Y580392D01*
X148125Y580017D01*
X148333Y579725D01*
X148583Y579517D01*
X149000Y579350D01*
X149375Y579308D01*
X149750Y579392D01*
X150000Y579517D01*
X150250Y579767D01*
X150417Y580058D01*
X150500Y580350D01*
Y580642D01*
X150417Y580933D01*
X150292Y581183D01*
X150125Y581392D01*
G01X150500Y583450D02*
X148000D01*
X148500Y582950D01*
G01X150500D02*
Y583950D01*
G01Y586467D02*
X149958Y586550D01*
X149500Y586675D01*
X149083Y586842D01*
X148625Y587050D01*
X148000Y587383D01*
Y585717D01*
G01X150125Y588733D02*
X150333Y588983D01*
X150458Y589275D01*
X150500Y589650D01*
X150417Y590025D01*
X150250Y590317D01*
X149958Y590525D01*
X149625Y590567D01*
X149292Y590483D01*
X149083Y590275D01*
X148917Y589983D01*
X148875Y589692D01*
X148917Y589400D01*
X149083Y589025D01*
X148000Y589150D01*
Y590275D01*
G01X155208Y580767D02*
X155083Y580517D01*
X155000Y580225D01*
Y579892D01*
X155125Y579517D01*
X155333Y579225D01*
X155583Y579017D01*
X156000Y578850D01*
X156375Y578808D01*
X156750Y578892D01*
X157000Y579017D01*
X157250Y579267D01*
X157417Y579558D01*
X157500Y579850D01*
Y580142D01*
X157417Y580433D01*
X157292Y580683D01*
X157125Y580892D01*
G01X157500Y582950D02*
X155000D01*
X155500Y582450D01*
G01X157500D02*
Y583450D01*
G01Y585967D02*
X156958Y586050D01*
X156500Y586175D01*
X156083Y586342D01*
X155625Y586550D01*
X155000Y586883D01*
Y585217D01*
G01X157500Y589150D02*
X157458Y589442D01*
X157333Y589775D01*
X157125Y589983D01*
X156833Y590067D01*
X156542Y589983D01*
X156292Y589733D01*
X156167Y589358D01*
Y588942D01*
X156083Y588692D01*
X155875Y588483D01*
X155583Y588400D01*
X155292Y588525D01*
X155083Y588817D01*
X155000Y589150D01*
X155083Y589483D01*
X155292Y589775D01*
X155583Y589900D01*
X155875Y589817D01*
X156083Y589608D01*
X156167Y589358D01*
Y588942D01*
X156292Y588567D01*
X156542Y588317D01*
X156833Y588233D01*
X157125Y588317D01*
X157333Y588525D01*
X157458Y588858D01*
X157500Y589150D01*
G01X154494Y570940D02*
X154244Y571065D01*
X153952Y571148D01*
X153619D01*
X153244Y571023D01*
X152952Y570815D01*
X152744Y570565D01*
X152577Y570148D01*
X152535Y569773D01*
X152619Y569398D01*
X152744Y569148D01*
X152994Y568898D01*
X153285Y568731D01*
X153577Y568648D01*
X153869D01*
X154160Y568731D01*
X154410Y568856D01*
X154619Y569023D01*
G01X156677Y568648D02*
Y571148D01*
X156177Y570648D01*
G01Y568648D02*
X157177D01*
G01X159777D02*
X160069Y568690D01*
X160402Y568815D01*
X160610Y569023D01*
X160694Y569315D01*
X160610Y569606D01*
X160360Y569856D01*
X159985Y569981D01*
X159569D01*
X159319Y570065D01*
X159110Y570273D01*
X159027Y570565D01*
X159152Y570856D01*
X159444Y571065D01*
X159777Y571148D01*
X160110Y571065D01*
X160402Y570856D01*
X160527Y570565D01*
X160444Y570273D01*
X160235Y570065D01*
X159985Y569981D01*
X159569D01*
X159194Y569856D01*
X158944Y569606D01*
X158860Y569315D01*
X158944Y569023D01*
X159152Y568815D01*
X159485Y568690D01*
X159777Y568648D01*
G01X161960Y569023D02*
X162210Y568815D01*
X162502Y568690D01*
X162877Y568648D01*
X163252Y568731D01*
X163544Y568898D01*
X163752Y569190D01*
X163794Y569523D01*
X163710Y569856D01*
X163502Y570065D01*
X163210Y570231D01*
X162919Y570273D01*
X162627Y570231D01*
X162252Y570065D01*
X162377Y571148D01*
X163502D01*
G01X163300Y590000D02*
Y587500D01*
G01X162342Y590000D02*
X164258D01*
G01X165567Y587500D02*
Y590000D01*
X166567D01*
X166900Y589875D01*
X167150Y589583D01*
X167233Y589250D01*
X167150Y588917D01*
X166942Y588667D01*
X166567Y588542D01*
X165567D01*
G01X168708Y589583D02*
X168958Y589833D01*
X169250Y589958D01*
X169583Y590000D01*
X170000Y589917D01*
X170292Y589708D01*
X170375Y589458D01*
X170333Y589208D01*
X170167Y589000D01*
X169333Y588583D01*
X168958Y588292D01*
X168708Y587875D01*
X168625Y587500D01*
X170375D01*
G01X171683Y588000D02*
X171933Y587708D01*
X172267Y587542D01*
X172642Y587500D01*
X172975Y587542D01*
X173308Y587750D01*
X173517Y588000D01*
X173558Y588250D01*
X173475Y588542D01*
X173183Y588750D01*
X172892Y588833D01*
X172517D01*
G01X172892D02*
X173142Y588958D01*
X173350Y589167D01*
X173433Y589417D01*
X173350Y589667D01*
X173142Y589875D01*
X172767Y590000D01*
X172392Y589958D01*
X172017Y589792D01*
G01X175617Y587500D02*
X175700Y588042D01*
X175825Y588500D01*
X175992Y588917D01*
X176200Y589375D01*
X176533Y590000D01*
X174867D01*
G01X152552Y635346D02*
Y637846D01*
X153593D01*
X153927Y637721D01*
X154135Y637554D01*
X154218Y637221D01*
X154135Y636888D01*
X153885Y636679D01*
X153593Y636554D01*
X152552D01*
G01X153593D02*
X154218Y635346D01*
G01X155693Y637429D02*
X155943Y637679D01*
X156235Y637804D01*
X156568Y637846D01*
X156985Y637763D01*
X157277Y637554D01*
X157360Y637304D01*
X157318Y637054D01*
X157152Y636846D01*
X156318Y636429D01*
X155943Y636138D01*
X155693Y635721D01*
X155610Y635346D01*
X157360D01*
G01X158668Y635846D02*
X158918Y635554D01*
X159252Y635388D01*
X159627Y635346D01*
X159960Y635388D01*
X160293Y635596D01*
X160502Y635846D01*
X160543Y636096D01*
X160460Y636388D01*
X160168Y636596D01*
X159877Y636679D01*
X159502D01*
G01X159877D02*
X160127Y636804D01*
X160335Y637013D01*
X160418Y637263D01*
X160335Y637513D01*
X160127Y637721D01*
X159752Y637846D01*
X159377Y637804D01*
X159002Y637638D01*
G01X161893Y637429D02*
X162143Y637679D01*
X162435Y637804D01*
X162768Y637846D01*
X163185Y637763D01*
X163477Y637554D01*
X163560Y637304D01*
X163518Y637054D01*
X163352Y636846D01*
X162518Y636429D01*
X162143Y636138D01*
X161893Y635721D01*
X161810Y635346D01*
X163560D01*
G01X141369Y638620D02*
Y634620D01*
X148769D01*
G01X131851Y650436D02*
Y646436D01*
X139251D01*
G01X154302Y641638D02*
X154052Y641763D01*
X153760Y641846D01*
X153427D01*
X153052Y641721D01*
X152760Y641513D01*
X152552Y641263D01*
X152385Y640846D01*
X152343Y640471D01*
X152427Y640096D01*
X152552Y639846D01*
X152802Y639596D01*
X153093Y639429D01*
X153385Y639346D01*
X153677D01*
X153968Y639429D01*
X154218Y639554D01*
X154427Y639721D01*
G01X155693Y641429D02*
X155943Y641679D01*
X156235Y641804D01*
X156568Y641846D01*
X156985Y641763D01*
X157277Y641554D01*
X157360Y641304D01*
X157318Y641054D01*
X157152Y640846D01*
X156318Y640429D01*
X155943Y640138D01*
X155693Y639721D01*
X155610Y639346D01*
X157360D01*
G01X158668Y639846D02*
X158918Y639554D01*
X159252Y639388D01*
X159627Y639346D01*
X159960Y639388D01*
X160293Y639596D01*
X160502Y639846D01*
X160543Y640096D01*
X160460Y640388D01*
X160168Y640596D01*
X159877Y640679D01*
X159502D01*
G01X159877D02*
X160127Y640804D01*
X160335Y641013D01*
X160418Y641263D01*
X160335Y641513D01*
X160127Y641721D01*
X159752Y641846D01*
X159377Y641804D01*
X159002Y641638D01*
G01X161977Y639638D02*
X162268Y639429D01*
X162602Y639346D01*
X162935Y639429D01*
X163227Y639679D01*
X163435Y640054D01*
X163518Y640429D01*
Y640888D01*
X163435Y641263D01*
X163227Y641596D01*
X162977Y641763D01*
X162685Y641846D01*
X162352Y641763D01*
X162102Y641596D01*
X161935Y641346D01*
X161852Y641013D01*
X161935Y640721D01*
X162143Y640429D01*
X162393Y640263D01*
X162685Y640221D01*
X163018Y640304D01*
X163268Y640513D01*
X163518Y640888D01*
G01X154302Y649638D02*
X154052Y649763D01*
X153760Y649846D01*
X153427D01*
X153052Y649721D01*
X152760Y649513D01*
X152552Y649263D01*
X152385Y648846D01*
X152343Y648471D01*
X152427Y648096D01*
X152552Y647846D01*
X152802Y647596D01*
X153093Y647429D01*
X153385Y647346D01*
X153677D01*
X153968Y647429D01*
X154218Y647554D01*
X154427Y647721D01*
G01X156485Y647346D02*
Y649846D01*
X155985Y649346D01*
G01Y647346D02*
X156985D01*
G01X159585D02*
X159877Y647388D01*
X160210Y647513D01*
X160418Y647721D01*
X160502Y648013D01*
X160418Y648304D01*
X160168Y648554D01*
X159793Y648679D01*
X159377D01*
X159127Y648763D01*
X158918Y648971D01*
X158835Y649263D01*
X158960Y649554D01*
X159252Y649763D01*
X159585Y649846D01*
X159918Y649763D01*
X160210Y649554D01*
X160335Y649263D01*
X160252Y648971D01*
X160043Y648763D01*
X159793Y648679D01*
X159377D01*
X159002Y648554D01*
X158752Y648304D01*
X158668Y648013D01*
X158752Y647721D01*
X158960Y647513D01*
X159293Y647388D01*
X159585Y647346D01*
G01X162685Y649846D02*
X162352Y649763D01*
X162102Y649554D01*
X161935Y649304D01*
X161810Y648971D01*
X161768Y648596D01*
X161810Y648221D01*
X161935Y647888D01*
X162102Y647638D01*
X162352Y647429D01*
X162685Y647346D01*
X163018Y647429D01*
X163268Y647638D01*
X163435Y647888D01*
X163560Y648221D01*
X163602Y648596D01*
X163560Y648971D01*
X163435Y649304D01*
X163268Y649554D01*
X163018Y649763D01*
X162685Y649846D01*
G01X154302Y645638D02*
X154052Y645763D01*
X153760Y645846D01*
X153427D01*
X153052Y645721D01*
X152760Y645513D01*
X152552Y645263D01*
X152385Y644846D01*
X152343Y644471D01*
X152427Y644096D01*
X152552Y643846D01*
X152802Y643596D01*
X153093Y643429D01*
X153385Y643346D01*
X153677D01*
X153968Y643429D01*
X154218Y643554D01*
X154427Y643721D01*
G01X156485Y643346D02*
Y645846D01*
X155985Y645346D01*
G01Y643346D02*
X156985D01*
G01X159502D02*
X159585Y643888D01*
X159710Y644346D01*
X159877Y644763D01*
X160085Y645221D01*
X160418Y645846D01*
X158752D01*
G01X161977Y643638D02*
X162268Y643429D01*
X162602Y643346D01*
X162935Y643429D01*
X163227Y643679D01*
X163435Y644054D01*
X163518Y644429D01*
Y644888D01*
X163435Y645263D01*
X163227Y645596D01*
X162977Y645763D01*
X162685Y645846D01*
X162352Y645763D01*
X162102Y645596D01*
X161935Y645346D01*
X161852Y645013D01*
X161935Y644721D01*
X162143Y644429D01*
X162393Y644263D01*
X162685Y644221D01*
X163018Y644304D01*
X163268Y644513D01*
X163518Y644888D01*
G01X137983Y625740D02*
Y623948D01*
X138150Y623573D01*
X138483Y623323D01*
X138900Y623240D01*
X139317Y623323D01*
X139650Y623573D01*
X139817Y623948D01*
Y625740D01*
G01X142000Y623240D02*
Y625740D01*
X141500Y625240D01*
G01Y623240D02*
X142500D01*
G01X145100D02*
X145392Y623282D01*
X145725Y623407D01*
X145933Y623615D01*
X146017Y623907D01*
X145933Y624198D01*
X145683Y624448D01*
X145308Y624573D01*
X144892D01*
X144642Y624657D01*
X144433Y624865D01*
X144350Y625157D01*
X144475Y625448D01*
X144767Y625657D01*
X145100Y625740D01*
X145433Y625657D01*
X145725Y625448D01*
X145850Y625157D01*
X145767Y624865D01*
X145558Y624657D01*
X145308Y624573D01*
X144892D01*
X144517Y624448D01*
X144267Y624198D01*
X144183Y623907D01*
X144267Y623615D01*
X144475Y623407D01*
X144808Y623282D01*
X145100Y623240D01*
G01X134017Y656000D02*
Y658500D01*
X135058D01*
X135392Y658375D01*
X135600Y658208D01*
X135683Y657875D01*
X135600Y657542D01*
X135350Y657333D01*
X135058Y657208D01*
X134017D01*
G01X135058D02*
X135683Y656000D01*
G01X137158Y658083D02*
X137408Y658333D01*
X137700Y658458D01*
X138033Y658500D01*
X138450Y658417D01*
X138742Y658208D01*
X138825Y657958D01*
X138783Y657708D01*
X138617Y657500D01*
X137783Y657083D01*
X137408Y656792D01*
X137158Y656375D01*
X137075Y656000D01*
X138825D01*
G01X140133Y656500D02*
X140383Y656208D01*
X140717Y656042D01*
X141092Y656000D01*
X141425Y656042D01*
X141758Y656250D01*
X141967Y656500D01*
X142008Y656750D01*
X141925Y657042D01*
X141633Y657250D01*
X141342Y657333D01*
X140967D01*
G01X141342D02*
X141592Y657458D01*
X141800Y657667D01*
X141883Y657917D01*
X141800Y658167D01*
X141592Y658375D01*
X141217Y658500D01*
X140842Y658458D01*
X140467Y658292D01*
G01X144150Y656000D02*
Y658500D01*
X143650Y658000D01*
G01Y656000D02*
X144650D01*
G01X135767Y654292D02*
X135517Y654417D01*
X135225Y654500D01*
X134892D01*
X134517Y654375D01*
X134225Y654167D01*
X134017Y653917D01*
X133850Y653500D01*
X133808Y653125D01*
X133892Y652750D01*
X134017Y652500D01*
X134267Y652250D01*
X134558Y652083D01*
X134850Y652000D01*
X135142D01*
X135433Y652083D01*
X135683Y652208D01*
X135892Y652375D01*
G01X137950Y652000D02*
Y654500D01*
X137450Y654000D01*
G01Y652000D02*
X138450D01*
G01X140967D02*
X141050Y652542D01*
X141175Y653000D01*
X141342Y653417D01*
X141550Y653875D01*
X141883Y654500D01*
X140217D01*
G01X144067Y652000D02*
X144150Y652542D01*
X144275Y653000D01*
X144442Y653417D01*
X144650Y653875D01*
X144983Y654500D01*
X143317D01*
G01X158362Y714003D02*
X158112Y714128D01*
X157820Y714211D01*
X157487D01*
X157112Y714086D01*
X156820Y713878D01*
X156612Y713628D01*
X156445Y713211D01*
X156403Y712836D01*
X156487Y712461D01*
X156612Y712211D01*
X156862Y711961D01*
X157153Y711794D01*
X157445Y711711D01*
X157737D01*
X158028Y711794D01*
X158278Y711919D01*
X158487Y712086D01*
G01X159753Y712753D02*
X160045Y713044D01*
X160295Y713211D01*
X160628Y713294D01*
X160920Y713211D01*
X161128Y713044D01*
X161295Y712794D01*
X161337Y712503D01*
X161295Y712253D01*
X161128Y712003D01*
X160878Y711794D01*
X160587Y711711D01*
X160253Y711794D01*
X159962Y712044D01*
X159795Y712419D01*
X159753Y712836D01*
X159837Y713378D01*
X159962Y713669D01*
X160170Y713961D01*
X160462Y714169D01*
X160753Y714211D01*
X161045Y714128D01*
X161253Y713919D01*
G01X162937Y712003D02*
X163228Y711794D01*
X163562Y711711D01*
X163895Y711794D01*
X164187Y712044D01*
X164395Y712419D01*
X164478Y712794D01*
Y713253D01*
X164395Y713628D01*
X164187Y713961D01*
X163937Y714128D01*
X163645Y714211D01*
X163312Y714128D01*
X163062Y713961D01*
X162895Y713711D01*
X162812Y713378D01*
X162895Y713086D01*
X163103Y712794D01*
X163353Y712628D01*
X163645Y712586D01*
X163978Y712669D01*
X164228Y712878D01*
X164478Y713253D01*
G01X165953Y713794D02*
X166203Y714044D01*
X166495Y714169D01*
X166828Y714211D01*
X167245Y714128D01*
X167537Y713919D01*
X167620Y713669D01*
X167578Y713419D01*
X167412Y713211D01*
X166578Y712794D01*
X166203Y712503D01*
X165953Y712086D01*
X165870Y711711D01*
X167620D01*
G01X137042Y698767D02*
X136917Y698517D01*
X136834Y698225D01*
Y697892D01*
X136959Y697517D01*
X137167Y697225D01*
X137417Y697017D01*
X137834Y696850D01*
X138209Y696808D01*
X138584Y696892D01*
X138834Y697017D01*
X139084Y697267D01*
X139251Y697558D01*
X139334Y697850D01*
Y698142D01*
X139251Y698433D01*
X139126Y698683D01*
X138959Y698892D01*
G01X137251Y700158D02*
X137001Y700408D01*
X136876Y700700D01*
X136834Y701033D01*
X136917Y701450D01*
X137126Y701742D01*
X137376Y701825D01*
X137626Y701783D01*
X137834Y701617D01*
X138251Y700783D01*
X138542Y700408D01*
X138959Y700158D01*
X139334Y700075D01*
Y701825D01*
G01X138292Y703258D02*
X138001Y703550D01*
X137834Y703800D01*
X137751Y704133D01*
X137834Y704425D01*
X138001Y704633D01*
X138251Y704800D01*
X138542Y704842D01*
X138792Y704800D01*
X139042Y704633D01*
X139251Y704383D01*
X139334Y704092D01*
X139251Y703758D01*
X139001Y703467D01*
X138626Y703300D01*
X138209Y703258D01*
X137667Y703342D01*
X137376Y703467D01*
X137084Y703675D01*
X136876Y703967D01*
X136834Y704258D01*
X136917Y704550D01*
X137126Y704758D01*
G01X137251Y706358D02*
X137001Y706608D01*
X136876Y706900D01*
X136834Y707233D01*
X136917Y707650D01*
X137126Y707942D01*
X137376Y708025D01*
X137626Y707983D01*
X137834Y707817D01*
X138251Y706983D01*
X138542Y706608D01*
X138959Y706358D01*
X139334Y706275D01*
Y708025D01*
G01X132542Y707267D02*
X132417Y707017D01*
X132334Y706725D01*
Y706392D01*
X132459Y706017D01*
X132667Y705725D01*
X132917Y705517D01*
X133334Y705350D01*
X133709Y705308D01*
X134084Y705392D01*
X134334Y705517D01*
X134584Y705767D01*
X134751Y706058D01*
X134834Y706350D01*
Y706642D01*
X134751Y706933D01*
X134626Y707183D01*
X134459Y707392D01*
G01X132751Y708658D02*
X132501Y708908D01*
X132376Y709200D01*
X132334Y709533D01*
X132417Y709950D01*
X132626Y710242D01*
X132876Y710325D01*
X133126Y710283D01*
X133334Y710117D01*
X133751Y709283D01*
X134042Y708908D01*
X134459Y708658D01*
X134834Y708575D01*
Y710325D01*
G01X134459Y711633D02*
X134667Y711883D01*
X134792Y712175D01*
X134834Y712550D01*
X134751Y712925D01*
X134584Y713217D01*
X134292Y713425D01*
X133959Y713467D01*
X133626Y713383D01*
X133417Y713175D01*
X133251Y712883D01*
X133209Y712592D01*
X133251Y712300D01*
X133417Y711925D01*
X132334Y712050D01*
Y713175D01*
G01X134834Y715650D02*
X134792Y715942D01*
X134667Y716275D01*
X134459Y716483D01*
X134167Y716567D01*
X133876Y716483D01*
X133626Y716233D01*
X133501Y715858D01*
Y715442D01*
X133417Y715192D01*
X133209Y714983D01*
X132917Y714900D01*
X132626Y715025D01*
X132417Y715317D01*
X132334Y715650D01*
X132417Y715983D01*
X132626Y716275D01*
X132917Y716400D01*
X133209Y716317D01*
X133417Y716108D01*
X133501Y715858D01*
Y715442D01*
X133626Y715067D01*
X133876Y714817D01*
X134167Y714733D01*
X134459Y714817D01*
X134667Y715025D01*
X134792Y715358D01*
X134834Y715650D01*
G01X152542Y705767D02*
X152417Y705517D01*
X152334Y705225D01*
Y704892D01*
X152459Y704517D01*
X152667Y704225D01*
X152917Y704017D01*
X153334Y703850D01*
X153709Y703808D01*
X154084Y703892D01*
X154334Y704017D01*
X154584Y704267D01*
X154751Y704558D01*
X154834Y704850D01*
Y705142D01*
X154751Y705433D01*
X154626Y705683D01*
X154459Y705892D01*
G01X154834Y707867D02*
X154292Y707950D01*
X153834Y708075D01*
X153417Y708242D01*
X152959Y708450D01*
X152334Y708783D01*
Y707117D01*
G01Y711050D02*
X152417Y710717D01*
X152626Y710467D01*
X152876Y710300D01*
X153209Y710175D01*
X153584Y710133D01*
X153959Y710175D01*
X154292Y710300D01*
X154542Y710467D01*
X154751Y710717D01*
X154834Y711050D01*
X154751Y711383D01*
X154542Y711633D01*
X154292Y711800D01*
X153959Y711925D01*
X153584Y711967D01*
X153209Y711925D01*
X152876Y711800D01*
X152626Y711633D01*
X152417Y711383D01*
X152334Y711050D01*
G01X154834Y714150D02*
X152334D01*
X152834Y713650D01*
G01X154834D02*
Y714650D01*
G01X148542Y705767D02*
X148417Y705517D01*
X148334Y705225D01*
Y704892D01*
X148459Y704517D01*
X148667Y704225D01*
X148917Y704017D01*
X149334Y703850D01*
X149709Y703808D01*
X150084Y703892D01*
X150334Y704017D01*
X150584Y704267D01*
X150751Y704558D01*
X150834Y704850D01*
Y705142D01*
X150751Y705433D01*
X150626Y705683D01*
X150459Y705892D01*
G01X150834Y707867D02*
X150292Y707950D01*
X149834Y708075D01*
X149417Y708242D01*
X148959Y708450D01*
X148334Y708783D01*
Y707117D01*
G01Y711050D02*
X148417Y710717D01*
X148626Y710467D01*
X148876Y710300D01*
X149209Y710175D01*
X149584Y710133D01*
X149959Y710175D01*
X150292Y710300D01*
X150542Y710467D01*
X150751Y710717D01*
X150834Y711050D01*
X150751Y711383D01*
X150542Y711633D01*
X150292Y711800D01*
X149959Y711925D01*
X149584Y711967D01*
X149209Y711925D01*
X148876Y711800D01*
X148626Y711633D01*
X148417Y711383D01*
X148334Y711050D01*
G01Y714150D02*
X148417Y713817D01*
X148626Y713567D01*
X148876Y713400D01*
X149209Y713275D01*
X149584Y713233D01*
X149959Y713275D01*
X150292Y713400D01*
X150542Y713567D01*
X150751Y713817D01*
X150834Y714150D01*
X150751Y714483D01*
X150542Y714733D01*
X150292Y714900D01*
X149959Y715025D01*
X149584Y715067D01*
X149209Y715025D01*
X148876Y714900D01*
X148626Y714733D01*
X148417Y714483D01*
X148334Y714150D01*
G01X140767Y749492D02*
X140517Y749617D01*
X140225Y749700D01*
X139892D01*
X139517Y749575D01*
X139225Y749367D01*
X139017Y749117D01*
X138850Y748700D01*
X138808Y748325D01*
X138892Y747950D01*
X139017Y747700D01*
X139267Y747450D01*
X139558Y747283D01*
X139850Y747200D01*
X140142D01*
X140433Y747283D01*
X140683Y747408D01*
X140892Y747575D01*
G01X142158Y748242D02*
X142450Y748533D01*
X142700Y748700D01*
X143033Y748783D01*
X143325Y748700D01*
X143533Y748533D01*
X143700Y748283D01*
X143742Y747992D01*
X143700Y747742D01*
X143533Y747492D01*
X143283Y747283D01*
X142992Y747200D01*
X142658Y747283D01*
X142367Y747533D01*
X142200Y747908D01*
X142158Y748325D01*
X142242Y748867D01*
X142367Y749158D01*
X142575Y749450D01*
X142867Y749658D01*
X143158Y749700D01*
X143450Y749617D01*
X143658Y749408D01*
G01X145342Y747492D02*
X145633Y747283D01*
X145967Y747200D01*
X146300Y747283D01*
X146592Y747533D01*
X146800Y747908D01*
X146883Y748283D01*
Y748742D01*
X146800Y749117D01*
X146592Y749450D01*
X146342Y749617D01*
X146050Y749700D01*
X145717Y749617D01*
X145467Y749450D01*
X145300Y749200D01*
X145217Y748867D01*
X145300Y748575D01*
X145508Y748283D01*
X145758Y748117D01*
X146050Y748075D01*
X146383Y748158D01*
X146633Y748367D01*
X146883Y748742D01*
G01X149150Y747200D02*
Y749700D01*
X148650Y749200D01*
G01Y747200D02*
X149650D01*
G01X135517Y740167D02*
Y742667D01*
X136558D01*
X136892Y742542D01*
X137100Y742375D01*
X137183Y742042D01*
X137100Y741709D01*
X136850Y741500D01*
X136558Y741375D01*
X135517D01*
G01X136558D02*
X137183Y740167D01*
G01X138742Y740459D02*
X139033Y740250D01*
X139367Y740167D01*
X139700Y740250D01*
X139992Y740500D01*
X140200Y740875D01*
X140283Y741250D01*
Y741709D01*
X140200Y742084D01*
X139992Y742417D01*
X139742Y742584D01*
X139450Y742667D01*
X139117Y742584D01*
X138867Y742417D01*
X138700Y742167D01*
X138617Y741834D01*
X138700Y741542D01*
X138908Y741250D01*
X139158Y741084D01*
X139450Y741042D01*
X139783Y741125D01*
X140033Y741334D01*
X140283Y741709D01*
G01X141758Y741209D02*
X142050Y741500D01*
X142300Y741667D01*
X142633Y741750D01*
X142925Y741667D01*
X143133Y741500D01*
X143300Y741250D01*
X143342Y740959D01*
X143300Y740709D01*
X143133Y740459D01*
X142883Y740250D01*
X142592Y740167D01*
X142258Y740250D01*
X141967Y740500D01*
X141800Y740875D01*
X141758Y741292D01*
X141842Y741834D01*
X141967Y742125D01*
X142175Y742417D01*
X142467Y742625D01*
X142758Y742667D01*
X143050Y742584D01*
X143258Y742375D01*
G01X144858Y741209D02*
X145150Y741500D01*
X145400Y741667D01*
X145733Y741750D01*
X146025Y741667D01*
X146233Y741500D01*
X146400Y741250D01*
X146442Y740959D01*
X146400Y740709D01*
X146233Y740459D01*
X145983Y740250D01*
X145692Y740167D01*
X145358Y740250D01*
X145067Y740500D01*
X144900Y740875D01*
X144858Y741292D01*
X144942Y741834D01*
X145067Y742125D01*
X145275Y742417D01*
X145567Y742625D01*
X145858Y742667D01*
X146150Y742584D01*
X146358Y742375D01*
G01X142600Y730300D02*
Y734300D01*
X135200D01*
G01X135517Y717167D02*
Y719667D01*
X136558D01*
X136892Y719542D01*
X137100Y719375D01*
X137183Y719042D01*
X137100Y718709D01*
X136850Y718500D01*
X136558Y718375D01*
X135517D01*
G01X136558D02*
X137183Y717167D01*
G01X138742Y717459D02*
X139033Y717250D01*
X139367Y717167D01*
X139700Y717250D01*
X139992Y717500D01*
X140200Y717875D01*
X140283Y718250D01*
Y718709D01*
X140200Y719084D01*
X139992Y719417D01*
X139742Y719584D01*
X139450Y719667D01*
X139117Y719584D01*
X138867Y719417D01*
X138700Y719167D01*
X138617Y718834D01*
X138700Y718542D01*
X138908Y718250D01*
X139158Y718084D01*
X139450Y718042D01*
X139783Y718125D01*
X140033Y718334D01*
X140283Y718709D01*
G01X141758Y718209D02*
X142050Y718500D01*
X142300Y718667D01*
X142633Y718750D01*
X142925Y718667D01*
X143133Y718500D01*
X143300Y718250D01*
X143342Y717959D01*
X143300Y717709D01*
X143133Y717459D01*
X142883Y717250D01*
X142592Y717167D01*
X142258Y717250D01*
X141967Y717500D01*
X141800Y717875D01*
X141758Y718292D01*
X141842Y718834D01*
X141967Y719125D01*
X142175Y719417D01*
X142467Y719625D01*
X142758Y719667D01*
X143050Y719584D01*
X143258Y719375D01*
G01X146150Y717167D02*
Y719667D01*
X144608Y717875D01*
X146692D01*
G01X135200Y729800D02*
Y725800D01*
X142600D01*
G01X154834Y716017D02*
X152334D01*
Y717058D01*
X152459Y717392D01*
X152626Y717600D01*
X152959Y717683D01*
X153292Y717600D01*
X153501Y717350D01*
X153626Y717058D01*
Y716017D01*
G01Y717058D02*
X154834Y717683D01*
G01Y719950D02*
X154792Y720242D01*
X154667Y720575D01*
X154459Y720783D01*
X154167Y720867D01*
X153876Y720783D01*
X153626Y720533D01*
X153501Y720158D01*
Y719742D01*
X153417Y719492D01*
X153209Y719283D01*
X152917Y719200D01*
X152626Y719325D01*
X152417Y719617D01*
X152334Y719950D01*
X152417Y720283D01*
X152626Y720575D01*
X152917Y720700D01*
X153209Y720617D01*
X153417Y720408D01*
X153501Y720158D01*
Y719742D01*
X153626Y719367D01*
X153876Y719117D01*
X154167Y719033D01*
X154459Y719117D01*
X154667Y719325D01*
X154792Y719658D01*
X154834Y719950D01*
G01Y722967D02*
X154292Y723050D01*
X153834Y723175D01*
X153417Y723342D01*
X152959Y723550D01*
X152334Y723883D01*
Y722217D01*
G01X154834Y726650D02*
X152334D01*
X154126Y725108D01*
Y727192D01*
G01X151700Y738700D02*
X155700D01*
Y746100D01*
G01X134483Y767167D02*
Y769667D01*
X135317D01*
X135650Y769542D01*
X135900Y769375D01*
X136108Y769125D01*
X136275Y768834D01*
X136317Y768417D01*
X136275Y768000D01*
X136108Y767709D01*
X135900Y767459D01*
X135650Y767292D01*
X135317Y767167D01*
X134483D01*
G01X137583Y767667D02*
X137833Y767375D01*
X138167Y767209D01*
X138542Y767167D01*
X138875Y767209D01*
X139208Y767417D01*
X139417Y767667D01*
X139458Y767917D01*
X139375Y768209D01*
X139083Y768417D01*
X138792Y768500D01*
X138417D01*
G01X138792D02*
X139042Y768625D01*
X139250Y768834D01*
X139333Y769084D01*
X139250Y769334D01*
X139042Y769542D01*
X138667Y769667D01*
X138292Y769625D01*
X137917Y769459D01*
G01X140808Y768209D02*
X141100Y768500D01*
X141350Y768667D01*
X141683Y768750D01*
X141975Y768667D01*
X142183Y768500D01*
X142350Y768250D01*
X142392Y767959D01*
X142350Y767709D01*
X142183Y767459D01*
X141933Y767250D01*
X141642Y767167D01*
X141308Y767250D01*
X141017Y767500D01*
X140850Y767875D01*
X140808Y768292D01*
X140892Y768834D01*
X141017Y769125D01*
X141225Y769417D01*
X141517Y769625D01*
X141808Y769667D01*
X142100Y769584D01*
X142308Y769375D01*
G01X132500Y772000D02*
Y765000D01*
G01X135217Y761959D02*
X134967Y762084D01*
X134675Y762167D01*
X134342D01*
X133967Y762042D01*
X133675Y761834D01*
X133467Y761584D01*
X133300Y761167D01*
X133258Y760792D01*
X133342Y760417D01*
X133467Y760167D01*
X133717Y759917D01*
X134008Y759750D01*
X134300Y759667D01*
X134592D01*
X134883Y759750D01*
X135133Y759875D01*
X135342Y760042D01*
G01X137317Y759667D02*
X137400Y760209D01*
X137525Y760667D01*
X137692Y761084D01*
X137900Y761542D01*
X138233Y762167D01*
X136567D01*
G01X139708Y761750D02*
X139958Y762000D01*
X140250Y762125D01*
X140583Y762167D01*
X141000Y762084D01*
X141292Y761875D01*
X141375Y761625D01*
X141333Y761375D01*
X141167Y761167D01*
X140333Y760750D01*
X139958Y760459D01*
X139708Y760042D01*
X139625Y759667D01*
X141375D01*
G01X143517D02*
X143600Y760209D01*
X143725Y760667D01*
X143892Y761084D01*
X144100Y761542D01*
X144433Y762167D01*
X142767D01*
G01X145992Y759959D02*
X146283Y759750D01*
X146617Y759667D01*
X146950Y759750D01*
X147242Y760000D01*
X147450Y760375D01*
X147533Y760750D01*
Y761209D01*
X147450Y761584D01*
X147242Y761917D01*
X146992Y762084D01*
X146700Y762167D01*
X146367Y762084D01*
X146117Y761917D01*
X145950Y761667D01*
X145867Y761334D01*
X145950Y761042D01*
X146158Y760750D01*
X146408Y760584D01*
X146700Y760542D01*
X147033Y760625D01*
X147283Y760834D01*
X147533Y761209D01*
G01X133467Y755667D02*
Y758167D01*
X134508D01*
X134842Y758042D01*
X135050Y757875D01*
X135133Y757542D01*
X135050Y757209D01*
X134800Y757000D01*
X134508Y756875D01*
X133467D01*
G01X134508D02*
X135133Y755667D01*
G01X136608Y757750D02*
X136858Y758000D01*
X137150Y758125D01*
X137483Y758167D01*
X137900Y758084D01*
X138192Y757875D01*
X138275Y757625D01*
X138233Y757375D01*
X138067Y757167D01*
X137233Y756750D01*
X136858Y756459D01*
X136608Y756042D01*
X136525Y755667D01*
X138275D01*
G01X140500D02*
Y758167D01*
X140000Y757667D01*
G01Y755667D02*
X141000D01*
G01X143600D02*
Y758167D01*
X143100Y757667D01*
G01Y755667D02*
X144100D01*
G01X146700D02*
X146992Y755709D01*
X147325Y755834D01*
X147533Y756042D01*
X147617Y756334D01*
X147533Y756625D01*
X147283Y756875D01*
X146908Y757000D01*
X146492D01*
X146242Y757084D01*
X146033Y757292D01*
X145950Y757584D01*
X146075Y757875D01*
X146367Y758084D01*
X146700Y758167D01*
X147033Y758084D01*
X147325Y757875D01*
X147450Y757584D01*
X147367Y757292D01*
X147158Y757084D01*
X146908Y757000D01*
X146492D01*
X146117Y756875D01*
X145867Y756625D01*
X145783Y756334D01*
X145867Y756042D01*
X146075Y755834D01*
X146408Y755709D01*
X146700Y755667D01*
G01X153000Y769017D02*
X150500D01*
Y770058D01*
X150625Y770392D01*
X150792Y770600D01*
X151125Y770683D01*
X151458Y770600D01*
X151667Y770350D01*
X151792Y770058D01*
Y769017D01*
G01Y770058D02*
X153000Y770683D01*
G01Y772950D02*
X152958Y773242D01*
X152833Y773575D01*
X152625Y773783D01*
X152333Y773867D01*
X152042Y773783D01*
X151792Y773533D01*
X151667Y773158D01*
Y772742D01*
X151583Y772492D01*
X151375Y772283D01*
X151083Y772200D01*
X150792Y772325D01*
X150583Y772617D01*
X150500Y772950D01*
X150583Y773283D01*
X150792Y773575D01*
X151083Y773700D01*
X151375Y773617D01*
X151583Y773408D01*
X151667Y773158D01*
Y772742D01*
X151792Y772367D01*
X152042Y772117D01*
X152333Y772033D01*
X152625Y772117D01*
X152833Y772325D01*
X152958Y772658D01*
X153000Y772950D01*
G01Y776050D02*
X152958Y776342D01*
X152833Y776675D01*
X152625Y776883D01*
X152333Y776967D01*
X152042Y776883D01*
X151792Y776633D01*
X151667Y776258D01*
Y775842D01*
X151583Y775592D01*
X151375Y775383D01*
X151083Y775300D01*
X150792Y775425D01*
X150583Y775717D01*
X150500Y776050D01*
X150583Y776383D01*
X150792Y776675D01*
X151083Y776800D01*
X151375Y776717D01*
X151583Y776508D01*
X151667Y776258D01*
Y775842D01*
X151792Y775467D01*
X152042Y775217D01*
X152333Y775133D01*
X152625Y775217D01*
X152833Y775425D01*
X152958Y775758D01*
X153000Y776050D01*
G01Y779650D02*
X150500D01*
X152292Y778108D01*
Y780192D01*
G01X162500Y772800D02*
X166500D01*
Y780200D01*
G01X149500Y769017D02*
X147000D01*
Y770058D01*
X147125Y770392D01*
X147292Y770600D01*
X147625Y770683D01*
X147958Y770600D01*
X148167Y770350D01*
X148292Y770058D01*
Y769017D01*
G01Y770058D02*
X149500Y770683D01*
G01Y772950D02*
X149458Y773242D01*
X149333Y773575D01*
X149125Y773783D01*
X148833Y773867D01*
X148542Y773783D01*
X148292Y773533D01*
X148167Y773158D01*
Y772742D01*
X148083Y772492D01*
X147875Y772283D01*
X147583Y772200D01*
X147292Y772325D01*
X147083Y772617D01*
X147000Y772950D01*
X147083Y773283D01*
X147292Y773575D01*
X147583Y773700D01*
X147875Y773617D01*
X148083Y773408D01*
X148167Y773158D01*
Y772742D01*
X148292Y772367D01*
X148542Y772117D01*
X148833Y772033D01*
X149125Y772117D01*
X149333Y772325D01*
X149458Y772658D01*
X149500Y772950D01*
G01Y775967D02*
X148958Y776050D01*
X148500Y776175D01*
X148083Y776342D01*
X147625Y776550D01*
X147000Y776883D01*
Y775217D01*
G01X149208Y778442D02*
X149417Y778733D01*
X149500Y779067D01*
X149417Y779400D01*
X149167Y779692D01*
X148792Y779900D01*
X148417Y779983D01*
X147958D01*
X147583Y779900D01*
X147250Y779692D01*
X147083Y779442D01*
X147000Y779150D01*
X147083Y778817D01*
X147250Y778567D01*
X147500Y778400D01*
X147833Y778317D01*
X148125Y778400D01*
X148417Y778608D01*
X148583Y778858D01*
X148625Y779150D01*
X148542Y779483D01*
X148333Y779733D01*
X147958Y779983D01*
G01X162000Y780200D02*
X158000D01*
Y772800D01*
G01X139017Y751200D02*
Y753700D01*
X140058D01*
X140392Y753575D01*
X140600Y753408D01*
X140683Y753075D01*
X140600Y752742D01*
X140350Y752533D01*
X140058Y752408D01*
X139017D01*
G01X140058D02*
X140683Y751200D01*
G01X142950D02*
X143242Y751242D01*
X143575Y751367D01*
X143783Y751575D01*
X143867Y751867D01*
X143783Y752158D01*
X143533Y752408D01*
X143158Y752533D01*
X142742D01*
X142492Y752617D01*
X142283Y752825D01*
X142200Y753117D01*
X142325Y753408D01*
X142617Y753617D01*
X142950Y753700D01*
X143283Y753617D01*
X143575Y753408D01*
X143700Y753117D01*
X143617Y752825D01*
X143408Y752617D01*
X143158Y752533D01*
X142742D01*
X142367Y752408D01*
X142117Y752158D01*
X142033Y751867D01*
X142117Y751575D01*
X142325Y751367D01*
X142658Y751242D01*
X142950Y751200D01*
G01X145967D02*
X146050Y751742D01*
X146175Y752200D01*
X146342Y752617D01*
X146550Y753075D01*
X146883Y753700D01*
X145217D01*
G01X149150Y751200D02*
Y753700D01*
X148650Y753200D01*
G01Y751200D02*
X149650D01*
G01X162000Y755400D02*
Y751400D01*
X169400D01*
G01X161200Y756917D02*
X158700D01*
Y757958D01*
X158825Y758292D01*
X158992Y758500D01*
X159325Y758583D01*
X159658Y758500D01*
X159867Y758250D01*
X159992Y757958D01*
Y756917D01*
G01Y757958D02*
X161200Y758583D01*
G01Y760850D02*
X161158Y761142D01*
X161033Y761475D01*
X160825Y761683D01*
X160533Y761767D01*
X160242Y761683D01*
X159992Y761433D01*
X159867Y761058D01*
Y760642D01*
X159783Y760392D01*
X159575Y760183D01*
X159283Y760100D01*
X158992Y760225D01*
X158783Y760517D01*
X158700Y760850D01*
X158783Y761183D01*
X158992Y761475D01*
X159283Y761600D01*
X159575Y761517D01*
X159783Y761308D01*
X159867Y761058D01*
Y760642D01*
X159992Y760267D01*
X160242Y760017D01*
X160533Y759933D01*
X160825Y760017D01*
X161033Y760225D01*
X161158Y760558D01*
X161200Y760850D01*
G01X160158Y763158D02*
X159867Y763450D01*
X159700Y763700D01*
X159617Y764033D01*
X159700Y764325D01*
X159867Y764533D01*
X160117Y764700D01*
X160408Y764742D01*
X160658Y764700D01*
X160908Y764533D01*
X161117Y764283D01*
X161200Y763992D01*
X161117Y763658D01*
X160867Y763367D01*
X160492Y763200D01*
X160075Y763158D01*
X159533Y763242D01*
X159242Y763367D01*
X158950Y763575D01*
X158742Y763867D01*
X158700Y764158D01*
X158783Y764450D01*
X158992Y764658D01*
G01X161200Y767050D02*
X161158Y767342D01*
X161033Y767675D01*
X160825Y767883D01*
X160533Y767967D01*
X160242Y767883D01*
X159992Y767633D01*
X159867Y767258D01*
Y766842D01*
X159783Y766592D01*
X159575Y766383D01*
X159283Y766300D01*
X158992Y766425D01*
X158783Y766717D01*
X158700Y767050D01*
X158783Y767383D01*
X158992Y767675D01*
X159283Y767800D01*
X159575Y767717D01*
X159783Y767508D01*
X159867Y767258D01*
Y766842D01*
X159992Y766467D01*
X160242Y766217D01*
X160533Y766133D01*
X160825Y766217D01*
X161033Y766425D01*
X161158Y766758D01*
X161200Y767050D01*
G01X157700Y756917D02*
X155200D01*
Y757958D01*
X155325Y758292D01*
X155492Y758500D01*
X155825Y758583D01*
X156158Y758500D01*
X156367Y758250D01*
X156492Y757958D01*
Y756917D01*
G01Y757958D02*
X157700Y758583D01*
G01Y760850D02*
X157658Y761142D01*
X157533Y761475D01*
X157325Y761683D01*
X157033Y761767D01*
X156742Y761683D01*
X156492Y761433D01*
X156367Y761058D01*
Y760642D01*
X156283Y760392D01*
X156075Y760183D01*
X155783Y760100D01*
X155492Y760225D01*
X155283Y760517D01*
X155200Y760850D01*
X155283Y761183D01*
X155492Y761475D01*
X155783Y761600D01*
X156075Y761517D01*
X156283Y761308D01*
X156367Y761058D01*
Y760642D01*
X156492Y760267D01*
X156742Y760017D01*
X157033Y759933D01*
X157325Y760017D01*
X157533Y760225D01*
X157658Y760558D01*
X157700Y760850D01*
G01X156658Y763158D02*
X156367Y763450D01*
X156200Y763700D01*
X156117Y764033D01*
X156200Y764325D01*
X156367Y764533D01*
X156617Y764700D01*
X156908Y764742D01*
X157158Y764700D01*
X157408Y764533D01*
X157617Y764283D01*
X157700Y763992D01*
X157617Y763658D01*
X157367Y763367D01*
X156992Y763200D01*
X156575Y763158D01*
X156033Y763242D01*
X155742Y763367D01*
X155450Y763575D01*
X155242Y763867D01*
X155200Y764158D01*
X155283Y764450D01*
X155492Y764658D01*
G01X156658Y766258D02*
X156367Y766550D01*
X156200Y766800D01*
X156117Y767133D01*
X156200Y767425D01*
X156367Y767633D01*
X156617Y767800D01*
X156908Y767842D01*
X157158Y767800D01*
X157408Y767633D01*
X157617Y767383D01*
X157700Y767092D01*
X157617Y766758D01*
X157367Y766467D01*
X156992Y766300D01*
X156575Y766258D01*
X156033Y766342D01*
X155742Y766467D01*
X155450Y766675D01*
X155242Y766967D01*
X155200Y767258D01*
X155283Y767550D01*
X155492Y767758D01*
G01X158000Y797800D02*
X166000D01*
G01X158000Y785900D02*
Y797800D01*
G01X166000Y785900D02*
X158000D01*
G01X162000Y787500D02*
X160400Y785900D01*
G01X162000Y787500D02*
X163600Y785900D01*
G01X166500Y818200D02*
X162500D01*
Y810800D01*
G01X158000D02*
X162000D01*
Y818200D01*
G01X169700Y806500D02*
Y810500D01*
X162300D01*
G01X148000Y803017D02*
X145500D01*
Y804058D01*
X145625Y804392D01*
X145792Y804600D01*
X146125Y804683D01*
X146458Y804600D01*
X146667Y804350D01*
X146792Y804058D01*
Y803017D01*
G01Y804058D02*
X148000Y804683D01*
G01Y806950D02*
X147958Y807242D01*
X147833Y807575D01*
X147625Y807783D01*
X147333Y807867D01*
X147042Y807783D01*
X146792Y807533D01*
X146667Y807158D01*
Y806742D01*
X146583Y806492D01*
X146375Y806283D01*
X146083Y806200D01*
X145792Y806325D01*
X145583Y806617D01*
X145500Y806950D01*
X145583Y807283D01*
X145792Y807575D01*
X146083Y807700D01*
X146375Y807617D01*
X146583Y807408D01*
X146667Y807158D01*
Y806742D01*
X146792Y806367D01*
X147042Y806117D01*
X147333Y806033D01*
X147625Y806117D01*
X147833Y806325D01*
X147958Y806658D01*
X148000Y806950D01*
G01Y809967D02*
X147458Y810050D01*
X147000Y810175D01*
X146583Y810342D01*
X146125Y810550D01*
X145500Y810883D01*
Y809217D01*
G01X148000Y813067D02*
X147458Y813150D01*
X147000Y813275D01*
X146583Y813442D01*
X146125Y813650D01*
X145500Y813983D01*
Y812317D01*
G01X144500Y793800D02*
X148500D01*
Y801200D01*
G01X154800Y810500D02*
Y806500D01*
X162200D01*
G01X136653Y794479D02*
X136528Y794229D01*
X136445Y793937D01*
Y793604D01*
X136570Y793229D01*
X136778Y792937D01*
X137028Y792729D01*
X137445Y792562D01*
X137820Y792520D01*
X138195Y792604D01*
X138445Y792729D01*
X138695Y792979D01*
X138862Y793270D01*
X138945Y793562D01*
Y793854D01*
X138862Y794145D01*
X138737Y794395D01*
X138570Y794604D01*
G01X137903Y795870D02*
X137612Y796162D01*
X137445Y796412D01*
X137362Y796745D01*
X137445Y797037D01*
X137612Y797245D01*
X137862Y797412D01*
X138153Y797454D01*
X138403Y797412D01*
X138653Y797245D01*
X138862Y796995D01*
X138945Y796704D01*
X138862Y796370D01*
X138612Y796079D01*
X138237Y795912D01*
X137820Y795870D01*
X137278Y795954D01*
X136987Y796079D01*
X136695Y796287D01*
X136487Y796579D01*
X136445Y796870D01*
X136528Y797162D01*
X136737Y797370D01*
G01X138653Y799054D02*
X138862Y799345D01*
X138945Y799679D01*
X138862Y800012D01*
X138612Y800304D01*
X138237Y800512D01*
X137862Y800595D01*
X137403D01*
X137028Y800512D01*
X136695Y800304D01*
X136528Y800054D01*
X136445Y799762D01*
X136528Y799429D01*
X136695Y799179D01*
X136945Y799012D01*
X137278Y798929D01*
X137570Y799012D01*
X137862Y799220D01*
X138028Y799470D01*
X138070Y799762D01*
X137987Y800095D01*
X137778Y800345D01*
X137403Y800595D01*
G01X138570Y801945D02*
X138778Y802195D01*
X138903Y802487D01*
X138945Y802862D01*
X138862Y803237D01*
X138695Y803529D01*
X138403Y803737D01*
X138070Y803779D01*
X137737Y803695D01*
X137528Y803487D01*
X137362Y803195D01*
X137320Y802904D01*
X137362Y802612D01*
X137528Y802237D01*
X136445Y802362D01*
Y803487D01*
G01X132453Y794579D02*
X132328Y794329D01*
X132245Y794037D01*
Y793704D01*
X132370Y793329D01*
X132578Y793037D01*
X132828Y792829D01*
X133245Y792662D01*
X133620Y792620D01*
X133995Y792704D01*
X134245Y792829D01*
X134495Y793079D01*
X134662Y793370D01*
X134745Y793662D01*
Y793954D01*
X134662Y794245D01*
X134537Y794495D01*
X134370Y794704D01*
G01X133703Y795970D02*
X133412Y796262D01*
X133245Y796512D01*
X133162Y796845D01*
X133245Y797137D01*
X133412Y797345D01*
X133662Y797512D01*
X133953Y797554D01*
X134203Y797512D01*
X134453Y797345D01*
X134662Y797095D01*
X134745Y796804D01*
X134662Y796470D01*
X134412Y796179D01*
X134037Y796012D01*
X133620Y795970D01*
X133078Y796054D01*
X132787Y796179D01*
X132495Y796387D01*
X132287Y796679D01*
X132245Y796970D01*
X132328Y797262D01*
X132537Y797470D01*
G01X134453Y799154D02*
X134662Y799445D01*
X134745Y799779D01*
X134662Y800112D01*
X134412Y800404D01*
X134037Y800612D01*
X133662Y800695D01*
X133203D01*
X132828Y800612D01*
X132495Y800404D01*
X132328Y800154D01*
X132245Y799862D01*
X132328Y799529D01*
X132495Y799279D01*
X132745Y799112D01*
X133078Y799029D01*
X133370Y799112D01*
X133662Y799320D01*
X133828Y799570D01*
X133870Y799862D01*
X133787Y800195D01*
X133578Y800445D01*
X133203Y800695D01*
G01X134745Y803462D02*
X132245D01*
X134037Y801920D01*
Y804004D01*
G01X158983Y826000D02*
Y824208D01*
X159150Y823833D01*
X159483Y823583D01*
X159900Y823500D01*
X160317Y823583D01*
X160650Y823833D01*
X160817Y824208D01*
Y826000D01*
G01X162083Y824000D02*
X162333Y823708D01*
X162667Y823542D01*
X163042Y823500D01*
X163375Y823542D01*
X163708Y823750D01*
X163917Y824000D01*
X163958Y824250D01*
X163875Y824542D01*
X163583Y824750D01*
X163292Y824833D01*
X162917D01*
G01X163292D02*
X163542Y824958D01*
X163750Y825167D01*
X163833Y825417D01*
X163750Y825667D01*
X163542Y825875D01*
X163167Y826000D01*
X162792Y825958D01*
X162417Y825792D01*
G01X166100Y826000D02*
X165767Y825917D01*
X165517Y825708D01*
X165350Y825458D01*
X165225Y825125D01*
X165183Y824750D01*
X165225Y824375D01*
X165350Y824042D01*
X165517Y823792D01*
X165767Y823583D01*
X166100Y823500D01*
X166433Y823583D01*
X166683Y823792D01*
X166850Y824042D01*
X166975Y824375D01*
X167017Y824750D01*
X166975Y825125D01*
X166850Y825458D01*
X166683Y825708D01*
X166433Y825917D01*
X166100Y826000D01*
G01X165767Y829792D02*
X165517Y829917D01*
X165225Y830000D01*
X164892D01*
X164517Y829875D01*
X164225Y829667D01*
X164017Y829417D01*
X163850Y829000D01*
X163808Y828625D01*
X163892Y828250D01*
X164017Y828000D01*
X164267Y827750D01*
X164558Y827583D01*
X164850Y827500D01*
X165142D01*
X165433Y827583D01*
X165683Y827708D01*
X165892Y827875D01*
G01X167158Y828542D02*
X167450Y828833D01*
X167700Y829000D01*
X168033Y829083D01*
X168325Y829000D01*
X168533Y828833D01*
X168700Y828583D01*
X168742Y828292D01*
X168700Y828042D01*
X168533Y827792D01*
X168283Y827583D01*
X167992Y827500D01*
X167658Y827583D01*
X167367Y827833D01*
X167200Y828208D01*
X167158Y828625D01*
X167242Y829167D01*
X167367Y829458D01*
X167575Y829750D01*
X167867Y829958D01*
X168158Y830000D01*
X168450Y829917D01*
X168658Y829708D01*
G01X170342Y827792D02*
X170633Y827583D01*
X170967Y827500D01*
X171300Y827583D01*
X171592Y827833D01*
X171800Y828208D01*
X171883Y828583D01*
Y829042D01*
X171800Y829417D01*
X171592Y829750D01*
X171342Y829917D01*
X171050Y830000D01*
X170717Y829917D01*
X170467Y829750D01*
X170300Y829500D01*
X170217Y829167D01*
X170300Y828875D01*
X170508Y828583D01*
X170758Y828417D01*
X171050Y828375D01*
X171383Y828458D01*
X171633Y828667D01*
X171883Y829042D01*
G01X173442Y827792D02*
X173733Y827583D01*
X174067Y827500D01*
X174400Y827583D01*
X174692Y827833D01*
X174900Y828208D01*
X174983Y828583D01*
Y829042D01*
X174900Y829417D01*
X174692Y829750D01*
X174442Y829917D01*
X174150Y830000D01*
X173817Y829917D01*
X173567Y829750D01*
X173400Y829500D01*
X173317Y829167D01*
X173400Y828875D01*
X173608Y828583D01*
X173858Y828417D01*
X174150Y828375D01*
X174483Y828458D01*
X174733Y828667D01*
X174983Y829042D01*
G01X150167Y821792D02*
X149917Y821917D01*
X149625Y822000D01*
X149292D01*
X148917Y821875D01*
X148625Y821667D01*
X148417Y821417D01*
X148250Y821000D01*
X148208Y820625D01*
X148292Y820250D01*
X148417Y820000D01*
X148667Y819750D01*
X148958Y819583D01*
X149250Y819500D01*
X149542D01*
X149833Y819583D01*
X150083Y819708D01*
X150292Y819875D01*
G01X151558Y820542D02*
X151850Y820833D01*
X152100Y821000D01*
X152433Y821083D01*
X152725Y821000D01*
X152933Y820833D01*
X153100Y820583D01*
X153142Y820292D01*
X153100Y820042D01*
X152933Y819792D01*
X152683Y819583D01*
X152392Y819500D01*
X152058Y819583D01*
X151767Y819833D01*
X151600Y820208D01*
X151558Y820625D01*
X151642Y821167D01*
X151767Y821458D01*
X151975Y821750D01*
X152267Y821958D01*
X152558Y822000D01*
X152850Y821917D01*
X153058Y821708D01*
G01X154742Y819792D02*
X155033Y819583D01*
X155367Y819500D01*
X155700Y819583D01*
X155992Y819833D01*
X156200Y820208D01*
X156283Y820583D01*
Y821042D01*
X156200Y821417D01*
X155992Y821750D01*
X155742Y821917D01*
X155450Y822000D01*
X155117Y821917D01*
X154867Y821750D01*
X154700Y821500D01*
X154617Y821167D01*
X154700Y820875D01*
X154908Y820583D01*
X155158Y820417D01*
X155450Y820375D01*
X155783Y820458D01*
X156033Y820667D01*
X156283Y821042D01*
G01X158467Y819500D02*
X158550Y820042D01*
X158675Y820500D01*
X158842Y820917D01*
X159050Y821375D01*
X159383Y822000D01*
X157717D01*
G01X152767Y829792D02*
X152517Y829917D01*
X152225Y830000D01*
X151892D01*
X151517Y829875D01*
X151225Y829667D01*
X151017Y829417D01*
X150850Y829000D01*
X150808Y828625D01*
X150892Y828250D01*
X151017Y828000D01*
X151267Y827750D01*
X151558Y827583D01*
X151850Y827500D01*
X152142D01*
X152433Y827583D01*
X152683Y827708D01*
X152892Y827875D01*
G01X154158Y828542D02*
X154450Y828833D01*
X154700Y829000D01*
X155033Y829083D01*
X155325Y829000D01*
X155533Y828833D01*
X155700Y828583D01*
X155742Y828292D01*
X155700Y828042D01*
X155533Y827792D01*
X155283Y827583D01*
X154992Y827500D01*
X154658Y827583D01*
X154367Y827833D01*
X154200Y828208D01*
X154158Y828625D01*
X154242Y829167D01*
X154367Y829458D01*
X154575Y829750D01*
X154867Y829958D01*
X155158Y830000D01*
X155450Y829917D01*
X155658Y829708D01*
G01X157342Y827792D02*
X157633Y827583D01*
X157967Y827500D01*
X158300Y827583D01*
X158592Y827833D01*
X158800Y828208D01*
X158883Y828583D01*
Y829042D01*
X158800Y829417D01*
X158592Y829750D01*
X158342Y829917D01*
X158050Y830000D01*
X157717Y829917D01*
X157467Y829750D01*
X157300Y829500D01*
X157217Y829167D01*
X157300Y828875D01*
X157508Y828583D01*
X157758Y828417D01*
X158050Y828375D01*
X158383Y828458D01*
X158633Y828667D01*
X158883Y829042D01*
G01X160358Y828542D02*
X160650Y828833D01*
X160900Y829000D01*
X161233Y829083D01*
X161525Y829000D01*
X161733Y828833D01*
X161900Y828583D01*
X161942Y828292D01*
X161900Y828042D01*
X161733Y827792D01*
X161483Y827583D01*
X161192Y827500D01*
X160858Y827583D01*
X160567Y827833D01*
X160400Y828208D01*
X160358Y828625D01*
X160442Y829167D01*
X160567Y829458D01*
X160775Y829750D01*
X161067Y829958D01*
X161358Y830000D01*
X161650Y829917D01*
X161858Y829708D01*
G01X166500Y835017D02*
X164000D01*
Y836058D01*
X164125Y836392D01*
X164292Y836600D01*
X164625Y836683D01*
X164958Y836600D01*
X165167Y836350D01*
X165292Y836058D01*
Y835017D01*
G01Y836058D02*
X166500Y836683D01*
G01Y838950D02*
X166458Y839242D01*
X166333Y839575D01*
X166125Y839783D01*
X165833Y839867D01*
X165542Y839783D01*
X165292Y839533D01*
X165167Y839158D01*
Y838742D01*
X165083Y838492D01*
X164875Y838283D01*
X164583Y838200D01*
X164292Y838325D01*
X164083Y838617D01*
X164000Y838950D01*
X164083Y839283D01*
X164292Y839575D01*
X164583Y839700D01*
X164875Y839617D01*
X165083Y839408D01*
X165167Y839158D01*
Y838742D01*
X165292Y838367D01*
X165542Y838117D01*
X165833Y838033D01*
X166125Y838117D01*
X166333Y838325D01*
X166458Y838658D01*
X166500Y838950D01*
G01Y842050D02*
X166458Y842342D01*
X166333Y842675D01*
X166125Y842883D01*
X165833Y842967D01*
X165542Y842883D01*
X165292Y842633D01*
X165167Y842258D01*
Y841842D01*
X165083Y841592D01*
X164875Y841383D01*
X164583Y841300D01*
X164292Y841425D01*
X164083Y841717D01*
X164000Y842050D01*
X164083Y842383D01*
X164292Y842675D01*
X164583Y842800D01*
X164875Y842717D01*
X165083Y842508D01*
X165167Y842258D01*
Y841842D01*
X165292Y841467D01*
X165542Y841217D01*
X165833Y841133D01*
X166125Y841217D01*
X166333Y841425D01*
X166458Y841758D01*
X166500Y842050D01*
G01X166000Y844233D02*
X166292Y844483D01*
X166458Y844817D01*
X166500Y845192D01*
X166458Y845525D01*
X166250Y845858D01*
X166000Y846067D01*
X165750Y846108D01*
X165458Y846025D01*
X165250Y845733D01*
X165167Y845442D01*
Y845067D01*
G01Y845442D02*
X165042Y845692D01*
X164833Y845900D01*
X164583Y845983D01*
X164333Y845900D01*
X164125Y845692D01*
X164000Y845317D01*
X164042Y844942D01*
X164208Y844567D01*
G01X162500Y835017D02*
X160000D01*
Y836058D01*
X160125Y836392D01*
X160292Y836600D01*
X160625Y836683D01*
X160958Y836600D01*
X161167Y836350D01*
X161292Y836058D01*
Y835017D01*
G01Y836058D02*
X162500Y836683D01*
G01Y838950D02*
X162458Y839242D01*
X162333Y839575D01*
X162125Y839783D01*
X161833Y839867D01*
X161542Y839783D01*
X161292Y839533D01*
X161167Y839158D01*
Y838742D01*
X161083Y838492D01*
X160875Y838283D01*
X160583Y838200D01*
X160292Y838325D01*
X160083Y838617D01*
X160000Y838950D01*
X160083Y839283D01*
X160292Y839575D01*
X160583Y839700D01*
X160875Y839617D01*
X161083Y839408D01*
X161167Y839158D01*
Y838742D01*
X161292Y838367D01*
X161542Y838117D01*
X161833Y838033D01*
X162125Y838117D01*
X162333Y838325D01*
X162458Y838658D01*
X162500Y838950D01*
G01Y842050D02*
X162458Y842342D01*
X162333Y842675D01*
X162125Y842883D01*
X161833Y842967D01*
X161542Y842883D01*
X161292Y842633D01*
X161167Y842258D01*
Y841842D01*
X161083Y841592D01*
X160875Y841383D01*
X160583Y841300D01*
X160292Y841425D01*
X160083Y841717D01*
X160000Y842050D01*
X160083Y842383D01*
X160292Y842675D01*
X160583Y842800D01*
X160875Y842717D01*
X161083Y842508D01*
X161167Y842258D01*
Y841842D01*
X161292Y841467D01*
X161542Y841217D01*
X161833Y841133D01*
X162125Y841217D01*
X162333Y841425D01*
X162458Y841758D01*
X162500Y842050D01*
G01X160000Y845150D02*
X160083Y844817D01*
X160292Y844567D01*
X160542Y844400D01*
X160875Y844275D01*
X161250Y844233D01*
X161625Y844275D01*
X161958Y844400D01*
X162208Y844567D01*
X162417Y844817D01*
X162500Y845150D01*
X162417Y845483D01*
X162208Y845733D01*
X161958Y845900D01*
X161625Y846025D01*
X161250Y846067D01*
X160875Y846025D01*
X160542Y845900D01*
X160292Y845733D01*
X160083Y845483D01*
X160000Y845150D01*
G01X164017Y831500D02*
Y834000D01*
X165058D01*
X165392Y833875D01*
X165600Y833708D01*
X165683Y833375D01*
X165600Y833042D01*
X165350Y832833D01*
X165058Y832708D01*
X164017D01*
G01X165058D02*
X165683Y831500D01*
G01X167950D02*
X168242Y831542D01*
X168575Y831667D01*
X168783Y831875D01*
X168867Y832167D01*
X168783Y832458D01*
X168533Y832708D01*
X168158Y832833D01*
X167742D01*
X167492Y832917D01*
X167283Y833125D01*
X167200Y833417D01*
X167325Y833708D01*
X167617Y833917D01*
X167950Y834000D01*
X168283Y833917D01*
X168575Y833708D01*
X168700Y833417D01*
X168617Y833125D01*
X168408Y832917D01*
X168158Y832833D01*
X167742D01*
X167367Y832708D01*
X167117Y832458D01*
X167033Y832167D01*
X167117Y831875D01*
X167325Y831667D01*
X167658Y831542D01*
X167950Y831500D01*
G01X170967D02*
X171050Y832042D01*
X171175Y832500D01*
X171342Y832917D01*
X171550Y833375D01*
X171883Y834000D01*
X170217D01*
G01X174150Y831500D02*
X174442Y831542D01*
X174775Y831667D01*
X174983Y831875D01*
X175067Y832167D01*
X174983Y832458D01*
X174733Y832708D01*
X174358Y832833D01*
X173942D01*
X173692Y832917D01*
X173483Y833125D01*
X173400Y833417D01*
X173525Y833708D01*
X173817Y833917D01*
X174150Y834000D01*
X174483Y833917D01*
X174775Y833708D01*
X174900Y833417D01*
X174817Y833125D01*
X174608Y832917D01*
X174358Y832833D01*
X173942D01*
X173567Y832708D01*
X173317Y832458D01*
X173233Y832167D01*
X173317Y831875D01*
X173525Y831667D01*
X173858Y831542D01*
X174150Y831500D01*
G01X151017D02*
Y834000D01*
X152058D01*
X152392Y833875D01*
X152600Y833708D01*
X152683Y833375D01*
X152600Y833042D01*
X152350Y832833D01*
X152058Y832708D01*
X151017D01*
G01X152058D02*
X152683Y831500D01*
G01X154950D02*
X155242Y831542D01*
X155575Y831667D01*
X155783Y831875D01*
X155867Y832167D01*
X155783Y832458D01*
X155533Y832708D01*
X155158Y832833D01*
X154742D01*
X154492Y832917D01*
X154283Y833125D01*
X154200Y833417D01*
X154325Y833708D01*
X154617Y833917D01*
X154950Y834000D01*
X155283Y833917D01*
X155575Y833708D01*
X155700Y833417D01*
X155617Y833125D01*
X155408Y832917D01*
X155158Y832833D01*
X154742D01*
X154367Y832708D01*
X154117Y832458D01*
X154033Y832167D01*
X154117Y831875D01*
X154325Y831667D01*
X154658Y831542D01*
X154950Y831500D01*
G01X157967D02*
X158050Y832042D01*
X158175Y832500D01*
X158342Y832917D01*
X158550Y833375D01*
X158883Y834000D01*
X157217D01*
G01X160358Y832542D02*
X160650Y832833D01*
X160900Y833000D01*
X161233Y833083D01*
X161525Y833000D01*
X161733Y832833D01*
X161900Y832583D01*
X161942Y832292D01*
X161900Y832042D01*
X161733Y831792D01*
X161483Y831583D01*
X161192Y831500D01*
X160858Y831583D01*
X160567Y831833D01*
X160400Y832208D01*
X160358Y832625D01*
X160442Y833167D01*
X160567Y833458D01*
X160775Y833750D01*
X161067Y833958D01*
X161358Y834000D01*
X161650Y833917D01*
X161858Y833708D01*
G01X185855Y111359D02*
X183355D01*
Y112400D01*
X183480Y112734D01*
X183647Y112942D01*
X183980Y113025D01*
X184313Y112942D01*
X184522Y112692D01*
X184647Y112400D01*
Y111359D01*
G01Y112400D02*
X185855Y113025D01*
G01X185480Y114375D02*
X185688Y114625D01*
X185813Y114917D01*
X185855Y115292D01*
X185772Y115667D01*
X185605Y115959D01*
X185313Y116167D01*
X184980Y116209D01*
X184647Y116125D01*
X184438Y115917D01*
X184272Y115625D01*
X184230Y115334D01*
X184272Y115042D01*
X184438Y114667D01*
X183355Y114792D01*
Y115917D01*
G01X185855Y118892D02*
X183355D01*
X185147Y117350D01*
Y119434D01*
G01X185480Y120575D02*
X185688Y120825D01*
X185813Y121117D01*
X185855Y121492D01*
X185772Y121867D01*
X185605Y122159D01*
X185313Y122367D01*
X184980Y122409D01*
X184647Y122325D01*
X184438Y122117D01*
X184272Y121825D01*
X184230Y121534D01*
X184272Y121242D01*
X184438Y120867D01*
X183355Y120992D01*
Y122117D01*
G01X199734Y131200D02*
X199692Y130867D01*
X199526Y130575D01*
X199276Y130325D01*
X198984Y130158D01*
X198651Y130075D01*
X198317D01*
X197984Y130158D01*
X197692Y130325D01*
X197442Y130575D01*
X197276Y130867D01*
X197234Y131200D01*
X197276Y131533D01*
X197442Y131825D01*
X197692Y132075D01*
X197984Y132242D01*
X198317Y132325D01*
X198651D01*
X198984Y132242D01*
X199276Y132075D01*
X199526Y131825D01*
X199692Y131533D01*
X199734Y131200D01*
G01X199067Y131533D02*
X199734Y132033D01*
G01Y134800D02*
X197234D01*
X199026Y133258D01*
Y135342D01*
G01X197651Y136608D02*
X197401Y136858D01*
X197276Y137150D01*
X197234Y137483D01*
X197317Y137900D01*
X197526Y138192D01*
X197776Y138275D01*
X198026Y138233D01*
X198234Y138067D01*
X198651Y137233D01*
X198942Y136858D01*
X199359Y136608D01*
X199734Y136525D01*
Y138275D01*
G01X189517Y143167D02*
Y145667D01*
X190558D01*
X190892Y145542D01*
X191100Y145375D01*
X191183Y145042D01*
X191100Y144709D01*
X190850Y144500D01*
X190558Y144375D01*
X189517D01*
G01X190558D02*
X191183Y143167D01*
G01X192658Y144209D02*
X192950Y144500D01*
X193200Y144667D01*
X193533Y144750D01*
X193825Y144667D01*
X194033Y144500D01*
X194200Y144250D01*
X194242Y143959D01*
X194200Y143709D01*
X194033Y143459D01*
X193783Y143250D01*
X193492Y143167D01*
X193158Y143250D01*
X192867Y143500D01*
X192700Y143875D01*
X192658Y144292D01*
X192742Y144834D01*
X192867Y145125D01*
X193075Y145417D01*
X193367Y145625D01*
X193658Y145667D01*
X193950Y145584D01*
X194158Y145375D01*
G01X195758Y145250D02*
X196008Y145500D01*
X196300Y145625D01*
X196633Y145667D01*
X197050Y145584D01*
X197342Y145375D01*
X197425Y145125D01*
X197383Y144875D01*
X197217Y144667D01*
X196383Y144250D01*
X196008Y143959D01*
X195758Y143542D01*
X195675Y143167D01*
X197425D01*
G01X198942Y143459D02*
X199233Y143250D01*
X199567Y143167D01*
X199900Y143250D01*
X200192Y143500D01*
X200400Y143875D01*
X200483Y144250D01*
Y144709D01*
X200400Y145084D01*
X200192Y145417D01*
X199942Y145584D01*
X199650Y145667D01*
X199317Y145584D01*
X199067Y145417D01*
X198900Y145167D01*
X198817Y144834D01*
X198900Y144542D01*
X199108Y144250D01*
X199358Y144084D01*
X199650Y144042D01*
X199983Y144125D01*
X200233Y144334D01*
X200483Y144709D01*
G01X198694Y172052D02*
Y174552D01*
X199735D01*
X200069Y174427D01*
X200277Y174260D01*
X200360Y173927D01*
X200277Y173594D01*
X200027Y173385D01*
X199735Y173260D01*
X198694D01*
G01X199735D02*
X200360Y172052D01*
G01X201835Y173094D02*
X202127Y173385D01*
X202377Y173552D01*
X202710Y173635D01*
X203002Y173552D01*
X203210Y173385D01*
X203377Y173135D01*
X203419Y172844D01*
X203377Y172594D01*
X203210Y172344D01*
X202960Y172135D01*
X202669Y172052D01*
X202335Y172135D01*
X202044Y172385D01*
X201877Y172760D01*
X201835Y173177D01*
X201919Y173719D01*
X202044Y174010D01*
X202252Y174302D01*
X202544Y174510D01*
X202835Y174552D01*
X203127Y174469D01*
X203335Y174260D01*
G01X205019Y172344D02*
X205310Y172135D01*
X205644Y172052D01*
X205977Y172135D01*
X206269Y172385D01*
X206477Y172760D01*
X206560Y173135D01*
Y173594D01*
X206477Y173969D01*
X206269Y174302D01*
X206019Y174469D01*
X205727Y174552D01*
X205394Y174469D01*
X205144Y174302D01*
X204977Y174052D01*
X204894Y173719D01*
X204977Y173427D01*
X205185Y173135D01*
X205435Y172969D01*
X205727Y172927D01*
X206060Y173010D01*
X206310Y173219D01*
X206560Y173594D01*
G01X208827Y172052D02*
X209119Y172094D01*
X209452Y172219D01*
X209660Y172427D01*
X209744Y172719D01*
X209660Y173010D01*
X209410Y173260D01*
X209035Y173385D01*
X208619D01*
X208369Y173469D01*
X208160Y173677D01*
X208077Y173969D01*
X208202Y174260D01*
X208494Y174469D01*
X208827Y174552D01*
X209160Y174469D01*
X209452Y174260D01*
X209577Y173969D01*
X209494Y173677D01*
X209285Y173469D01*
X209035Y173385D01*
X208619D01*
X208244Y173260D01*
X207994Y173010D01*
X207910Y172719D01*
X207994Y172427D01*
X208202Y172219D01*
X208535Y172094D01*
X208827Y172052D01*
G01X171200Y213500D02*
Y195500D01*
G01X178417Y188400D02*
Y185900D01*
X180083D01*
G01X182350D02*
X182642Y185942D01*
X182975Y186067D01*
X183183Y186275D01*
X183267Y186567D01*
X183183Y186858D01*
X182933Y187108D01*
X182558Y187233D01*
X182142D01*
X181892Y187317D01*
X181683Y187525D01*
X181600Y187817D01*
X181725Y188108D01*
X182017Y188317D01*
X182350Y188400D01*
X182683Y188317D01*
X182975Y188108D01*
X183100Y187817D01*
X183017Y187525D01*
X182808Y187317D01*
X182558Y187233D01*
X182142D01*
X181767Y187108D01*
X181517Y186858D01*
X181433Y186567D01*
X181517Y186275D01*
X181725Y186067D01*
X182058Y185942D01*
X182350Y185900D01*
G01X174484Y184686D02*
Y188686D01*
X167084D01*
G01X174484Y179686D02*
Y183686D01*
X167084D01*
G01X197707Y181205D02*
X195207D01*
Y182246D01*
X195332Y182580D01*
X195499Y182788D01*
X195832Y182871D01*
X196165Y182788D01*
X196374Y182538D01*
X196499Y182246D01*
Y181205D01*
G01Y182246D02*
X197707Y182871D01*
G01Y185638D02*
X195207D01*
X196999Y184096D01*
Y186180D01*
G01X197415Y187530D02*
X197624Y187821D01*
X197707Y188155D01*
X197624Y188488D01*
X197374Y188780D01*
X196999Y188988D01*
X196624Y189071D01*
X196165D01*
X195790Y188988D01*
X195457Y188780D01*
X195290Y188530D01*
X195207Y188238D01*
X195290Y187905D01*
X195457Y187655D01*
X195707Y187488D01*
X196040Y187405D01*
X196332Y187488D01*
X196624Y187696D01*
X196790Y187946D01*
X196832Y188238D01*
X196749Y188571D01*
X196540Y188821D01*
X196165Y189071D01*
G01X197707Y191338D02*
X197665Y191630D01*
X197540Y191963D01*
X197332Y192171D01*
X197040Y192255D01*
X196749Y192171D01*
X196499Y191921D01*
X196374Y191546D01*
Y191130D01*
X196290Y190880D01*
X196082Y190671D01*
X195790Y190588D01*
X195499Y190713D01*
X195290Y191005D01*
X195207Y191338D01*
X195290Y191671D01*
X195499Y191963D01*
X195790Y192088D01*
X196082Y192005D01*
X196290Y191796D01*
X196374Y191546D01*
Y191130D01*
X196499Y190755D01*
X196749Y190505D01*
X197040Y190421D01*
X197332Y190505D01*
X197540Y190713D01*
X197665Y191046D01*
X197707Y191338D01*
G01X198018Y201756D02*
X194018D01*
Y194356D01*
G01X176800Y194017D02*
X174300D01*
Y195058D01*
X174425Y195392D01*
X174592Y195600D01*
X174925Y195683D01*
X175258Y195600D01*
X175467Y195350D01*
X175592Y195058D01*
Y194017D01*
G01Y195058D02*
X176800Y195683D01*
G01Y198450D02*
X174300D01*
X176092Y196908D01*
Y198992D01*
G01X176508Y200342D02*
X176717Y200633D01*
X176800Y200967D01*
X176717Y201300D01*
X176467Y201592D01*
X176092Y201800D01*
X175717Y201883D01*
X175258D01*
X174883Y201800D01*
X174550Y201592D01*
X174383Y201342D01*
X174300Y201050D01*
X174383Y200717D01*
X174550Y200467D01*
X174800Y200300D01*
X175133Y200217D01*
X175425Y200300D01*
X175717Y200508D01*
X175883Y200758D01*
X175925Y201050D01*
X175842Y201383D01*
X175633Y201633D01*
X175258Y201883D01*
G01X176800Y204067D02*
X176258Y204150D01*
X175800Y204275D01*
X175383Y204442D01*
X174925Y204650D01*
X174300Y204983D01*
Y203317D01*
G01X184418Y194356D02*
X188418D01*
Y201756D01*
G01X198300Y194400D02*
X202300D01*
Y201800D01*
G01X180900Y193917D02*
X178400D01*
Y194958D01*
X178525Y195292D01*
X178692Y195500D01*
X179025Y195583D01*
X179358Y195500D01*
X179567Y195250D01*
X179692Y194958D01*
Y193917D01*
G01Y194958D02*
X180900Y195583D01*
G01Y198350D02*
X178400D01*
X180192Y196808D01*
Y198892D01*
G01X180608Y200242D02*
X180817Y200533D01*
X180900Y200867D01*
X180817Y201200D01*
X180567Y201492D01*
X180192Y201700D01*
X179817Y201783D01*
X179358D01*
X178983Y201700D01*
X178650Y201492D01*
X178483Y201242D01*
X178400Y200950D01*
X178483Y200617D01*
X178650Y200367D01*
X178900Y200200D01*
X179233Y200117D01*
X179525Y200200D01*
X179817Y200408D01*
X179983Y200658D01*
X180025Y200950D01*
X179942Y201283D01*
X179733Y201533D01*
X179358Y201783D01*
G01X180608Y203342D02*
X180817Y203633D01*
X180900Y203967D01*
X180817Y204300D01*
X180567Y204592D01*
X180192Y204800D01*
X179817Y204883D01*
X179358D01*
X178983Y204800D01*
X178650Y204592D01*
X178483Y204342D01*
X178400Y204050D01*
X178483Y203717D01*
X178650Y203467D01*
X178900Y203300D01*
X179233Y203217D01*
X179525Y203300D01*
X179817Y203508D01*
X179983Y203758D01*
X180025Y204050D01*
X179942Y204383D01*
X179733Y204633D01*
X179358Y204883D01*
G01X193018Y201756D02*
X189018D01*
Y194356D01*
G01X182568Y202656D02*
Y212480D01*
X177068Y220030D01*
Y231182D01*
X182568Y238732D01*
Y248556D01*
X214468D01*
Y238732D01*
X219968Y231182D01*
Y220030D01*
X214468Y212480D01*
Y202656D01*
X182568D01*
G01X177834Y236617D02*
X175334D01*
Y237658D01*
X175459Y237992D01*
X175626Y238200D01*
X175959Y238283D01*
X176292Y238200D01*
X176501Y237950D01*
X176626Y237658D01*
Y236617D01*
G01Y237658D02*
X177834Y238283D01*
G01X176792Y239758D02*
X176501Y240050D01*
X176334Y240300D01*
X176251Y240633D01*
X176334Y240925D01*
X176501Y241133D01*
X176751Y241300D01*
X177042Y241342D01*
X177292Y241300D01*
X177542Y241133D01*
X177751Y240883D01*
X177834Y240592D01*
X177751Y240258D01*
X177501Y239967D01*
X177126Y239800D01*
X176709Y239758D01*
X176167Y239842D01*
X175876Y239967D01*
X175584Y240175D01*
X175376Y240467D01*
X175334Y240758D01*
X175417Y241050D01*
X175626Y241258D01*
G01X177334Y242733D02*
X177626Y242983D01*
X177792Y243317D01*
X177834Y243692D01*
X177792Y244025D01*
X177584Y244358D01*
X177334Y244567D01*
X177084Y244608D01*
X176792Y244525D01*
X176584Y244233D01*
X176501Y243942D01*
Y243567D01*
G01Y243942D02*
X176376Y244192D01*
X176167Y244400D01*
X175917Y244483D01*
X175667Y244400D01*
X175459Y244192D01*
X175334Y243817D01*
X175376Y243442D01*
X175542Y243067D01*
G01X177459Y245833D02*
X177667Y246083D01*
X177792Y246375D01*
X177834Y246750D01*
X177751Y247125D01*
X177584Y247417D01*
X177292Y247625D01*
X176959Y247667D01*
X176626Y247583D01*
X176417Y247375D01*
X176251Y247083D01*
X176209Y246792D01*
X176251Y246500D01*
X176417Y246125D01*
X175334Y246250D01*
Y247375D01*
G01X190118Y235006D02*
X210518D01*
G01X190118Y216206D02*
Y235006D01*
G01Y216206D02*
X211218D01*
G01X178967Y264267D02*
X179300Y264517D01*
X179550Y264933D01*
X179717Y265517D01*
X179550Y266017D01*
X179217Y266350D01*
X178633Y266600D01*
X176383D01*
Y261600D01*
X179133D01*
X179717Y261933D01*
X180050Y262433D01*
X180217Y263017D01*
X180050Y263600D01*
X179550Y264100D01*
X178967Y264267D01*
X176383D01*
G01X181733Y261600D02*
Y266600D01*
X183900Y262433D01*
X186067Y266600D01*
Y261600D01*
G01X191333Y266183D02*
X190833Y266433D01*
X190250Y266600D01*
X189583D01*
X188833Y266350D01*
X188250Y265933D01*
X187833Y265433D01*
X187500Y264600D01*
X187417Y263850D01*
X187583Y263100D01*
X187833Y262600D01*
X188333Y262100D01*
X188917Y261767D01*
X189500Y261600D01*
X190083D01*
X190667Y261767D01*
X191167Y262017D01*
X191583Y262350D01*
G01X198867Y266600D02*
Y263017D01*
X199200Y262267D01*
X199867Y261767D01*
X200700Y261600D01*
X201533Y261767D01*
X202200Y262267D01*
X202533Y263017D01*
Y266600D01*
G01X204217Y261600D02*
X206300Y266600D01*
X208383Y261600D01*
G01X207633Y263350D02*
X204967D01*
G01X210233Y261600D02*
Y266600D01*
X212317D01*
X212983Y266350D01*
X213400Y266017D01*
X213567Y265350D01*
X213400Y264683D01*
X212900Y264267D01*
X212317Y264017D01*
X210233D01*
G01X212317D02*
X213567Y261600D01*
G01X217500Y266600D02*
Y261600D01*
G01X215583Y266600D02*
X219417D01*
G01X168600Y254500D02*
Y259500D01*
G01X172617Y258667D02*
X173117Y259167D01*
X173700Y259417D01*
X174367Y259500D01*
X175200Y259333D01*
X175783Y258917D01*
X175950Y258417D01*
X175867Y257917D01*
X175533Y257500D01*
X173867Y256667D01*
X173117Y256083D01*
X172617Y255250D01*
X172450Y254500D01*
X175950D01*
G01X179800D02*
Y259500D01*
X178800Y258500D01*
G01Y254500D02*
X180800D01*
G01X185400Y259500D02*
X184733Y259333D01*
X184233Y258917D01*
X183900Y258417D01*
X183650Y257750D01*
X183567Y257000D01*
X183650Y256250D01*
X183900Y255583D01*
X184233Y255083D01*
X184733Y254667D01*
X185400Y254500D01*
X186067Y254667D01*
X186567Y255083D01*
X186900Y255583D01*
X187150Y256250D01*
X187233Y257000D01*
X187150Y257750D01*
X186900Y258417D01*
X186567Y258917D01*
X186067Y259333D01*
X185400Y259500D01*
G01X195017Y254500D02*
Y259500D01*
X198183D01*
G01X197017Y257083D02*
X195017D01*
G01X200533Y259500D02*
Y254500D01*
X203867D01*
G01X205717D02*
X207800Y259500D01*
X209883Y254500D01*
G01X209133Y256250D02*
X206467D01*
G01X211650Y255167D02*
X212317Y254750D01*
X213067Y254500D01*
X213733D01*
X214400Y254750D01*
X214900Y255167D01*
X215150Y255750D01*
X214983Y256333D01*
X214567Y256833D01*
X213817Y257167D01*
X212817Y257333D01*
X212233Y257667D01*
X211983Y258250D01*
X212150Y258833D01*
X212567Y259250D01*
X213150Y259500D01*
X213733D01*
X214317Y259333D01*
X214817Y258917D01*
G01X217250Y254500D02*
Y259500D01*
G01X220750D02*
Y254500D01*
G01Y257000D02*
X217250D01*
G01X179917Y250200D02*
Y252700D01*
X180958D01*
X181292Y252575D01*
X181500Y252408D01*
X181583Y252075D01*
X181500Y251742D01*
X181250Y251533D01*
X180958Y251408D01*
X179917D01*
G01X180958D02*
X181583Y250200D01*
G01X182933Y250575D02*
X183183Y250367D01*
X183475Y250242D01*
X183850Y250200D01*
X184225Y250283D01*
X184517Y250450D01*
X184725Y250742D01*
X184767Y251075D01*
X184683Y251408D01*
X184475Y251617D01*
X184183Y251783D01*
X183892Y251825D01*
X183600Y251783D01*
X183225Y251617D01*
X183350Y252700D01*
X184475D01*
G01X186950D02*
X186617Y252617D01*
X186367Y252408D01*
X186200Y252158D01*
X186075Y251825D01*
X186033Y251450D01*
X186075Y251075D01*
X186200Y250742D01*
X186367Y250492D01*
X186617Y250283D01*
X186950Y250200D01*
X187283Y250283D01*
X187533Y250492D01*
X187700Y250742D01*
X187825Y251075D01*
X187867Y251450D01*
X187825Y251825D01*
X187700Y252158D01*
X187533Y252408D01*
X187283Y252617D01*
X186950Y252700D01*
G01X190050Y250200D02*
X190342Y250242D01*
X190675Y250367D01*
X190883Y250575D01*
X190967Y250867D01*
X190883Y251158D01*
X190633Y251408D01*
X190258Y251533D01*
X189842D01*
X189592Y251617D01*
X189383Y251825D01*
X189300Y252117D01*
X189425Y252408D01*
X189717Y252617D01*
X190050Y252700D01*
X190383Y252617D01*
X190675Y252408D01*
X190800Y252117D01*
X190717Y251825D01*
X190508Y251617D01*
X190258Y251533D01*
X189842D01*
X189467Y251408D01*
X189217Y251158D01*
X189133Y250867D01*
X189217Y250575D01*
X189425Y250367D01*
X189758Y250242D01*
X190050Y250200D01*
G01X199400Y249100D02*
Y253100D01*
X192000D01*
G01X168662Y276290D02*
X166162D01*
Y277290D01*
X166287Y277623D01*
X166579Y277873D01*
X166912Y277956D01*
X167245Y277873D01*
X167495Y277665D01*
X167620Y277290D01*
Y276290D01*
G01X167412Y280473D02*
Y281306D01*
X168162D01*
X168412Y281056D01*
X168579Y280765D01*
X168662Y280348D01*
X168579Y279931D01*
X168412Y279640D01*
X168162Y279390D01*
X167870Y279223D01*
X167537Y279140D01*
X167245D01*
X166995Y279223D01*
X166704Y279390D01*
X166454Y279640D01*
X166287Y279890D01*
X166162Y280223D01*
Y280515D01*
X166245Y280848D01*
X166412Y281098D01*
G01X168662Y283323D02*
X166162D01*
X166662Y282823D01*
G01X168662D02*
Y283823D01*
G01X219900Y280372D02*
X177900D01*
Y268372D01*
X219900D01*
Y280372D01*
G01X178241Y302132D02*
Y307132D01*
X181407D01*
G01X180241Y304715D02*
X178241D01*
G01X185424Y302132D02*
Y307132D01*
X184424Y306132D01*
G01Y302132D02*
X186424D01*
G01X191024Y301965D02*
X190857Y302049D01*
Y302215D01*
X191024Y302299D01*
X191191Y302215D01*
Y302049D01*
X191024Y301965D01*
G01Y304215D02*
X190857Y304299D01*
Y304465D01*
X191024Y304549D01*
X191191Y304465D01*
Y304299D01*
X191024Y304215D01*
G01X196624Y302132D02*
Y307132D01*
X195624Y306132D01*
G01Y302132D02*
X197624D01*
G01X202224Y301965D02*
X202057Y302049D01*
Y302215D01*
X202224Y302299D01*
X202391Y302215D01*
Y302049D01*
X202224Y301965D01*
G01X205991Y302882D02*
X206491Y302465D01*
X207074Y302215D01*
X207824Y302132D01*
X208574Y302299D01*
X209157Y302632D01*
X209574Y303215D01*
X209657Y303882D01*
X209491Y304549D01*
X209074Y304965D01*
X208491Y305299D01*
X207907Y305382D01*
X207324Y305299D01*
X206574Y304965D01*
X206824Y307132D01*
X209074D01*
G01X211341Y302132D02*
X213424Y307132D01*
X215507Y302132D01*
G01X214757Y303882D02*
X212091D01*
G01X217524Y301965D02*
X220524Y307132D01*
G01X224624Y302132D02*
X225207Y302215D01*
X225874Y302465D01*
X226291Y302882D01*
X226457Y303465D01*
X226291Y304049D01*
X225791Y304549D01*
X225041Y304799D01*
X224207D01*
X223707Y304965D01*
X223291Y305382D01*
X223124Y305965D01*
X223374Y306549D01*
X223957Y306965D01*
X224624Y307132D01*
X225291Y306965D01*
X225874Y306549D01*
X226124Y305965D01*
X225957Y305382D01*
X225541Y304965D01*
X225041Y304799D01*
X224207D01*
X223457Y304549D01*
X222957Y304049D01*
X222791Y303465D01*
X222957Y302882D01*
X223374Y302465D01*
X224041Y302215D01*
X224624Y302132D01*
G01X228141Y307132D02*
X230224Y302132D01*
X232307Y307132D01*
G01X191050Y285000D02*
Y282500D01*
G01X190092Y285000D02*
X192008D01*
G01X193275Y282500D02*
X195025Y285000D01*
G01X193275D02*
X195025Y282500D01*
G01X178608Y285000D02*
X179650Y282500D01*
X180692Y285000D01*
G01X183667Y284792D02*
X183417Y284917D01*
X183125Y285000D01*
X182792D01*
X182417Y284875D01*
X182125Y284667D01*
X181917Y284417D01*
X181750Y284000D01*
X181708Y283625D01*
X181792Y283250D01*
X181917Y283000D01*
X182167Y282750D01*
X182458Y282583D01*
X182750Y282500D01*
X183042D01*
X183333Y282583D01*
X183583Y282708D01*
X183792Y282875D01*
G01X186767Y284792D02*
X186517Y284917D01*
X186225Y285000D01*
X185892D01*
X185517Y284875D01*
X185225Y284667D01*
X185017Y284417D01*
X184850Y284000D01*
X184808Y283625D01*
X184892Y283250D01*
X185017Y283000D01*
X185267Y282750D01*
X185558Y282583D01*
X185850Y282500D01*
X186142D01*
X186433Y282583D01*
X186683Y282708D01*
X186892Y282875D01*
G01X169921Y307375D02*
X167421D01*
Y308375D01*
X167546Y308708D01*
X167838Y308958D01*
X168171Y309041D01*
X168504Y308958D01*
X168754Y308750D01*
X168879Y308375D01*
Y307375D01*
G01X167629Y312225D02*
X167504Y311975D01*
X167421Y311683D01*
Y311350D01*
X167546Y310975D01*
X167754Y310683D01*
X168004Y310475D01*
X168421Y310308D01*
X168796Y310266D01*
X169171Y310350D01*
X169421Y310475D01*
X169671Y310725D01*
X169838Y311016D01*
X169921Y311308D01*
Y311600D01*
X169838Y311891D01*
X169713Y312141D01*
X169546Y312350D01*
G01X168879Y313616D02*
X168588Y313908D01*
X168421Y314158D01*
X168338Y314491D01*
X168421Y314783D01*
X168588Y314991D01*
X168838Y315158D01*
X169129Y315200D01*
X169379Y315158D01*
X169629Y314991D01*
X169838Y314741D01*
X169921Y314450D01*
X169838Y314116D01*
X169588Y313825D01*
X169213Y313658D01*
X168796Y313616D01*
X168254Y313700D01*
X167963Y313825D01*
X167671Y314033D01*
X167463Y314325D01*
X167421Y314616D01*
X167504Y314908D01*
X167713Y315116D01*
G01X168879Y316716D02*
X168588Y317008D01*
X168421Y317258D01*
X168338Y317591D01*
X168421Y317883D01*
X168588Y318091D01*
X168838Y318258D01*
X169129Y318300D01*
X169379Y318258D01*
X169629Y318091D01*
X169838Y317841D01*
X169921Y317550D01*
X169838Y317216D01*
X169588Y316925D01*
X169213Y316758D01*
X168796Y316716D01*
X168254Y316800D01*
X167963Y316925D01*
X167671Y317133D01*
X167463Y317425D01*
X167421Y317716D01*
X167504Y318008D01*
X167713Y318216D01*
G01X173700Y307417D02*
X171200D01*
Y308417D01*
X171325Y308750D01*
X171617Y309000D01*
X171950Y309083D01*
X172283Y309000D01*
X172533Y308792D01*
X172658Y308417D01*
Y307417D01*
G01X171408Y312267D02*
X171283Y312017D01*
X171200Y311725D01*
Y311392D01*
X171325Y311017D01*
X171533Y310725D01*
X171783Y310517D01*
X172200Y310350D01*
X172575Y310308D01*
X172950Y310392D01*
X173200Y310517D01*
X173450Y310767D01*
X173617Y311058D01*
X173700Y311350D01*
Y311642D01*
X173617Y311933D01*
X173492Y312183D01*
X173325Y312392D01*
G01X172658Y313658D02*
X172367Y313950D01*
X172200Y314200D01*
X172117Y314533D01*
X172200Y314825D01*
X172367Y315033D01*
X172617Y315200D01*
X172908Y315242D01*
X173158Y315200D01*
X173408Y315033D01*
X173617Y314783D01*
X173700Y314492D01*
X173617Y314158D01*
X173367Y313867D01*
X172992Y313700D01*
X172575Y313658D01*
X172033Y313742D01*
X171742Y313867D01*
X171450Y314075D01*
X171242Y314367D01*
X171200Y314658D01*
X171283Y314950D01*
X171492Y315158D01*
G01X173700Y317550D02*
X173658Y317842D01*
X173533Y318175D01*
X173325Y318383D01*
X173033Y318467D01*
X172742Y318383D01*
X172492Y318133D01*
X172367Y317758D01*
Y317342D01*
X172283Y317092D01*
X172075Y316883D01*
X171783Y316800D01*
X171492Y316925D01*
X171283Y317217D01*
X171200Y317550D01*
X171283Y317883D01*
X171492Y318175D01*
X171783Y318300D01*
X172075Y318217D01*
X172283Y318008D01*
X172367Y317758D01*
Y317342D01*
X172492Y316967D01*
X172742Y316717D01*
X173033Y316633D01*
X173325Y316717D01*
X173533Y316925D01*
X173658Y317258D01*
X173700Y317550D01*
G01X196411Y293258D02*
Y295758D01*
X197452D01*
X197786Y295633D01*
X197994Y295466D01*
X198077Y295133D01*
X197994Y294800D01*
X197744Y294591D01*
X197452Y294466D01*
X196411D01*
G01X197452D02*
X198077Y293258D01*
G01X199636Y293550D02*
X199927Y293341D01*
X200261Y293258D01*
X200594Y293341D01*
X200886Y293591D01*
X201094Y293966D01*
X201177Y294341D01*
Y294800D01*
X201094Y295175D01*
X200886Y295508D01*
X200636Y295675D01*
X200344Y295758D01*
X200011Y295675D01*
X199761Y295508D01*
X199594Y295258D01*
X199511Y294925D01*
X199594Y294633D01*
X199802Y294341D01*
X200052Y294175D01*
X200344Y294133D01*
X200677Y294216D01*
X200927Y294425D01*
X201177Y294800D01*
G01X203944Y293258D02*
Y295758D01*
X202402Y293966D01*
X204486D01*
G01X205752Y295341D02*
X206002Y295591D01*
X206294Y295716D01*
X206627Y295758D01*
X207044Y295675D01*
X207336Y295466D01*
X207419Y295216D01*
X207377Y294966D01*
X207211Y294758D01*
X206377Y294341D01*
X206002Y294050D01*
X205752Y293633D01*
X205669Y293258D01*
X207419D01*
G01X196015Y287501D02*
Y291501D01*
X188615D01*
G01X205961Y287306D02*
Y291307D01*
X198561Y291306D01*
G01X176569Y293691D02*
X176902Y293483D01*
X177277Y293358D01*
X177611D01*
X177944Y293483D01*
X178194Y293691D01*
X178319Y293983D01*
X178236Y294275D01*
X178027Y294525D01*
X177652Y294691D01*
X177152Y294775D01*
X176861Y294941D01*
X176736Y295233D01*
X176819Y295525D01*
X177027Y295733D01*
X177319Y295858D01*
X177611D01*
X177902Y295775D01*
X178152Y295566D01*
G01X181461Y295650D02*
X181211Y295775D01*
X180919Y295858D01*
X180586D01*
X180211Y295733D01*
X179919Y295525D01*
X179711Y295275D01*
X179544Y294858D01*
X179502Y294483D01*
X179586Y294108D01*
X179711Y293858D01*
X179961Y293608D01*
X180252Y293441D01*
X180544Y293358D01*
X180836D01*
X181127Y293441D01*
X181377Y293566D01*
X181586Y293733D01*
G01X183644Y293358D02*
Y295858D01*
X183144Y295358D01*
G01Y293358D02*
X184144D01*
G01X185827Y293858D02*
X186077Y293566D01*
X186411Y293400D01*
X186786Y293358D01*
X187119Y293400D01*
X187452Y293608D01*
X187661Y293858D01*
X187702Y294108D01*
X187619Y294400D01*
X187327Y294608D01*
X187036Y294691D01*
X186661D01*
G01X187036D02*
X187286Y294816D01*
X187494Y295025D01*
X187577Y295275D01*
X187494Y295525D01*
X187286Y295733D01*
X186911Y295858D01*
X186536Y295816D01*
X186161Y295650D01*
G01X189844Y295858D02*
X189511Y295775D01*
X189261Y295566D01*
X189094Y295316D01*
X188969Y294983D01*
X188927Y294608D01*
X188969Y294233D01*
X189094Y293900D01*
X189261Y293650D01*
X189511Y293441D01*
X189844Y293358D01*
X190177Y293441D01*
X190427Y293650D01*
X190594Y293900D01*
X190719Y294233D01*
X190761Y294608D01*
X190719Y294983D01*
X190594Y295316D01*
X190427Y295566D01*
X190177Y295775D01*
X189844Y295858D01*
G01X192944Y293358D02*
X193236Y293400D01*
X193569Y293525D01*
X193777Y293733D01*
X193861Y294025D01*
X193777Y294316D01*
X193527Y294566D01*
X193152Y294691D01*
X192736D01*
X192486Y294775D01*
X192277Y294983D01*
X192194Y295275D01*
X192319Y295566D01*
X192611Y295775D01*
X192944Y295858D01*
X193277Y295775D01*
X193569Y295566D01*
X193694Y295275D01*
X193611Y294983D01*
X193402Y294775D01*
X193152Y294691D01*
X192736D01*
X192361Y294566D01*
X192111Y294316D01*
X192027Y294025D01*
X192111Y293733D01*
X192319Y293525D01*
X192652Y293400D01*
X192944Y293358D01*
G01X169926Y320922D02*
Y323422D01*
X170967D01*
X171301Y323297D01*
X171509Y323130D01*
X171592Y322797D01*
X171509Y322464D01*
X171259Y322255D01*
X170967Y322130D01*
X169926D01*
G01X170967D02*
X171592Y320922D01*
G01X173067Y321964D02*
X173359Y322255D01*
X173609Y322422D01*
X173942Y322505D01*
X174234Y322422D01*
X174442Y322255D01*
X174609Y322005D01*
X174651Y321714D01*
X174609Y321464D01*
X174442Y321214D01*
X174192Y321005D01*
X173901Y320922D01*
X173567Y321005D01*
X173276Y321255D01*
X173109Y321630D01*
X173067Y322047D01*
X173151Y322589D01*
X173276Y322880D01*
X173484Y323172D01*
X173776Y323380D01*
X174067Y323422D01*
X174359Y323339D01*
X174567Y323130D01*
G01X176042Y321422D02*
X176292Y321130D01*
X176626Y320964D01*
X177001Y320922D01*
X177334Y320964D01*
X177667Y321172D01*
X177876Y321422D01*
X177917Y321672D01*
X177834Y321964D01*
X177542Y322172D01*
X177251Y322255D01*
X176876D01*
G01X177251D02*
X177501Y322380D01*
X177709Y322589D01*
X177792Y322839D01*
X177709Y323089D01*
X177501Y323297D01*
X177126Y323422D01*
X176751Y323380D01*
X176376Y323214D01*
G01X180059Y320922D02*
Y323422D01*
X179559Y322922D01*
G01Y320922D02*
X180559D01*
G01X183743Y401953D02*
Y400161D01*
X183910Y399786D01*
X184243Y399536D01*
X184660Y399453D01*
X185077Y399536D01*
X185410Y399786D01*
X185577Y400161D01*
Y401953D01*
G01X186843Y399953D02*
X187093Y399661D01*
X187427Y399495D01*
X187802Y399453D01*
X188135Y399495D01*
X188468Y399703D01*
X188677Y399953D01*
X188718Y400203D01*
X188635Y400495D01*
X188343Y400703D01*
X188052Y400786D01*
X187677D01*
G01X188052D02*
X188302Y400911D01*
X188510Y401120D01*
X188593Y401370D01*
X188510Y401620D01*
X188302Y401828D01*
X187927Y401953D01*
X187552Y401911D01*
X187177Y401745D01*
G01X190777Y399453D02*
X190860Y399995D01*
X190985Y400453D01*
X191152Y400870D01*
X191360Y401328D01*
X191693Y401953D01*
X190027D01*
G01X183827Y394553D02*
Y397053D01*
X184868D01*
X185202Y396928D01*
X185410Y396761D01*
X185493Y396428D01*
X185410Y396095D01*
X185160Y395886D01*
X184868Y395761D01*
X183827D01*
G01X184868D02*
X185493Y394553D01*
G01X186968Y395595D02*
X187260Y395886D01*
X187510Y396053D01*
X187843Y396136D01*
X188135Y396053D01*
X188343Y395886D01*
X188510Y395636D01*
X188552Y395345D01*
X188510Y395095D01*
X188343Y394845D01*
X188093Y394636D01*
X187802Y394553D01*
X187468Y394636D01*
X187177Y394886D01*
X187010Y395261D01*
X186968Y395678D01*
X187052Y396220D01*
X187177Y396511D01*
X187385Y396803D01*
X187677Y397011D01*
X187968Y397053D01*
X188260Y396970D01*
X188468Y396761D01*
G01X189943Y394928D02*
X190193Y394720D01*
X190485Y394595D01*
X190860Y394553D01*
X191235Y394636D01*
X191527Y394803D01*
X191735Y395095D01*
X191777Y395428D01*
X191693Y395761D01*
X191485Y395970D01*
X191193Y396136D01*
X190902Y396178D01*
X190610Y396136D01*
X190235Y395970D01*
X190360Y397053D01*
X191485D01*
G01X197360Y395170D02*
X194860D01*
Y396211D01*
X194985Y396545D01*
X195152Y396753D01*
X195485Y396836D01*
X195818Y396753D01*
X196027Y396503D01*
X196152Y396211D01*
Y395170D01*
G01Y396211D02*
X197360Y396836D01*
G01X196860Y398186D02*
X197152Y398436D01*
X197318Y398770D01*
X197360Y399145D01*
X197318Y399478D01*
X197110Y399811D01*
X196860Y400020D01*
X196610Y400061D01*
X196318Y399978D01*
X196110Y399686D01*
X196027Y399395D01*
Y399020D01*
G01Y399395D02*
X195902Y399645D01*
X195693Y399853D01*
X195443Y399936D01*
X195193Y399853D01*
X194985Y399645D01*
X194860Y399270D01*
X194902Y398895D01*
X195068Y398520D01*
G01X195277Y401411D02*
X195027Y401661D01*
X194902Y401953D01*
X194860Y402286D01*
X194943Y402703D01*
X195152Y402995D01*
X195402Y403078D01*
X195652Y403036D01*
X195860Y402870D01*
X196277Y402036D01*
X196568Y401661D01*
X196985Y401411D01*
X197360Y401328D01*
Y403078D01*
G01Y405303D02*
X197318Y405595D01*
X197193Y405928D01*
X196985Y406136D01*
X196693Y406220D01*
X196402Y406136D01*
X196152Y405886D01*
X196027Y405511D01*
Y405095D01*
X195943Y404845D01*
X195735Y404636D01*
X195443Y404553D01*
X195152Y404678D01*
X194943Y404970D01*
X194860Y405303D01*
X194943Y405636D01*
X195152Y405928D01*
X195443Y406053D01*
X195735Y405970D01*
X195943Y405761D01*
X196027Y405511D01*
Y405095D01*
X196152Y404720D01*
X196402Y404470D01*
X196693Y404386D01*
X196985Y404470D01*
X197193Y404678D01*
X197318Y405011D01*
X197360Y405303D01*
G01X183827Y404153D02*
Y406653D01*
X184868D01*
X185202Y406528D01*
X185410Y406361D01*
X185493Y406028D01*
X185410Y405695D01*
X185160Y405486D01*
X184868Y405361D01*
X183827D01*
G01X184868D02*
X185493Y404153D01*
G01X186968Y405195D02*
X187260Y405486D01*
X187510Y405653D01*
X187843Y405736D01*
X188135Y405653D01*
X188343Y405486D01*
X188510Y405236D01*
X188552Y404945D01*
X188510Y404695D01*
X188343Y404445D01*
X188093Y404236D01*
X187802Y404153D01*
X187468Y404236D01*
X187177Y404486D01*
X187010Y404861D01*
X186968Y405278D01*
X187052Y405820D01*
X187177Y406111D01*
X187385Y406403D01*
X187677Y406611D01*
X187968Y406653D01*
X188260Y406570D01*
X188468Y406361D01*
G01X191360Y404153D02*
Y406653D01*
X189818Y404861D01*
X191902D01*
G01X190477Y407953D02*
Y410453D01*
X191518D01*
X191852Y410328D01*
X192060Y410161D01*
X192143Y409828D01*
X192060Y409495D01*
X191810Y409286D01*
X191518Y409161D01*
X190477D01*
G01X191518D02*
X192143Y407953D01*
G01X194910D02*
Y410453D01*
X193368Y408661D01*
X195452D01*
G01X198010Y407953D02*
Y410453D01*
X196468Y408661D01*
X198552D01*
G01X200610Y410453D02*
X200277Y410370D01*
X200027Y410161D01*
X199860Y409911D01*
X199735Y409578D01*
X199693Y409203D01*
X199735Y408828D01*
X199860Y408495D01*
X200027Y408245D01*
X200277Y408036D01*
X200610Y407953D01*
X200943Y408036D01*
X201193Y408245D01*
X201360Y408495D01*
X201485Y408828D01*
X201527Y409203D01*
X201485Y409578D01*
X201360Y409911D01*
X201193Y410161D01*
X200943Y410370D01*
X200610Y410453D01*
G01X178077Y408153D02*
Y410653D01*
X179118D01*
X179452Y410528D01*
X179660Y410361D01*
X179743Y410028D01*
X179660Y409695D01*
X179410Y409486D01*
X179118Y409361D01*
X178077D01*
G01X179118D02*
X179743Y408153D01*
G01X182510D02*
Y410653D01*
X180968Y408861D01*
X183052D01*
G01X185610Y408153D02*
Y410653D01*
X184068Y408861D01*
X186152D01*
G01X188210Y408153D02*
Y410653D01*
X187710Y410153D01*
G01Y408153D02*
X188710D01*
G01X168330Y406707D02*
X165830D01*
Y407748D01*
X165955Y408082D01*
X166122Y408290D01*
X166455Y408373D01*
X166788Y408290D01*
X166997Y408040D01*
X167122Y407748D01*
Y406707D01*
G01Y407748D02*
X168330Y408373D01*
G01X167288Y409848D02*
X166997Y410140D01*
X166830Y410390D01*
X166747Y410723D01*
X166830Y411015D01*
X166997Y411223D01*
X167247Y411390D01*
X167538Y411432D01*
X167788Y411390D01*
X168038Y411223D01*
X168247Y410973D01*
X168330Y410682D01*
X168247Y410348D01*
X167997Y410057D01*
X167622Y409890D01*
X167205Y409848D01*
X166663Y409932D01*
X166372Y410057D01*
X166080Y410265D01*
X165872Y410557D01*
X165830Y410848D01*
X165913Y411140D01*
X166122Y411348D01*
G01X167955Y412823D02*
X168163Y413073D01*
X168288Y413365D01*
X168330Y413740D01*
X168247Y414115D01*
X168080Y414407D01*
X167788Y414615D01*
X167455Y414657D01*
X167122Y414573D01*
X166913Y414365D01*
X166747Y414073D01*
X166705Y413782D01*
X166747Y413490D01*
X166913Y413115D01*
X165830Y413240D01*
Y414365D01*
G01X168330Y416840D02*
X168288Y417132D01*
X168163Y417465D01*
X167955Y417673D01*
X167663Y417757D01*
X167372Y417673D01*
X167122Y417423D01*
X166997Y417048D01*
Y416632D01*
X166913Y416382D01*
X166705Y416173D01*
X166413Y416090D01*
X166122Y416215D01*
X165913Y416507D01*
X165830Y416840D01*
X165913Y417173D01*
X166122Y417465D01*
X166413Y417590D01*
X166705Y417507D01*
X166913Y417298D01*
X166997Y417048D01*
Y416632D01*
X167122Y416257D01*
X167372Y416007D01*
X167663Y415923D01*
X167955Y416007D01*
X168163Y416215D01*
X168288Y416548D01*
X168330Y416840D01*
G01X175484Y429546D02*
X177984D01*
G01X175484Y428588D02*
Y430504D01*
G01X177984Y431813D02*
X175484D01*
Y432813D01*
X175609Y433146D01*
X175901Y433396D01*
X176234Y433479D01*
X176567Y433396D01*
X176817Y433188D01*
X176942Y432813D01*
Y431813D01*
G01X175901Y434954D02*
X175651Y435204D01*
X175526Y435496D01*
X175484Y435829D01*
X175567Y436246D01*
X175776Y436538D01*
X176026Y436621D01*
X176276Y436579D01*
X176484Y436413D01*
X176901Y435579D01*
X177192Y435204D01*
X177609Y434954D01*
X177984Y434871D01*
Y436621D01*
G01Y438846D02*
X175484D01*
X175984Y438346D01*
G01X177984D02*
Y439346D01*
G01Y441863D02*
X177442Y441946D01*
X176984Y442071D01*
X176567Y442238D01*
X176109Y442446D01*
X175484Y442779D01*
Y441113D01*
G01X171777Y427999D02*
X174277D01*
G01X171777Y427041D02*
Y428957D01*
G01X174277Y430266D02*
X171777D01*
Y431266D01*
X171902Y431599D01*
X172194Y431849D01*
X172527Y431932D01*
X172860Y431849D01*
X173110Y431641D01*
X173235Y431266D01*
Y430266D01*
G01X173985Y433491D02*
X174194Y433782D01*
X174277Y434116D01*
X174194Y434449D01*
X173944Y434741D01*
X173569Y434949D01*
X173194Y435032D01*
X172735D01*
X172360Y434949D01*
X172027Y434741D01*
X171860Y434491D01*
X171777Y434199D01*
X171860Y433866D01*
X172027Y433616D01*
X172277Y433449D01*
X172610Y433366D01*
X172902Y433449D01*
X173194Y433657D01*
X173360Y433907D01*
X173402Y434199D01*
X173319Y434532D01*
X173110Y434782D01*
X172735Y435032D01*
G01X174277Y437799D02*
X171777D01*
X173569Y436257D01*
Y438341D01*
G01X194016Y427380D02*
X191516D01*
Y428421D01*
X191641Y428755D01*
X191808Y428963D01*
X192141Y429046D01*
X192474Y428963D01*
X192683Y428713D01*
X192808Y428421D01*
Y427380D01*
G01Y428421D02*
X194016Y429046D01*
G01X193516Y430396D02*
X193808Y430646D01*
X193974Y430980D01*
X194016Y431355D01*
X193974Y431688D01*
X193766Y432021D01*
X193516Y432230D01*
X193266Y432271D01*
X192974Y432188D01*
X192766Y431896D01*
X192683Y431605D01*
Y431230D01*
G01Y431605D02*
X192558Y431855D01*
X192349Y432063D01*
X192099Y432146D01*
X191849Y432063D01*
X191641Y431855D01*
X191516Y431480D01*
X191558Y431105D01*
X191724Y430730D01*
G01X193516Y433496D02*
X193808Y433746D01*
X193974Y434080D01*
X194016Y434455D01*
X193974Y434788D01*
X193766Y435121D01*
X193516Y435330D01*
X193266Y435371D01*
X192974Y435288D01*
X192766Y434996D01*
X192683Y434705D01*
Y434330D01*
G01Y434705D02*
X192558Y434955D01*
X192349Y435163D01*
X192099Y435246D01*
X191849Y435163D01*
X191641Y434955D01*
X191516Y434580D01*
X191558Y434205D01*
X191724Y433830D01*
G01X191516Y437513D02*
X191599Y437180D01*
X191808Y436930D01*
X192058Y436763D01*
X192391Y436638D01*
X192766Y436596D01*
X193141Y436638D01*
X193474Y436763D01*
X193724Y436930D01*
X193933Y437180D01*
X194016Y437513D01*
X193933Y437846D01*
X193724Y438096D01*
X193474Y438263D01*
X193141Y438388D01*
X192766Y438430D01*
X192391Y438388D01*
X192058Y438263D01*
X191808Y438096D01*
X191599Y437846D01*
X191516Y437513D01*
G01X199841Y435842D02*
X195841D01*
Y428442D01*
G01X188860Y412570D02*
X186360D01*
Y413611D01*
X186485Y413945D01*
X186652Y414153D01*
X186985Y414236D01*
X187318Y414153D01*
X187527Y413903D01*
X187652Y413611D01*
Y412570D01*
G01Y413611D02*
X188860Y414236D01*
G01X188485Y415586D02*
X188693Y415836D01*
X188818Y416128D01*
X188860Y416503D01*
X188777Y416878D01*
X188610Y417170D01*
X188318Y417378D01*
X187985Y417420D01*
X187652Y417336D01*
X187443Y417128D01*
X187277Y416836D01*
X187235Y416545D01*
X187277Y416253D01*
X187443Y415878D01*
X186360Y416003D01*
Y417128D01*
G01X188860Y420103D02*
X186360D01*
X188152Y418561D01*
Y420645D01*
G01X186777Y421911D02*
X186527Y422161D01*
X186402Y422453D01*
X186360Y422786D01*
X186443Y423203D01*
X186652Y423495D01*
X186902Y423578D01*
X187152Y423536D01*
X187360Y423370D01*
X187777Y422536D01*
X188068Y422161D01*
X188485Y421911D01*
X188860Y421828D01*
Y423578D01*
G01X192960Y412570D02*
X190460D01*
Y413611D01*
X190585Y413945D01*
X190752Y414153D01*
X191085Y414236D01*
X191418Y414153D01*
X191627Y413903D01*
X191752Y413611D01*
Y412570D01*
G01Y413611D02*
X192960Y414236D01*
G01X191918Y415711D02*
X191627Y416003D01*
X191460Y416253D01*
X191377Y416586D01*
X191460Y416878D01*
X191627Y417086D01*
X191877Y417253D01*
X192168Y417295D01*
X192418Y417253D01*
X192668Y417086D01*
X192877Y416836D01*
X192960Y416545D01*
X192877Y416211D01*
X192627Y415920D01*
X192252Y415753D01*
X191835Y415711D01*
X191293Y415795D01*
X191002Y415920D01*
X190710Y416128D01*
X190502Y416420D01*
X190460Y416711D01*
X190543Y417003D01*
X190752Y417211D01*
G01X192960Y420103D02*
X190460D01*
X192252Y418561D01*
Y420645D01*
G01X190877Y421911D02*
X190627Y422161D01*
X190502Y422453D01*
X190460Y422786D01*
X190543Y423203D01*
X190752Y423495D01*
X191002Y423578D01*
X191252Y423536D01*
X191460Y423370D01*
X191877Y422536D01*
X192168Y422161D01*
X192585Y421911D01*
X192960Y421828D01*
Y423578D01*
G01X179572Y434410D02*
Y436910D01*
X180613D01*
X180947Y436785D01*
X181155Y436618D01*
X181238Y436285D01*
X181155Y435952D01*
X180905Y435743D01*
X180613Y435618D01*
X179572D01*
G01X180613D02*
X181238Y434410D01*
G01X182588Y434785D02*
X182838Y434577D01*
X183130Y434452D01*
X183505Y434410D01*
X183880Y434493D01*
X184172Y434660D01*
X184380Y434952D01*
X184422Y435285D01*
X184338Y435618D01*
X184130Y435827D01*
X183838Y435993D01*
X183547Y436035D01*
X183255Y435993D01*
X182880Y435827D01*
X183005Y436910D01*
X184130D01*
G01X187105Y434410D02*
Y436910D01*
X185563Y435118D01*
X187647D01*
G01X188913Y435452D02*
X189205Y435743D01*
X189455Y435910D01*
X189788Y435993D01*
X190080Y435910D01*
X190288Y435743D01*
X190455Y435493D01*
X190497Y435202D01*
X190455Y434952D01*
X190288Y434702D01*
X190038Y434493D01*
X189747Y434410D01*
X189413Y434493D01*
X189122Y434743D01*
X188955Y435118D01*
X188913Y435535D01*
X188997Y436077D01*
X189122Y436368D01*
X189330Y436660D01*
X189622Y436868D01*
X189913Y436910D01*
X190205Y436827D01*
X190413Y436618D01*
G01X179587Y430335D02*
Y432835D01*
X180628D01*
X180962Y432710D01*
X181170Y432543D01*
X181253Y432210D01*
X181170Y431877D01*
X180920Y431668D01*
X180628Y431543D01*
X179587D01*
G01X180628D02*
X181253Y430335D01*
G01X182603Y430710D02*
X182853Y430502D01*
X183145Y430377D01*
X183520Y430335D01*
X183895Y430418D01*
X184187Y430585D01*
X184395Y430877D01*
X184437Y431210D01*
X184353Y431543D01*
X184145Y431752D01*
X183853Y431918D01*
X183562Y431960D01*
X183270Y431918D01*
X182895Y431752D01*
X183020Y432835D01*
X184145D01*
G01X185828Y431377D02*
X186120Y431668D01*
X186370Y431835D01*
X186703Y431918D01*
X186995Y431835D01*
X187203Y431668D01*
X187370Y431418D01*
X187412Y431127D01*
X187370Y430877D01*
X187203Y430627D01*
X186953Y430418D01*
X186662Y430335D01*
X186328Y430418D01*
X186037Y430668D01*
X185870Y431043D01*
X185828Y431460D01*
X185912Y432002D01*
X186037Y432293D01*
X186245Y432585D01*
X186537Y432793D01*
X186828Y432835D01*
X187120Y432752D01*
X187328Y432543D01*
G01X189720Y430335D02*
Y432835D01*
X189220Y432335D01*
G01Y430335D02*
X190220D01*
G01X184554Y444672D02*
Y448672D01*
X177154D01*
G01X170763Y424917D02*
X168263D01*
Y425958D01*
X168388Y426292D01*
X168555Y426500D01*
X168888Y426583D01*
X169221Y426500D01*
X169430Y426250D01*
X169555Y425958D01*
Y424917D01*
G01Y425958D02*
X170763Y426583D01*
G01Y429350D02*
X168263D01*
X170055Y427808D01*
Y429892D01*
G01X170763Y431867D02*
X170221Y431950D01*
X169763Y432075D01*
X169346Y432242D01*
X168888Y432450D01*
X168263Y432783D01*
Y431117D01*
G01X170263Y434133D02*
X170555Y434383D01*
X170721Y434717D01*
X170763Y435092D01*
X170721Y435425D01*
X170513Y435758D01*
X170263Y435967D01*
X170013Y436008D01*
X169721Y435925D01*
X169513Y435633D01*
X169430Y435342D01*
Y434967D01*
G01Y435342D02*
X169305Y435592D01*
X169096Y435800D01*
X168846Y435883D01*
X168596Y435800D01*
X168388Y435592D01*
X168263Y435217D01*
X168305Y434842D01*
X168471Y434467D01*
G01X191787Y468894D02*
X194287D01*
G01X191787Y467936D02*
Y469852D01*
G01X194287Y471161D02*
X191787D01*
Y472161D01*
X191912Y472494D01*
X192204Y472744D01*
X192537Y472827D01*
X192870Y472744D01*
X193120Y472536D01*
X193245Y472161D01*
Y471161D01*
G01X194287Y475094D02*
X191787D01*
X192287Y474594D01*
G01X194287D02*
Y475594D01*
G01X193912Y477277D02*
X194120Y477527D01*
X194245Y477819D01*
X194287Y478194D01*
X194204Y478569D01*
X194037Y478861D01*
X193745Y479069D01*
X193412Y479111D01*
X193079Y479027D01*
X192870Y478819D01*
X192704Y478527D01*
X192662Y478236D01*
X192704Y477944D01*
X192870Y477569D01*
X191787Y477694D01*
Y478819D01*
G01X194287Y481794D02*
X191787D01*
X193579Y480252D01*
Y482336D01*
G01X173750Y473600D02*
Y471100D01*
G01X172792Y473600D02*
X174708D01*
G01X176017Y471100D02*
Y473600D01*
X177017D01*
X177350Y473475D01*
X177600Y473183D01*
X177683Y472850D01*
X177600Y472517D01*
X177392Y472267D01*
X177017Y472142D01*
X176017D01*
G01X179242Y471392D02*
X179533Y471183D01*
X179867Y471100D01*
X180200Y471183D01*
X180492Y471433D01*
X180700Y471808D01*
X180783Y472183D01*
Y472642D01*
X180700Y473017D01*
X180492Y473350D01*
X180242Y473517D01*
X179950Y473600D01*
X179617Y473517D01*
X179367Y473350D01*
X179200Y473100D01*
X179117Y472767D01*
X179200Y472475D01*
X179408Y472183D01*
X179658Y472017D01*
X179950Y471975D01*
X180283Y472058D01*
X180533Y472267D01*
X180783Y472642D01*
G01X182258Y473183D02*
X182508Y473433D01*
X182800Y473558D01*
X183133Y473600D01*
X183550Y473517D01*
X183842Y473308D01*
X183925Y473058D01*
X183883Y472808D01*
X183717Y472600D01*
X182883Y472183D01*
X182508Y471892D01*
X182258Y471475D01*
X182175Y471100D01*
X183925D01*
G01X175450Y470300D02*
Y467800D01*
G01X174492Y470300D02*
X176408D01*
G01X177717Y467800D02*
Y470300D01*
X178717D01*
X179050Y470175D01*
X179300Y469883D01*
X179383Y469550D01*
X179300Y469217D01*
X179092Y468967D01*
X178717Y468842D01*
X177717D01*
G01X180942Y468092D02*
X181233Y467883D01*
X181567Y467800D01*
X181900Y467883D01*
X182192Y468133D01*
X182400Y468508D01*
X182483Y468883D01*
Y469342D01*
X182400Y469717D01*
X182192Y470050D01*
X181942Y470217D01*
X181650Y470300D01*
X181317Y470217D01*
X181067Y470050D01*
X180900Y469800D01*
X180817Y469467D01*
X180900Y469175D01*
X181108Y468883D01*
X181358Y468717D01*
X181650Y468675D01*
X181983Y468758D01*
X182233Y468967D01*
X182483Y469342D01*
G01X183833Y468175D02*
X184083Y467967D01*
X184375Y467842D01*
X184750Y467800D01*
X185125Y467883D01*
X185417Y468050D01*
X185625Y468342D01*
X185667Y468675D01*
X185583Y469008D01*
X185375Y469217D01*
X185083Y469383D01*
X184792Y469425D01*
X184500Y469383D01*
X184125Y469217D01*
X184250Y470300D01*
X185375D01*
G01X198800Y452617D02*
X196300D01*
Y453658D01*
X196425Y453992D01*
X196592Y454200D01*
X196925Y454283D01*
X197258Y454200D01*
X197467Y453950D01*
X197592Y453658D01*
Y452617D01*
G01Y453658D02*
X198800Y454283D01*
G01X198425Y455633D02*
X198633Y455883D01*
X198758Y456175D01*
X198800Y456550D01*
X198717Y456925D01*
X198550Y457217D01*
X198258Y457425D01*
X197925Y457467D01*
X197592Y457383D01*
X197383Y457175D01*
X197217Y456883D01*
X197175Y456592D01*
X197217Y456300D01*
X197383Y455925D01*
X196300Y456050D01*
Y457175D01*
G01X197758Y458858D02*
X197467Y459150D01*
X197300Y459400D01*
X197217Y459733D01*
X197300Y460025D01*
X197467Y460233D01*
X197717Y460400D01*
X198008Y460442D01*
X198258Y460400D01*
X198508Y460233D01*
X198717Y459983D01*
X198800Y459692D01*
X198717Y459358D01*
X198467Y459067D01*
X198092Y458900D01*
X197675Y458858D01*
X197133Y458942D01*
X196842Y459067D01*
X196550Y459275D01*
X196342Y459567D01*
X196300Y459858D01*
X196383Y460150D01*
X196592Y460358D01*
G01X196717Y461958D02*
X196467Y462208D01*
X196342Y462500D01*
X196300Y462833D01*
X196383Y463250D01*
X196592Y463542D01*
X196842Y463625D01*
X197092Y463583D01*
X197300Y463417D01*
X197717Y462583D01*
X198008Y462208D01*
X198425Y461958D01*
X198800Y461875D01*
Y463625D01*
G01X186116Y464010D02*
X182116D01*
Y456610D01*
G01X194733Y463532D02*
X190733D01*
Y456132D01*
G01X177139Y452747D02*
Y448747D01*
X184539D01*
G01X190150Y463905D02*
X186150D01*
Y456505D01*
G01X174800Y463200D02*
X170800D01*
Y455800D01*
G01X206600Y503200D02*
Y498708D01*
X195698D01*
Y493120D01*
X199463D01*
Y488503D01*
X197639D01*
Y483328D01*
G01X193021Y525790D02*
X195521D01*
G01X193021Y524832D02*
Y526748D01*
G01X195521Y528057D02*
X193021D01*
Y529057D01*
X193146Y529390D01*
X193438Y529640D01*
X193771Y529723D01*
X194104Y529640D01*
X194354Y529432D01*
X194479Y529057D01*
Y528057D01*
G01X195521Y531990D02*
X193021D01*
X193521Y531490D01*
G01X195521D02*
Y532490D01*
G01X194479Y534298D02*
X194188Y534590D01*
X194021Y534840D01*
X193938Y535173D01*
X194021Y535465D01*
X194188Y535673D01*
X194438Y535840D01*
X194729Y535882D01*
X194979Y535840D01*
X195229Y535673D01*
X195438Y535423D01*
X195521Y535132D01*
X195438Y534798D01*
X195188Y534507D01*
X194813Y534340D01*
X194396Y534298D01*
X193854Y534382D01*
X193563Y534507D01*
X193271Y534715D01*
X193063Y535007D01*
X193021Y535298D01*
X193104Y535590D01*
X193313Y535798D01*
G01X195521Y538190D02*
X193021D01*
X193521Y537690D01*
G01X195521D02*
Y538690D01*
G01X189114Y535644D02*
X191614D01*
G01X189114Y534686D02*
Y536602D01*
G01X191614Y537911D02*
X189114D01*
Y538911D01*
X189239Y539244D01*
X189531Y539494D01*
X189864Y539577D01*
X190197Y539494D01*
X190447Y539286D01*
X190572Y538911D01*
Y537911D01*
G01X191614Y541844D02*
X189114D01*
X189614Y541344D01*
G01X191614D02*
Y542344D01*
G01X190572Y544152D02*
X190281Y544444D01*
X190114Y544694D01*
X190031Y545027D01*
X190114Y545319D01*
X190281Y545527D01*
X190531Y545694D01*
X190822Y545736D01*
X191072Y545694D01*
X191322Y545527D01*
X191531Y545277D01*
X191614Y544986D01*
X191531Y544652D01*
X191281Y544361D01*
X190906Y544194D01*
X190489Y544152D01*
X189947Y544236D01*
X189656Y544361D01*
X189364Y544569D01*
X189156Y544861D01*
X189114Y545152D01*
X189197Y545444D01*
X189406Y545652D01*
G01X189531Y547252D02*
X189281Y547502D01*
X189156Y547794D01*
X189114Y548127D01*
X189197Y548544D01*
X189406Y548836D01*
X189656Y548919D01*
X189906Y548877D01*
X190114Y548711D01*
X190531Y547877D01*
X190822Y547502D01*
X191239Y547252D01*
X191614Y547169D01*
Y548919D01*
G01X189062Y517601D02*
X191562D01*
G01X189062Y516643D02*
Y518559D01*
G01X191562Y519868D02*
X189062D01*
Y520868D01*
X189187Y521201D01*
X189479Y521451D01*
X189812Y521534D01*
X190145Y521451D01*
X190395Y521243D01*
X190520Y520868D01*
Y519868D01*
G01X189479Y523009D02*
X189229Y523259D01*
X189104Y523551D01*
X189062Y523884D01*
X189145Y524301D01*
X189354Y524593D01*
X189604Y524676D01*
X189854Y524634D01*
X190062Y524468D01*
X190479Y523634D01*
X190770Y523259D01*
X191187Y523009D01*
X191562Y522926D01*
Y524676D01*
G01Y526901D02*
X189062D01*
X189562Y526401D01*
G01X191562D02*
Y527401D01*
G01X191270Y529293D02*
X191479Y529584D01*
X191562Y529918D01*
X191479Y530251D01*
X191229Y530543D01*
X190854Y530751D01*
X190479Y530834D01*
X190020D01*
X189645Y530751D01*
X189312Y530543D01*
X189145Y530293D01*
X189062Y530001D01*
X189145Y529668D01*
X189312Y529418D01*
X189562Y529251D01*
X189895Y529168D01*
X190187Y529251D01*
X190479Y529459D01*
X190645Y529709D01*
X190687Y530001D01*
X190604Y530334D01*
X190395Y530584D01*
X190020Y530834D01*
G01X180900Y567267D02*
Y564767D01*
G01X179942Y567267D02*
X181858D01*
G01X183167Y564767D02*
Y567267D01*
X184167D01*
X184500Y567142D01*
X184750Y566850D01*
X184833Y566517D01*
X184750Y566184D01*
X184542Y565934D01*
X184167Y565809D01*
X183167D01*
G01X186308Y566850D02*
X186558Y567100D01*
X186850Y567225D01*
X187183Y567267D01*
X187600Y567184D01*
X187892Y566975D01*
X187975Y566725D01*
X187933Y566475D01*
X187767Y566267D01*
X186933Y565850D01*
X186558Y565559D01*
X186308Y565142D01*
X186225Y564767D01*
X187975D01*
G01X189283Y565267D02*
X189533Y564975D01*
X189867Y564809D01*
X190242Y564767D01*
X190575Y564809D01*
X190908Y565017D01*
X191117Y565267D01*
X191158Y565517D01*
X191075Y565809D01*
X190783Y566017D01*
X190492Y566100D01*
X190117D01*
G01X190492D02*
X190742Y566225D01*
X190950Y566434D01*
X191033Y566684D01*
X190950Y566934D01*
X190742Y567142D01*
X190367Y567267D01*
X189992Y567225D01*
X189617Y567059D01*
G01X193300Y567267D02*
X192967Y567184D01*
X192717Y566975D01*
X192550Y566725D01*
X192425Y566392D01*
X192383Y566017D01*
X192425Y565642D01*
X192550Y565309D01*
X192717Y565059D01*
X192967Y564850D01*
X193300Y564767D01*
X193633Y564850D01*
X193883Y565059D01*
X194050Y565309D01*
X194175Y565642D01*
X194217Y566017D01*
X194175Y566392D01*
X194050Y566725D01*
X193883Y566975D01*
X193633Y567184D01*
X193300Y567267D01*
G01X174400Y557767D02*
Y555267D01*
G01X173442Y557767D02*
X175358D01*
G01X176667Y555267D02*
Y557767D01*
X177667D01*
X178000Y557642D01*
X178250Y557350D01*
X178333Y557017D01*
X178250Y556684D01*
X178042Y556434D01*
X177667Y556309D01*
X176667D01*
G01X179808Y557350D02*
X180058Y557600D01*
X180350Y557725D01*
X180683Y557767D01*
X181100Y557684D01*
X181392Y557475D01*
X181475Y557225D01*
X181433Y556975D01*
X181267Y556767D01*
X180433Y556350D01*
X180058Y556059D01*
X179808Y555642D01*
X179725Y555267D01*
X181475D01*
G01X182783Y555767D02*
X183033Y555475D01*
X183367Y555309D01*
X183742Y555267D01*
X184075Y555309D01*
X184408Y555517D01*
X184617Y555767D01*
X184658Y556017D01*
X184575Y556309D01*
X184283Y556517D01*
X183992Y556600D01*
X183617D01*
G01X183992D02*
X184242Y556725D01*
X184450Y556934D01*
X184533Y557184D01*
X184450Y557434D01*
X184242Y557642D01*
X183867Y557767D01*
X183492Y557725D01*
X183117Y557559D01*
G01X186008Y557350D02*
X186258Y557600D01*
X186550Y557725D01*
X186883Y557767D01*
X187300Y557684D01*
X187592Y557475D01*
X187675Y557225D01*
X187633Y556975D01*
X187467Y556767D01*
X186633Y556350D01*
X186258Y556059D01*
X186008Y555642D01*
X185925Y555267D01*
X187675D01*
G01X181400Y563267D02*
Y560767D01*
G01X180442Y563267D02*
X182358D01*
G01X183667Y560767D02*
Y563267D01*
X184667D01*
X185000Y563142D01*
X185250Y562850D01*
X185333Y562517D01*
X185250Y562184D01*
X185042Y561934D01*
X184667Y561809D01*
X183667D01*
G01X186808Y562850D02*
X187058Y563100D01*
X187350Y563225D01*
X187683Y563267D01*
X188100Y563184D01*
X188392Y562975D01*
X188475Y562725D01*
X188433Y562475D01*
X188267Y562267D01*
X187433Y561850D01*
X187058Y561559D01*
X186808Y561142D01*
X186725Y560767D01*
X188475D01*
G01X191200D02*
Y563267D01*
X189658Y561475D01*
X191742D01*
G01X193800Y563267D02*
X193467Y563184D01*
X193217Y562975D01*
X193050Y562725D01*
X192925Y562392D01*
X192883Y562017D01*
X192925Y561642D01*
X193050Y561309D01*
X193217Y561059D01*
X193467Y560850D01*
X193800Y560767D01*
X194133Y560850D01*
X194383Y561059D01*
X194550Y561309D01*
X194675Y561642D01*
X194717Y562017D01*
X194675Y562392D01*
X194550Y562725D01*
X194383Y562975D01*
X194133Y563184D01*
X193800Y563267D01*
G01X190643Y552856D02*
Y555356D01*
X191684D01*
X192018Y555231D01*
X192226Y555064D01*
X192309Y554731D01*
X192226Y554398D01*
X191976Y554189D01*
X191684Y554064D01*
X190643D01*
G01X191684D02*
X192309Y552856D01*
G01X194576D02*
Y555356D01*
X194076Y554856D01*
G01Y552856D02*
X195076D01*
G01X196759Y553231D02*
X197009Y553023D01*
X197301Y552898D01*
X197676Y552856D01*
X198051Y552939D01*
X198343Y553106D01*
X198551Y553398D01*
X198593Y553731D01*
X198509Y554064D01*
X198301Y554273D01*
X198009Y554439D01*
X197718Y554481D01*
X197426Y554439D01*
X197051Y554273D01*
X197176Y555356D01*
X198301D01*
G01X200776D02*
X200443Y555273D01*
X200193Y555064D01*
X200026Y554814D01*
X199901Y554481D01*
X199859Y554106D01*
X199901Y553731D01*
X200026Y553398D01*
X200193Y553148D01*
X200443Y552939D01*
X200776Y552856D01*
X201109Y552939D01*
X201359Y553148D01*
X201526Y553398D01*
X201651Y553731D01*
X201693Y554106D01*
X201651Y554481D01*
X201526Y554814D01*
X201359Y555064D01*
X201109Y555273D01*
X200776Y555356D01*
G01X191502Y557196D02*
X191835Y556988D01*
X192210Y556863D01*
X192544D01*
X192877Y556988D01*
X193127Y557196D01*
X193252Y557488D01*
X193169Y557780D01*
X192960Y558030D01*
X192585Y558196D01*
X192085Y558280D01*
X191794Y558446D01*
X191669Y558738D01*
X191752Y559030D01*
X191960Y559238D01*
X192252Y559363D01*
X192544D01*
X192835Y559280D01*
X193085Y559071D01*
G01X194644Y556863D02*
Y559363D01*
X195685D01*
X196019Y559238D01*
X196227Y559071D01*
X196310Y558738D01*
X196227Y558405D01*
X195977Y558196D01*
X195685Y558071D01*
X194644D01*
G01X195685D02*
X196310Y556863D01*
G01X197869Y557155D02*
X198160Y556946D01*
X198494Y556863D01*
X198827Y556946D01*
X199119Y557196D01*
X199327Y557571D01*
X199410Y557946D01*
Y558405D01*
X199327Y558780D01*
X199119Y559113D01*
X198869Y559280D01*
X198577Y559363D01*
X198244Y559280D01*
X197994Y559113D01*
X197827Y558863D01*
X197744Y558530D01*
X197827Y558238D01*
X198035Y557946D01*
X198285Y557780D01*
X198577Y557738D01*
X198910Y557821D01*
X199160Y558030D01*
X199410Y558405D01*
G01X202177Y556863D02*
Y559363D01*
X200635Y557571D01*
X202719D01*
G01X205277Y556863D02*
Y559363D01*
X203735Y557571D01*
X205819D01*
G01X183500Y568800D02*
X187500D01*
Y576200D01*
G01X169500Y574517D02*
X167000D01*
Y575558D01*
X167125Y575892D01*
X167292Y576100D01*
X167625Y576183D01*
X167958Y576100D01*
X168167Y575850D01*
X168292Y575558D01*
Y574517D01*
G01Y575558D02*
X169500Y576183D01*
G01X167417Y577658D02*
X167167Y577908D01*
X167042Y578200D01*
X167000Y578533D01*
X167083Y578950D01*
X167292Y579242D01*
X167542Y579325D01*
X167792Y579283D01*
X168000Y579117D01*
X168417Y578283D01*
X168708Y577908D01*
X169125Y577658D01*
X169500Y577575D01*
Y579325D01*
G01X167417Y580758D02*
X167167Y581008D01*
X167042Y581300D01*
X167000Y581633D01*
X167083Y582050D01*
X167292Y582342D01*
X167542Y582425D01*
X167792Y582383D01*
X168000Y582217D01*
X168417Y581383D01*
X168708Y581008D01*
X169125Y580758D01*
X169500Y580675D01*
Y582425D01*
G01X169208Y583942D02*
X169417Y584233D01*
X169500Y584567D01*
X169417Y584900D01*
X169167Y585192D01*
X168792Y585400D01*
X168417Y585483D01*
X167958D01*
X167583Y585400D01*
X167250Y585192D01*
X167083Y584942D01*
X167000Y584650D01*
X167083Y584317D01*
X167250Y584067D01*
X167500Y583900D01*
X167833Y583817D01*
X168125Y583900D01*
X168417Y584108D01*
X168583Y584358D01*
X168625Y584650D01*
X168542Y584983D01*
X168333Y585233D01*
X167958Y585483D01*
G01X187500Y568800D02*
X191500D01*
Y576200D01*
G01X185167Y578925D02*
X185375Y579258D01*
X185500Y579633D01*
Y579967D01*
X185375Y580300D01*
X185167Y580550D01*
X184875Y580675D01*
X184583Y580592D01*
X184333Y580383D01*
X184167Y580008D01*
X184083Y579508D01*
X183917Y579217D01*
X183625Y579092D01*
X183333Y579175D01*
X183125Y579383D01*
X183000Y579675D01*
Y579967D01*
X183083Y580258D01*
X183292Y580508D01*
G01X185500Y582067D02*
X183000D01*
Y583108D01*
X183125Y583442D01*
X183292Y583650D01*
X183625Y583733D01*
X183958Y583650D01*
X184167Y583400D01*
X184292Y583108D01*
Y582067D01*
G01Y583108D02*
X185500Y583733D01*
G01Y586000D02*
X185458Y586292D01*
X185333Y586625D01*
X185125Y586833D01*
X184833Y586917D01*
X184542Y586833D01*
X184292Y586583D01*
X184167Y586208D01*
Y585792D01*
X184083Y585542D01*
X183875Y585333D01*
X183583Y585250D01*
X183292Y585375D01*
X183083Y585667D01*
X183000Y586000D01*
X183083Y586333D01*
X183292Y586625D01*
X183583Y586750D01*
X183875Y586667D01*
X184083Y586458D01*
X184167Y586208D01*
Y585792D01*
X184292Y585417D01*
X184542Y585167D01*
X184833Y585083D01*
X185125Y585167D01*
X185333Y585375D01*
X185458Y585708D01*
X185500Y586000D01*
G01X185125Y588183D02*
X185333Y588433D01*
X185458Y588725D01*
X185500Y589100D01*
X185417Y589475D01*
X185250Y589767D01*
X184958Y589975D01*
X184625Y590017D01*
X184292Y589933D01*
X184083Y589725D01*
X183917Y589433D01*
X183875Y589142D01*
X183917Y588850D01*
X184083Y588475D01*
X183000Y588600D01*
Y589725D01*
G01X185000Y591283D02*
X185292Y591533D01*
X185458Y591867D01*
X185500Y592242D01*
X185458Y592575D01*
X185250Y592908D01*
X185000Y593117D01*
X184750Y593158D01*
X184458Y593075D01*
X184250Y592783D01*
X184167Y592492D01*
Y592117D01*
G01Y592492D02*
X184042Y592742D01*
X183833Y592950D01*
X183583Y593033D01*
X183333Y592950D01*
X183125Y592742D01*
X183000Y592367D01*
X183042Y591992D01*
X183208Y591617D01*
G01X199500Y575732D02*
X195500D01*
Y568332D01*
G01X187975Y607659D02*
Y605159D01*
G01X187017Y607659D02*
X188933D01*
G01X190242Y605159D02*
Y607659D01*
X191242D01*
X191575Y607534D01*
X191825Y607242D01*
X191908Y606909D01*
X191825Y606576D01*
X191617Y606326D01*
X191242Y606201D01*
X190242D01*
G01X193258Y605659D02*
X193508Y605367D01*
X193842Y605201D01*
X194217Y605159D01*
X194550Y605201D01*
X194883Y605409D01*
X195092Y605659D01*
X195133Y605909D01*
X195050Y606201D01*
X194758Y606409D01*
X194467Y606492D01*
X194092D01*
G01X194467D02*
X194717Y606617D01*
X194925Y606826D01*
X195008Y607076D01*
X194925Y607326D01*
X194717Y607534D01*
X194342Y607659D01*
X193967Y607617D01*
X193592Y607451D01*
G01X196483Y607242D02*
X196733Y607492D01*
X197025Y607617D01*
X197358Y607659D01*
X197775Y607576D01*
X198067Y607367D01*
X198150Y607117D01*
X198108Y606867D01*
X197942Y606659D01*
X197108Y606242D01*
X196733Y605951D01*
X196483Y605534D01*
X196400Y605159D01*
X198150D01*
G01X200375Y607659D02*
X200042Y607576D01*
X199792Y607367D01*
X199625Y607117D01*
X199500Y606784D01*
X199458Y606409D01*
X199500Y606034D01*
X199625Y605701D01*
X199792Y605451D01*
X200042Y605242D01*
X200375Y605159D01*
X200708Y605242D01*
X200958Y605451D01*
X201125Y605701D01*
X201250Y606034D01*
X201292Y606409D01*
X201250Y606784D01*
X201125Y607117D01*
X200958Y607367D01*
X200708Y607576D01*
X200375Y607659D01*
G01X193500Y596300D02*
X197500D01*
Y603700D01*
G01X189500Y588800D02*
X193500D01*
Y596200D01*
G01Y603700D02*
X189500D01*
Y596300D01*
G01X197500Y596200D02*
X193500D01*
Y588800D01*
G01X193000Y609780D02*
X190500D01*
Y610821D01*
X190625Y611155D01*
X190792Y611363D01*
X191125Y611446D01*
X191458Y611363D01*
X191667Y611113D01*
X191792Y610821D01*
Y609780D01*
G01Y610821D02*
X193000Y611446D01*
G01X192625Y612796D02*
X192833Y613046D01*
X192958Y613338D01*
X193000Y613713D01*
X192917Y614088D01*
X192750Y614380D01*
X192458Y614588D01*
X192125Y614630D01*
X191792Y614546D01*
X191583Y614338D01*
X191417Y614046D01*
X191375Y613755D01*
X191417Y613463D01*
X191583Y613088D01*
X190500Y613213D01*
Y614338D01*
G01X193000Y616813D02*
X192958Y617105D01*
X192833Y617438D01*
X192625Y617646D01*
X192333Y617730D01*
X192042Y617646D01*
X191792Y617396D01*
X191667Y617021D01*
Y616605D01*
X191583Y616355D01*
X191375Y616146D01*
X191083Y616063D01*
X190792Y616188D01*
X190583Y616480D01*
X190500Y616813D01*
X190583Y617146D01*
X190792Y617438D01*
X191083Y617563D01*
X191375Y617480D01*
X191583Y617271D01*
X191667Y617021D01*
Y616605D01*
X191792Y616230D01*
X192042Y615980D01*
X192333Y615896D01*
X192625Y615980D01*
X192833Y616188D01*
X192958Y616521D01*
X193000Y616813D01*
G01X192708Y619205D02*
X192917Y619496D01*
X193000Y619830D01*
X192917Y620163D01*
X192667Y620455D01*
X192292Y620663D01*
X191917Y620746D01*
X191458D01*
X191083Y620663D01*
X190750Y620455D01*
X190583Y620205D01*
X190500Y619913D01*
X190583Y619580D01*
X190750Y619330D01*
X191000Y619163D01*
X191333Y619080D01*
X191625Y619163D01*
X191917Y619371D01*
X192083Y619621D01*
X192125Y619913D01*
X192042Y620246D01*
X191833Y620496D01*
X191458Y620746D01*
G01X189500Y581300D02*
X193500D01*
Y588700D01*
G01X197000Y609780D02*
X194500D01*
Y610821D01*
X194625Y611155D01*
X194792Y611363D01*
X195125Y611446D01*
X195458Y611363D01*
X195667Y611113D01*
X195792Y610821D01*
Y609780D01*
G01Y610821D02*
X197000Y611446D01*
G01X196625Y612796D02*
X196833Y613046D01*
X196958Y613338D01*
X197000Y613713D01*
X196917Y614088D01*
X196750Y614380D01*
X196458Y614588D01*
X196125Y614630D01*
X195792Y614546D01*
X195583Y614338D01*
X195417Y614046D01*
X195375Y613755D01*
X195417Y613463D01*
X195583Y613088D01*
X194500Y613213D01*
Y614338D01*
G01X196708Y616105D02*
X196917Y616396D01*
X197000Y616730D01*
X196917Y617063D01*
X196667Y617355D01*
X196292Y617563D01*
X195917Y617646D01*
X195458D01*
X195083Y617563D01*
X194750Y617355D01*
X194583Y617105D01*
X194500Y616813D01*
X194583Y616480D01*
X194750Y616230D01*
X195000Y616063D01*
X195333Y615980D01*
X195625Y616063D01*
X195917Y616271D01*
X196083Y616521D01*
X196125Y616813D01*
X196042Y617146D01*
X195833Y617396D01*
X195458Y617646D01*
G01X194500Y619913D02*
X194583Y619580D01*
X194792Y619330D01*
X195042Y619163D01*
X195375Y619038D01*
X195750Y618996D01*
X196125Y619038D01*
X196458Y619163D01*
X196708Y619330D01*
X196917Y619580D01*
X197000Y619913D01*
X196917Y620246D01*
X196708Y620496D01*
X196458Y620663D01*
X196125Y620788D01*
X195750Y620830D01*
X195375Y620788D01*
X195042Y620663D01*
X194792Y620496D01*
X194583Y620246D01*
X194500Y619913D01*
G01X197500Y588700D02*
X193500D01*
Y581300D01*
G01X177240Y603492D02*
X177115Y603242D01*
X177032Y602950D01*
Y602617D01*
X177157Y602242D01*
X177365Y601950D01*
X177615Y601742D01*
X178032Y601575D01*
X178407Y601533D01*
X178782Y601617D01*
X179032Y601742D01*
X179282Y601992D01*
X179449Y602283D01*
X179532Y602575D01*
Y602867D01*
X179449Y603158D01*
X179324Y603408D01*
X179157Y603617D01*
G01X177449Y604883D02*
X177199Y605133D01*
X177074Y605425D01*
X177032Y605758D01*
X177115Y606175D01*
X177324Y606467D01*
X177574Y606550D01*
X177824Y606508D01*
X178032Y606342D01*
X178449Y605508D01*
X178740Y605133D01*
X179157Y604883D01*
X179532Y604800D01*
Y606550D01*
G01X177032Y608775D02*
X177115Y608442D01*
X177324Y608192D01*
X177574Y608025D01*
X177907Y607900D01*
X178282Y607858D01*
X178657Y607900D01*
X178990Y608025D01*
X179240Y608192D01*
X179449Y608442D01*
X179532Y608775D01*
X179449Y609108D01*
X179240Y609358D01*
X178990Y609525D01*
X178657Y609650D01*
X178282Y609692D01*
X177907Y609650D01*
X177574Y609525D01*
X177324Y609358D01*
X177115Y609108D01*
X177032Y608775D01*
G01Y611875D02*
X177115Y611542D01*
X177324Y611292D01*
X177574Y611125D01*
X177907Y611000D01*
X178282Y610958D01*
X178657Y611000D01*
X178990Y611125D01*
X179240Y611292D01*
X179449Y611542D01*
X179532Y611875D01*
X179449Y612208D01*
X179240Y612458D01*
X178990Y612625D01*
X178657Y612750D01*
X178282Y612792D01*
X177907Y612750D01*
X177574Y612625D01*
X177324Y612458D01*
X177115Y612208D01*
X177032Y611875D01*
G01X197000Y636280D02*
X194500D01*
Y637321D01*
X194625Y637655D01*
X194792Y637863D01*
X195125Y637946D01*
X195458Y637863D01*
X195667Y637613D01*
X195792Y637321D01*
Y636280D01*
G01Y637321D02*
X197000Y637946D01*
G01Y640213D02*
X194500D01*
X195000Y639713D01*
G01X197000D02*
Y640713D01*
G01X195958Y642521D02*
X195667Y642813D01*
X195500Y643063D01*
X195417Y643396D01*
X195500Y643688D01*
X195667Y643896D01*
X195917Y644063D01*
X196208Y644105D01*
X196458Y644063D01*
X196708Y643896D01*
X196917Y643646D01*
X197000Y643355D01*
X196917Y643021D01*
X196667Y642730D01*
X196292Y642563D01*
X195875Y642521D01*
X195333Y642605D01*
X195042Y642730D01*
X194750Y642938D01*
X194542Y643230D01*
X194500Y643521D01*
X194583Y643813D01*
X194792Y644021D01*
G01X194500Y646413D02*
X194583Y646080D01*
X194792Y645830D01*
X195042Y645663D01*
X195375Y645538D01*
X195750Y645496D01*
X196125Y645538D01*
X196458Y645663D01*
X196708Y645830D01*
X196917Y646080D01*
X197000Y646413D01*
X196917Y646746D01*
X196708Y646996D01*
X196458Y647163D01*
X196125Y647288D01*
X195750Y647330D01*
X195375Y647288D01*
X195042Y647163D01*
X194792Y646996D01*
X194583Y646746D01*
X194500Y646413D01*
G01X193000Y623280D02*
X190500D01*
Y624321D01*
X190625Y624655D01*
X190792Y624863D01*
X191125Y624946D01*
X191458Y624863D01*
X191667Y624613D01*
X191792Y624321D01*
Y623280D01*
G01Y624321D02*
X193000Y624946D01*
G01Y627213D02*
X190500D01*
X191000Y626713D01*
G01X193000D02*
Y627713D01*
G01X191958Y629521D02*
X191667Y629813D01*
X191500Y630063D01*
X191417Y630396D01*
X191500Y630688D01*
X191667Y630896D01*
X191917Y631063D01*
X192208Y631105D01*
X192458Y631063D01*
X192708Y630896D01*
X192917Y630646D01*
X193000Y630355D01*
X192917Y630021D01*
X192667Y629730D01*
X192292Y629563D01*
X191875Y629521D01*
X191333Y629605D01*
X191042Y629730D01*
X190750Y629938D01*
X190542Y630230D01*
X190500Y630521D01*
X190583Y630813D01*
X190792Y631021D01*
G01X193000Y633413D02*
X190500D01*
X191000Y632913D01*
G01X193000D02*
Y633913D01*
G01Y636280D02*
X190500D01*
Y637321D01*
X190625Y637655D01*
X190792Y637863D01*
X191125Y637946D01*
X191458Y637863D01*
X191667Y637613D01*
X191792Y637321D01*
Y636280D01*
G01Y637321D02*
X193000Y637946D01*
G01Y640213D02*
X190500D01*
X191000Y639713D01*
G01X193000D02*
Y640713D01*
G01X191958Y642521D02*
X191667Y642813D01*
X191500Y643063D01*
X191417Y643396D01*
X191500Y643688D01*
X191667Y643896D01*
X191917Y644063D01*
X192208Y644105D01*
X192458Y644063D01*
X192708Y643896D01*
X192917Y643646D01*
X193000Y643355D01*
X192917Y643021D01*
X192667Y642730D01*
X192292Y642563D01*
X191875Y642521D01*
X191333Y642605D01*
X191042Y642730D01*
X190750Y642938D01*
X190542Y643230D01*
X190500Y643521D01*
X190583Y643813D01*
X190792Y644021D01*
G01X193000Y646913D02*
X190500D01*
X192292Y645371D01*
Y647455D01*
G01X197000Y623280D02*
X194500D01*
Y624321D01*
X194625Y624655D01*
X194792Y624863D01*
X195125Y624946D01*
X195458Y624863D01*
X195667Y624613D01*
X195792Y624321D01*
Y623280D01*
G01Y624321D02*
X197000Y624946D01*
G01Y627213D02*
X194500D01*
X195000Y626713D01*
G01X197000D02*
Y627713D01*
G01X195958Y629521D02*
X195667Y629813D01*
X195500Y630063D01*
X195417Y630396D01*
X195500Y630688D01*
X195667Y630896D01*
X195917Y631063D01*
X196208Y631105D01*
X196458Y631063D01*
X196708Y630896D01*
X196917Y630646D01*
X197000Y630355D01*
X196917Y630021D01*
X196667Y629730D01*
X196292Y629563D01*
X195875Y629521D01*
X195333Y629605D01*
X195042Y629730D01*
X194750Y629938D01*
X194542Y630230D01*
X194500Y630521D01*
X194583Y630813D01*
X194792Y631021D01*
G01X196625Y632496D02*
X196833Y632746D01*
X196958Y633038D01*
X197000Y633413D01*
X196917Y633788D01*
X196750Y634080D01*
X196458Y634288D01*
X196125Y634330D01*
X195792Y634246D01*
X195583Y634038D01*
X195417Y633746D01*
X195375Y633455D01*
X195417Y633163D01*
X195583Y632788D01*
X194500Y632913D01*
Y634038D01*
G01X200278Y674912D02*
X197778D01*
Y675953D01*
X197903Y676287D01*
X198070Y676495D01*
X198403Y676578D01*
X198736Y676495D01*
X198945Y676245D01*
X199070Y675953D01*
Y674912D01*
G01Y675953D02*
X200278Y676578D01*
G01Y678845D02*
X200236Y679137D01*
X200111Y679470D01*
X199903Y679678D01*
X199611Y679762D01*
X199320Y679678D01*
X199070Y679428D01*
X198945Y679053D01*
Y678637D01*
X198861Y678387D01*
X198653Y678178D01*
X198361Y678095D01*
X198070Y678220D01*
X197861Y678512D01*
X197778Y678845D01*
X197861Y679178D01*
X198070Y679470D01*
X198361Y679595D01*
X198653Y679512D01*
X198861Y679303D01*
X198945Y679053D01*
Y678637D01*
X199070Y678262D01*
X199320Y678012D01*
X199611Y677928D01*
X199903Y678012D01*
X200111Y678220D01*
X200236Y678553D01*
X200278Y678845D01*
G01X199986Y681237D02*
X200195Y681528D01*
X200278Y681862D01*
X200195Y682195D01*
X199945Y682487D01*
X199570Y682695D01*
X199195Y682778D01*
X198736D01*
X198361Y682695D01*
X198028Y682487D01*
X197861Y682237D01*
X197778Y681945D01*
X197861Y681612D01*
X198028Y681362D01*
X198278Y681195D01*
X198611Y681112D01*
X198903Y681195D01*
X199195Y681403D01*
X199361Y681653D01*
X199403Y681945D01*
X199320Y682278D01*
X199111Y682528D01*
X198736Y682778D01*
G01X199986Y684337D02*
X200195Y684628D01*
X200278Y684962D01*
X200195Y685295D01*
X199945Y685587D01*
X199570Y685795D01*
X199195Y685878D01*
X198736D01*
X198361Y685795D01*
X198028Y685587D01*
X197861Y685337D01*
X197778Y685045D01*
X197861Y684712D01*
X198028Y684462D01*
X198278Y684295D01*
X198611Y684212D01*
X198903Y684295D01*
X199195Y684503D01*
X199361Y684753D01*
X199403Y685045D01*
X199320Y685378D01*
X199111Y685628D01*
X198736Y685878D01*
G01X197500Y706900D02*
Y718800D01*
G01X205500Y706900D02*
X197500D01*
G01X191063Y689786D02*
X190813Y689911D01*
X190521Y689994D01*
X190188D01*
X189813Y689869D01*
X189521Y689661D01*
X189313Y689411D01*
X189146Y688994D01*
X189104Y688619D01*
X189188Y688244D01*
X189313Y687994D01*
X189563Y687744D01*
X189854Y687577D01*
X190146Y687494D01*
X190438D01*
X190729Y687577D01*
X190979Y687702D01*
X191188Y687869D01*
G01X193163Y687494D02*
X193246Y688036D01*
X193371Y688494D01*
X193538Y688911D01*
X193746Y689369D01*
X194079Y689994D01*
X192413D01*
G01X196346D02*
X196013Y689911D01*
X195763Y689702D01*
X195596Y689452D01*
X195471Y689119D01*
X195429Y688744D01*
X195471Y688369D01*
X195596Y688036D01*
X195763Y687786D01*
X196013Y687577D01*
X196346Y687494D01*
X196679Y687577D01*
X196929Y687786D01*
X197096Y688036D01*
X197221Y688369D01*
X197263Y688744D01*
X197221Y689119D01*
X197096Y689452D01*
X196929Y689702D01*
X196679Y689911D01*
X196346Y689994D01*
G01X198738Y687786D02*
X199029Y687577D01*
X199363Y687494D01*
X199696Y687577D01*
X199988Y687827D01*
X200196Y688202D01*
X200279Y688577D01*
Y689036D01*
X200196Y689411D01*
X199988Y689744D01*
X199738Y689911D01*
X199446Y689994D01*
X199113Y689911D01*
X198863Y689744D01*
X198696Y689494D01*
X198613Y689161D01*
X198696Y688869D01*
X198904Y688577D01*
X199154Y688411D01*
X199446Y688369D01*
X199779Y688452D01*
X200029Y688661D01*
X200279Y689036D01*
G01X171212Y713942D02*
X170962Y714067D01*
X170670Y714150D01*
X170337D01*
X169962Y714025D01*
X169670Y713817D01*
X169462Y713567D01*
X169295Y713150D01*
X169253Y712775D01*
X169337Y712400D01*
X169462Y712150D01*
X169712Y711900D01*
X170003Y711733D01*
X170295Y711650D01*
X170587D01*
X170878Y711733D01*
X171128Y711858D01*
X171337Y712025D01*
G01X172603Y712692D02*
X172895Y712983D01*
X173145Y713150D01*
X173478Y713233D01*
X173770Y713150D01*
X173978Y712983D01*
X174145Y712733D01*
X174187Y712442D01*
X174145Y712192D01*
X173978Y711942D01*
X173728Y711733D01*
X173437Y711650D01*
X173103Y711733D01*
X172812Y711983D01*
X172645Y712358D01*
X172603Y712775D01*
X172687Y713317D01*
X172812Y713608D01*
X173020Y713900D01*
X173312Y714108D01*
X173603Y714150D01*
X173895Y714067D01*
X174103Y713858D01*
G01X176495Y711650D02*
X176787Y711692D01*
X177120Y711817D01*
X177328Y712025D01*
X177412Y712317D01*
X177328Y712608D01*
X177078Y712858D01*
X176703Y712983D01*
X176287D01*
X176037Y713067D01*
X175828Y713275D01*
X175745Y713567D01*
X175870Y713858D01*
X176162Y714067D01*
X176495Y714150D01*
X176828Y714067D01*
X177120Y713858D01*
X177245Y713567D01*
X177162Y713275D01*
X176953Y713067D01*
X176703Y712983D01*
X176287D01*
X175912Y712858D01*
X175662Y712608D01*
X175578Y712317D01*
X175662Y712025D01*
X175870Y711817D01*
X176203Y711692D01*
X176495Y711650D01*
G01X178887Y711942D02*
X179178Y711733D01*
X179512Y711650D01*
X179845Y711733D01*
X180137Y711983D01*
X180345Y712358D01*
X180428Y712733D01*
Y713192D01*
X180345Y713567D01*
X180137Y713900D01*
X179887Y714067D01*
X179595Y714150D01*
X179262Y714067D01*
X179012Y713900D01*
X178845Y713650D01*
X178762Y713317D01*
X178845Y713025D01*
X179053Y712733D01*
X179303Y712567D01*
X179595Y712525D01*
X179928Y712608D01*
X180178Y712817D01*
X180428Y713192D01*
G01X201500Y701200D02*
X197500D01*
Y693800D01*
G01X184000Y714800D02*
X188000D01*
Y722200D01*
G01X172811Y698379D02*
X170311D01*
Y699420D01*
X170436Y699754D01*
X170603Y699962D01*
X170936Y700045D01*
X171269Y699962D01*
X171478Y699712D01*
X171603Y699420D01*
Y698379D01*
G01Y699420D02*
X172811Y700045D01*
G01Y702312D02*
X172769Y702604D01*
X172644Y702937D01*
X172436Y703145D01*
X172144Y703229D01*
X171853Y703145D01*
X171603Y702895D01*
X171478Y702520D01*
Y702104D01*
X171394Y701854D01*
X171186Y701645D01*
X170894Y701562D01*
X170603Y701687D01*
X170394Y701979D01*
X170311Y702312D01*
X170394Y702645D01*
X170603Y702937D01*
X170894Y703062D01*
X171186Y702979D01*
X171394Y702770D01*
X171478Y702520D01*
Y702104D01*
X171603Y701729D01*
X171853Y701479D01*
X172144Y701395D01*
X172436Y701479D01*
X172644Y701687D01*
X172769Y702020D01*
X172811Y702312D01*
G01X171769Y704620D02*
X171478Y704912D01*
X171311Y705162D01*
X171228Y705495D01*
X171311Y705787D01*
X171478Y705995D01*
X171728Y706162D01*
X172019Y706204D01*
X172269Y706162D01*
X172519Y705995D01*
X172728Y705745D01*
X172811Y705454D01*
X172728Y705120D01*
X172478Y704829D01*
X172103Y704662D01*
X171686Y704620D01*
X171144Y704704D01*
X170853Y704829D01*
X170561Y705037D01*
X170353Y705329D01*
X170311Y705620D01*
X170394Y705912D01*
X170603Y706120D01*
G01X172811Y708429D02*
X172269Y708512D01*
X171811Y708637D01*
X171394Y708804D01*
X170936Y709012D01*
X170311Y709345D01*
Y707679D01*
G01X168811Y698379D02*
X166311D01*
Y699420D01*
X166436Y699754D01*
X166603Y699962D01*
X166936Y700045D01*
X167269Y699962D01*
X167478Y699712D01*
X167603Y699420D01*
Y698379D01*
G01Y699420D02*
X168811Y700045D01*
G01Y702312D02*
X168769Y702604D01*
X168644Y702937D01*
X168436Y703145D01*
X168144Y703229D01*
X167853Y703145D01*
X167603Y702895D01*
X167478Y702520D01*
Y702104D01*
X167394Y701854D01*
X167186Y701645D01*
X166894Y701562D01*
X166603Y701687D01*
X166394Y701979D01*
X166311Y702312D01*
X166394Y702645D01*
X166603Y702937D01*
X166894Y703062D01*
X167186Y702979D01*
X167394Y702770D01*
X167478Y702520D01*
Y702104D01*
X167603Y701729D01*
X167853Y701479D01*
X168144Y701395D01*
X168436Y701479D01*
X168644Y701687D01*
X168769Y702020D01*
X168811Y702312D01*
G01X167769Y704620D02*
X167478Y704912D01*
X167311Y705162D01*
X167228Y705495D01*
X167311Y705787D01*
X167478Y705995D01*
X167728Y706162D01*
X168019Y706204D01*
X168269Y706162D01*
X168519Y705995D01*
X168728Y705745D01*
X168811Y705454D01*
X168728Y705120D01*
X168478Y704829D01*
X168103Y704662D01*
X167686Y704620D01*
X167144Y704704D01*
X166853Y704829D01*
X166561Y705037D01*
X166353Y705329D01*
X166311Y705620D01*
X166394Y705912D01*
X166603Y706120D01*
G01X168436Y707595D02*
X168644Y707845D01*
X168769Y708137D01*
X168811Y708512D01*
X168728Y708887D01*
X168561Y709179D01*
X168269Y709387D01*
X167936Y709429D01*
X167603Y709345D01*
X167394Y709137D01*
X167228Y708845D01*
X167186Y708554D01*
X167228Y708262D01*
X167394Y707887D01*
X166311Y708012D01*
Y709137D01*
G01X184465Y694501D02*
X184340Y694251D01*
X184257Y693959D01*
Y693626D01*
X184382Y693251D01*
X184590Y692959D01*
X184840Y692751D01*
X185257Y692584D01*
X185632Y692542D01*
X186007Y692626D01*
X186257Y692751D01*
X186507Y693001D01*
X186674Y693292D01*
X186757Y693584D01*
Y693876D01*
X186674Y694167D01*
X186549Y694417D01*
X186382Y694626D01*
G01X184674Y695892D02*
X184424Y696142D01*
X184299Y696434D01*
X184257Y696767D01*
X184340Y697184D01*
X184549Y697476D01*
X184799Y697559D01*
X185049Y697517D01*
X185257Y697351D01*
X185674Y696517D01*
X185965Y696142D01*
X186382Y695892D01*
X186757Y695809D01*
Y697559D01*
G01X185715Y698992D02*
X185424Y699284D01*
X185257Y699534D01*
X185174Y699867D01*
X185257Y700159D01*
X185424Y700367D01*
X185674Y700534D01*
X185965Y700576D01*
X186215Y700534D01*
X186465Y700367D01*
X186674Y700117D01*
X186757Y699826D01*
X186674Y699492D01*
X186424Y699201D01*
X186049Y699034D01*
X185632Y698992D01*
X185090Y699076D01*
X184799Y699201D01*
X184507Y699409D01*
X184299Y699701D01*
X184257Y699992D01*
X184340Y700284D01*
X184549Y700492D01*
G01X186382Y701967D02*
X186590Y702217D01*
X186715Y702509D01*
X186757Y702884D01*
X186674Y703259D01*
X186507Y703551D01*
X186215Y703759D01*
X185882Y703801D01*
X185549Y703717D01*
X185340Y703509D01*
X185174Y703217D01*
X185132Y702926D01*
X185174Y702634D01*
X185340Y702259D01*
X184257Y702384D01*
Y703509D01*
G01X180465Y694501D02*
X180340Y694251D01*
X180257Y693959D01*
Y693626D01*
X180382Y693251D01*
X180590Y692959D01*
X180840Y692751D01*
X181257Y692584D01*
X181632Y692542D01*
X182007Y692626D01*
X182257Y692751D01*
X182507Y693001D01*
X182674Y693292D01*
X182757Y693584D01*
Y693876D01*
X182674Y694167D01*
X182549Y694417D01*
X182382Y694626D01*
G01X180674Y695892D02*
X180424Y696142D01*
X180299Y696434D01*
X180257Y696767D01*
X180340Y697184D01*
X180549Y697476D01*
X180799Y697559D01*
X181049Y697517D01*
X181257Y697351D01*
X181674Y696517D01*
X181965Y696142D01*
X182382Y695892D01*
X182757Y695809D01*
Y697559D01*
G01X182382Y698867D02*
X182590Y699117D01*
X182715Y699409D01*
X182757Y699784D01*
X182674Y700159D01*
X182507Y700451D01*
X182215Y700659D01*
X181882Y700701D01*
X181549Y700617D01*
X181340Y700409D01*
X181174Y700117D01*
X181132Y699826D01*
X181174Y699534D01*
X181340Y699159D01*
X180257Y699284D01*
Y700409D01*
G01X182257Y701967D02*
X182549Y702217D01*
X182715Y702551D01*
X182757Y702926D01*
X182715Y703259D01*
X182507Y703592D01*
X182257Y703801D01*
X182007Y703842D01*
X181715Y703759D01*
X181507Y703467D01*
X181424Y703176D01*
Y702801D01*
G01Y703176D02*
X181299Y703426D01*
X181090Y703634D01*
X180840Y703717D01*
X180590Y703634D01*
X180382Y703426D01*
X180257Y703051D01*
X180299Y702676D01*
X180465Y702301D01*
G01X197500Y718800D02*
X205500D01*
G01X182483Y748667D02*
Y746875D01*
X182650Y746500D01*
X182983Y746250D01*
X183400Y746167D01*
X183817Y746250D01*
X184150Y746500D01*
X184317Y746875D01*
Y748667D01*
G01X185708Y748250D02*
X185958Y748500D01*
X186250Y748625D01*
X186583Y748667D01*
X187000Y748584D01*
X187292Y748375D01*
X187375Y748125D01*
X187333Y747875D01*
X187167Y747667D01*
X186333Y747250D01*
X185958Y746959D01*
X185708Y746542D01*
X185625Y746167D01*
X187375D01*
G01X188892Y746459D02*
X189183Y746250D01*
X189517Y746167D01*
X189850Y746250D01*
X190142Y746500D01*
X190350Y746875D01*
X190433Y747250D01*
Y747709D01*
X190350Y748084D01*
X190142Y748417D01*
X189892Y748584D01*
X189600Y748667D01*
X189267Y748584D01*
X189017Y748417D01*
X188850Y748167D01*
X188767Y747834D01*
X188850Y747542D01*
X189058Y747250D01*
X189308Y747084D01*
X189600Y747042D01*
X189933Y747125D01*
X190183Y747334D01*
X190433Y747709D01*
G01X173200Y742700D02*
Y730800D01*
G01X165200Y742700D02*
X173200D01*
G01X165200Y730800D02*
Y742700D01*
G01X173200Y730800D02*
X165200D01*
G01X169200Y732400D02*
X167600Y730800D01*
G01X169200Y732400D02*
X170800Y730800D01*
G01X182767Y751959D02*
X182517Y752084D01*
X182225Y752167D01*
X181892D01*
X181517Y752042D01*
X181225Y751834D01*
X181017Y751584D01*
X180850Y751167D01*
X180808Y750792D01*
X180892Y750417D01*
X181017Y750167D01*
X181267Y749917D01*
X181558Y749750D01*
X181850Y749667D01*
X182142D01*
X182433Y749750D01*
X182683Y749875D01*
X182892Y750042D01*
G01X184158Y750709D02*
X184450Y751000D01*
X184700Y751167D01*
X185033Y751250D01*
X185325Y751167D01*
X185533Y751000D01*
X185700Y750750D01*
X185742Y750459D01*
X185700Y750209D01*
X185533Y749959D01*
X185283Y749750D01*
X184992Y749667D01*
X184658Y749750D01*
X184367Y750000D01*
X184200Y750375D01*
X184158Y750792D01*
X184242Y751334D01*
X184367Y751625D01*
X184575Y751917D01*
X184867Y752125D01*
X185158Y752167D01*
X185450Y752084D01*
X185658Y751875D01*
G01X187342Y749959D02*
X187633Y749750D01*
X187967Y749667D01*
X188300Y749750D01*
X188592Y750000D01*
X188800Y750375D01*
X188883Y750750D01*
Y751209D01*
X188800Y751584D01*
X188592Y751917D01*
X188342Y752084D01*
X188050Y752167D01*
X187717Y752084D01*
X187467Y751917D01*
X187300Y751667D01*
X187217Y751334D01*
X187300Y751042D01*
X187508Y750750D01*
X187758Y750584D01*
X188050Y750542D01*
X188383Y750625D01*
X188633Y750834D01*
X188883Y751209D01*
G01X191150Y752167D02*
X190817Y752084D01*
X190567Y751875D01*
X190400Y751625D01*
X190275Y751292D01*
X190233Y750917D01*
X190275Y750542D01*
X190400Y750209D01*
X190567Y749959D01*
X190817Y749750D01*
X191150Y749667D01*
X191483Y749750D01*
X191733Y749959D01*
X191900Y750209D01*
X192025Y750542D01*
X192067Y750917D01*
X192025Y751292D01*
X191900Y751625D01*
X191733Y751875D01*
X191483Y752084D01*
X191150Y752167D01*
G01X197500Y731800D02*
X201500D01*
Y739200D01*
G01X194300Y731500D02*
Y727500D01*
X201700D01*
G01X190834Y723517D02*
X188334D01*
Y724558D01*
X188459Y724892D01*
X188626Y725100D01*
X188959Y725183D01*
X189292Y725100D01*
X189501Y724850D01*
X189626Y724558D01*
Y723517D01*
G01Y724558D02*
X190834Y725183D01*
G01Y727450D02*
X190792Y727742D01*
X190667Y728075D01*
X190459Y728283D01*
X190167Y728367D01*
X189876Y728283D01*
X189626Y728033D01*
X189501Y727658D01*
Y727242D01*
X189417Y726992D01*
X189209Y726783D01*
X188917Y726700D01*
X188626Y726825D01*
X188417Y727117D01*
X188334Y727450D01*
X188417Y727783D01*
X188626Y728075D01*
X188917Y728200D01*
X189209Y728117D01*
X189417Y727908D01*
X189501Y727658D01*
Y727242D01*
X189626Y726867D01*
X189876Y726617D01*
X190167Y726533D01*
X190459Y726617D01*
X190667Y726825D01*
X190792Y727158D01*
X190834Y727450D01*
G01X190542Y729842D02*
X190751Y730133D01*
X190834Y730467D01*
X190751Y730800D01*
X190501Y731092D01*
X190126Y731300D01*
X189751Y731383D01*
X189292D01*
X188917Y731300D01*
X188584Y731092D01*
X188417Y730842D01*
X188334Y730550D01*
X188417Y730217D01*
X188584Y729967D01*
X188834Y729800D01*
X189167Y729717D01*
X189459Y729800D01*
X189751Y730008D01*
X189917Y730258D01*
X189959Y730550D01*
X189876Y730883D01*
X189667Y731133D01*
X189292Y731383D01*
G01X189792Y732858D02*
X189501Y733150D01*
X189334Y733400D01*
X189251Y733733D01*
X189334Y734025D01*
X189501Y734233D01*
X189751Y734400D01*
X190042Y734442D01*
X190292Y734400D01*
X190542Y734233D01*
X190751Y733983D01*
X190834Y733692D01*
X190751Y733358D01*
X190501Y733067D01*
X190126Y732900D01*
X189709Y732858D01*
X189167Y732942D01*
X188876Y733067D01*
X188584Y733275D01*
X188376Y733567D01*
X188334Y733858D01*
X188417Y734150D01*
X188626Y734358D01*
G01X195334Y737517D02*
X192834D01*
Y738558D01*
X192959Y738892D01*
X193126Y739100D01*
X193459Y739183D01*
X193792Y739100D01*
X194001Y738850D01*
X194126Y738558D01*
Y737517D01*
G01Y738558D02*
X195334Y739183D01*
G01Y741450D02*
X195292Y741742D01*
X195167Y742075D01*
X194959Y742283D01*
X194667Y742367D01*
X194376Y742283D01*
X194126Y742033D01*
X194001Y741658D01*
Y741242D01*
X193917Y740992D01*
X193709Y740783D01*
X193417Y740700D01*
X193126Y740825D01*
X192917Y741117D01*
X192834Y741450D01*
X192917Y741783D01*
X193126Y742075D01*
X193417Y742200D01*
X193709Y742117D01*
X193917Y741908D01*
X194001Y741658D01*
Y741242D01*
X194126Y740867D01*
X194376Y740617D01*
X194667Y740533D01*
X194959Y740617D01*
X195167Y740825D01*
X195292Y741158D01*
X195334Y741450D01*
G01Y744467D02*
X194792Y744550D01*
X194334Y744675D01*
X193917Y744842D01*
X193459Y745050D01*
X192834Y745383D01*
Y743717D01*
G01X193251Y746858D02*
X193001Y747108D01*
X192876Y747400D01*
X192834Y747733D01*
X192917Y748150D01*
X193126Y748442D01*
X193376Y748525D01*
X193626Y748483D01*
X193834Y748317D01*
X194251Y747483D01*
X194542Y747108D01*
X194959Y746858D01*
X195334Y746775D01*
Y748525D01*
G01X182700Y730700D02*
X186700D01*
Y738100D01*
G01X169700Y717700D02*
X173700D01*
Y725100D01*
G01X169200D02*
X165200D01*
Y717700D01*
G01X197500Y774300D02*
X205500D01*
G01X197500Y762400D02*
Y774300D01*
G01X205500Y762400D02*
X197500D01*
G01X181011Y760239D02*
X180761Y760364D01*
X180469Y760447D01*
X180136D01*
X179761Y760322D01*
X179469Y760114D01*
X179261Y759864D01*
X179094Y759447D01*
X179052Y759072D01*
X179136Y758697D01*
X179261Y758447D01*
X179511Y758197D01*
X179802Y758030D01*
X180094Y757947D01*
X180386D01*
X180677Y758030D01*
X180927Y758155D01*
X181136Y758322D01*
G01X183111Y757947D02*
X183194Y758489D01*
X183319Y758947D01*
X183486Y759364D01*
X183694Y759822D01*
X184027Y760447D01*
X182361D01*
G01X186294D02*
X185961Y760364D01*
X185711Y760155D01*
X185544Y759905D01*
X185419Y759572D01*
X185377Y759197D01*
X185419Y758822D01*
X185544Y758489D01*
X185711Y758239D01*
X185961Y758030D01*
X186294Y757947D01*
X186627Y758030D01*
X186877Y758239D01*
X187044Y758489D01*
X187169Y758822D01*
X187211Y759197D01*
X187169Y759572D01*
X187044Y759905D01*
X186877Y760155D01*
X186627Y760364D01*
X186294Y760447D01*
G01X188477Y758447D02*
X188727Y758155D01*
X189061Y757989D01*
X189436Y757947D01*
X189769Y757989D01*
X190102Y758197D01*
X190311Y758447D01*
X190352Y758697D01*
X190269Y758989D01*
X189977Y759197D01*
X189686Y759280D01*
X189311D01*
G01X189686D02*
X189936Y759405D01*
X190144Y759614D01*
X190227Y759864D01*
X190144Y760114D01*
X189936Y760322D01*
X189561Y760447D01*
X189186Y760405D01*
X188811Y760239D01*
G01X182704Y785612D02*
X182454Y785737D01*
X182162Y785820D01*
X181829D01*
X181454Y785695D01*
X181162Y785487D01*
X180954Y785237D01*
X180787Y784820D01*
X180745Y784445D01*
X180829Y784070D01*
X180954Y783820D01*
X181204Y783570D01*
X181495Y783403D01*
X181787Y783320D01*
X182079D01*
X182370Y783403D01*
X182620Y783528D01*
X182829Y783695D01*
G01X184804Y783320D02*
X184887Y783862D01*
X185012Y784320D01*
X185179Y784737D01*
X185387Y785195D01*
X185720Y785820D01*
X184054D01*
G01X187987D02*
X187654Y785737D01*
X187404Y785528D01*
X187237Y785278D01*
X187112Y784945D01*
X187070Y784570D01*
X187112Y784195D01*
X187237Y783862D01*
X187404Y783612D01*
X187654Y783403D01*
X187987Y783320D01*
X188320Y783403D01*
X188570Y783612D01*
X188737Y783862D01*
X188862Y784195D01*
X188904Y784570D01*
X188862Y784945D01*
X188737Y785278D01*
X188570Y785528D01*
X188320Y785737D01*
X187987Y785820D01*
G01X190295Y785403D02*
X190545Y785653D01*
X190837Y785778D01*
X191170Y785820D01*
X191587Y785737D01*
X191879Y785528D01*
X191962Y785278D01*
X191920Y785028D01*
X191754Y784820D01*
X190920Y784403D01*
X190545Y784112D01*
X190295Y783695D01*
X190212Y783320D01*
X191962D01*
G01X201500Y756700D02*
X197500D01*
Y749300D01*
G01X178334Y772517D02*
X175834D01*
Y773558D01*
X175959Y773892D01*
X176126Y774100D01*
X176459Y774183D01*
X176792Y774100D01*
X177001Y773850D01*
X177126Y773558D01*
Y772517D01*
G01Y773558D02*
X178334Y774183D01*
G01Y776450D02*
X178292Y776742D01*
X178167Y777075D01*
X177959Y777283D01*
X177667Y777367D01*
X177376Y777283D01*
X177126Y777033D01*
X177001Y776658D01*
Y776242D01*
X176917Y775992D01*
X176709Y775783D01*
X176417Y775700D01*
X176126Y775825D01*
X175917Y776117D01*
X175834Y776450D01*
X175917Y776783D01*
X176126Y777075D01*
X176417Y777200D01*
X176709Y777117D01*
X176917Y776908D01*
X177001Y776658D01*
Y776242D01*
X177126Y775867D01*
X177376Y775617D01*
X177667Y775533D01*
X177959Y775617D01*
X178167Y775825D01*
X178292Y776158D01*
X178334Y776450D01*
G01Y779550D02*
X178292Y779842D01*
X178167Y780175D01*
X177959Y780383D01*
X177667Y780467D01*
X177376Y780383D01*
X177126Y780133D01*
X177001Y779758D01*
Y779342D01*
X176917Y779092D01*
X176709Y778883D01*
X176417Y778800D01*
X176126Y778925D01*
X175917Y779217D01*
X175834Y779550D01*
X175917Y779883D01*
X176126Y780175D01*
X176417Y780300D01*
X176709Y780217D01*
X176917Y780008D01*
X177001Y779758D01*
Y779342D01*
X177126Y778967D01*
X177376Y778717D01*
X177667Y778633D01*
X177959Y778717D01*
X178167Y778925D01*
X178292Y779258D01*
X178334Y779550D01*
G01Y782567D02*
X177792Y782650D01*
X177334Y782775D01*
X176917Y782942D01*
X176459Y783150D01*
X175834Y783483D01*
Y781817D01*
G01X184000Y770300D02*
X188000D01*
Y777700D01*
G01X180517Y753667D02*
Y756167D01*
X181558D01*
X181892Y756042D01*
X182100Y755875D01*
X182183Y755542D01*
X182100Y755209D01*
X181850Y755000D01*
X181558Y754875D01*
X180517D01*
G01X181558D02*
X182183Y753667D01*
G01X184450D02*
X184742Y753709D01*
X185075Y753834D01*
X185283Y754042D01*
X185367Y754334D01*
X185283Y754625D01*
X185033Y754875D01*
X184658Y755000D01*
X184242D01*
X183992Y755084D01*
X183783Y755292D01*
X183700Y755584D01*
X183825Y755875D01*
X184117Y756084D01*
X184450Y756167D01*
X184783Y756084D01*
X185075Y755875D01*
X185200Y755584D01*
X185117Y755292D01*
X184908Y755084D01*
X184658Y755000D01*
X184242D01*
X183867Y754875D01*
X183617Y754625D01*
X183533Y754334D01*
X183617Y754042D01*
X183825Y753834D01*
X184158Y753709D01*
X184450Y753667D01*
G01X187467D02*
X187550Y754209D01*
X187675Y754667D01*
X187842Y755084D01*
X188050Y755542D01*
X188383Y756167D01*
X186717D01*
G01X189733Y754167D02*
X189983Y753875D01*
X190317Y753709D01*
X190692Y753667D01*
X191025Y753709D01*
X191358Y753917D01*
X191567Y754167D01*
X191608Y754417D01*
X191525Y754709D01*
X191233Y754917D01*
X190942Y755000D01*
X190567D01*
G01X190942D02*
X191192Y755125D01*
X191400Y755334D01*
X191483Y755584D01*
X191400Y755834D01*
X191192Y756042D01*
X190817Y756167D01*
X190442Y756125D01*
X190067Y755959D01*
G01X176900Y751400D02*
Y755400D01*
X169500D01*
G01X173700Y763100D02*
X169700D01*
Y755700D01*
G01X165200D02*
X169200D01*
Y763100D01*
G01X175542Y761767D02*
X175417Y761517D01*
X175334Y761225D01*
Y760892D01*
X175459Y760517D01*
X175667Y760225D01*
X175917Y760017D01*
X176334Y759850D01*
X176709Y759808D01*
X177084Y759892D01*
X177334Y760017D01*
X177584Y760267D01*
X177751Y760558D01*
X177834Y760850D01*
Y761142D01*
X177751Y761433D01*
X177626Y761683D01*
X177459Y761892D01*
G01X177834Y763867D02*
X177292Y763950D01*
X176834Y764075D01*
X176417Y764242D01*
X175959Y764450D01*
X175334Y764783D01*
Y763117D01*
G01Y767050D02*
X175417Y766717D01*
X175626Y766467D01*
X175876Y766300D01*
X176209Y766175D01*
X176584Y766133D01*
X176959Y766175D01*
X177292Y766300D01*
X177542Y766467D01*
X177751Y766717D01*
X177834Y767050D01*
X177751Y767383D01*
X177542Y767633D01*
X177292Y767800D01*
X176959Y767925D01*
X176584Y767967D01*
X176209Y767925D01*
X175876Y767800D01*
X175626Y767633D01*
X175417Y767383D01*
X175334Y767050D01*
G01X177834Y770067D02*
X177292Y770150D01*
X176834Y770275D01*
X176417Y770442D01*
X175959Y770650D01*
X175334Y770983D01*
Y769317D01*
G01X171542Y769267D02*
X171417Y769017D01*
X171334Y768725D01*
Y768392D01*
X171459Y768017D01*
X171667Y767725D01*
X171917Y767517D01*
X172334Y767350D01*
X172709Y767308D01*
X173084Y767392D01*
X173334Y767517D01*
X173584Y767767D01*
X173751Y768058D01*
X173834Y768350D01*
Y768642D01*
X173751Y768933D01*
X173626Y769183D01*
X173459Y769392D01*
G01X173834Y771367D02*
X173292Y771450D01*
X172834Y771575D01*
X172417Y771742D01*
X171959Y771950D01*
X171334Y772283D01*
Y770617D01*
G01Y774550D02*
X171417Y774217D01*
X171626Y773967D01*
X171876Y773800D01*
X172209Y773675D01*
X172584Y773633D01*
X172959Y773675D01*
X173292Y773800D01*
X173542Y773967D01*
X173751Y774217D01*
X173834Y774550D01*
X173751Y774883D01*
X173542Y775133D01*
X173292Y775300D01*
X172959Y775425D01*
X172584Y775467D01*
X172209Y775425D01*
X171876Y775300D01*
X171626Y775133D01*
X171417Y774883D01*
X171334Y774550D01*
G01X172792Y776858D02*
X172501Y777150D01*
X172334Y777400D01*
X172251Y777733D01*
X172334Y778025D01*
X172501Y778233D01*
X172751Y778400D01*
X173042Y778442D01*
X173292Y778400D01*
X173542Y778233D01*
X173751Y777983D01*
X173834Y777692D01*
X173751Y777358D01*
X173501Y777067D01*
X173126Y776900D01*
X172709Y776858D01*
X172167Y776942D01*
X171876Y777067D01*
X171584Y777275D01*
X171376Y777567D01*
X171334Y777858D01*
X171417Y778150D01*
X171626Y778358D01*
G01X166000Y797800D02*
Y785900D01*
G01X193910Y791544D02*
X191410D01*
Y792585D01*
X191535Y792919D01*
X191702Y793127D01*
X192035Y793210D01*
X192368Y793127D01*
X192577Y792877D01*
X192702Y792585D01*
Y791544D01*
G01Y792585D02*
X193910Y793210D01*
G01Y795477D02*
X193868Y795769D01*
X193743Y796102D01*
X193535Y796310D01*
X193243Y796394D01*
X192952Y796310D01*
X192702Y796060D01*
X192577Y795685D01*
Y795269D01*
X192493Y795019D01*
X192285Y794810D01*
X191993Y794727D01*
X191702Y794852D01*
X191493Y795144D01*
X191410Y795477D01*
X191493Y795810D01*
X191702Y796102D01*
X191993Y796227D01*
X192285Y796144D01*
X192493Y795935D01*
X192577Y795685D01*
Y795269D01*
X192702Y794894D01*
X192952Y794644D01*
X193243Y794560D01*
X193535Y794644D01*
X193743Y794852D01*
X193868Y795185D01*
X193910Y795477D01*
G01X193618Y797869D02*
X193827Y798160D01*
X193910Y798494D01*
X193827Y798827D01*
X193577Y799119D01*
X193202Y799327D01*
X192827Y799410D01*
X192368D01*
X191993Y799327D01*
X191660Y799119D01*
X191493Y798869D01*
X191410Y798577D01*
X191493Y798244D01*
X191660Y797994D01*
X191910Y797827D01*
X192243Y797744D01*
X192535Y797827D01*
X192827Y798035D01*
X192993Y798285D01*
X193035Y798577D01*
X192952Y798910D01*
X192743Y799160D01*
X192368Y799410D01*
G01X193910Y802177D02*
X191410D01*
X193202Y800635D01*
Y802719D01*
G01X189910Y791544D02*
X187410D01*
Y792585D01*
X187535Y792919D01*
X187702Y793127D01*
X188035Y793210D01*
X188368Y793127D01*
X188577Y792877D01*
X188702Y792585D01*
Y791544D01*
G01Y792585D02*
X189910Y793210D01*
G01Y795477D02*
X189868Y795769D01*
X189743Y796102D01*
X189535Y796310D01*
X189243Y796394D01*
X188952Y796310D01*
X188702Y796060D01*
X188577Y795685D01*
Y795269D01*
X188493Y795019D01*
X188285Y794810D01*
X187993Y794727D01*
X187702Y794852D01*
X187493Y795144D01*
X187410Y795477D01*
X187493Y795810D01*
X187702Y796102D01*
X187993Y796227D01*
X188285Y796144D01*
X188493Y795935D01*
X188577Y795685D01*
Y795269D01*
X188702Y794894D01*
X188952Y794644D01*
X189243Y794560D01*
X189535Y794644D01*
X189743Y794852D01*
X189868Y795185D01*
X189910Y795477D01*
G01X189618Y797869D02*
X189827Y798160D01*
X189910Y798494D01*
X189827Y798827D01*
X189577Y799119D01*
X189202Y799327D01*
X188827Y799410D01*
X188368D01*
X187993Y799327D01*
X187660Y799119D01*
X187493Y798869D01*
X187410Y798577D01*
X187493Y798244D01*
X187660Y797994D01*
X187910Y797827D01*
X188243Y797744D01*
X188535Y797827D01*
X188827Y798035D01*
X188993Y798285D01*
X189035Y798577D01*
X188952Y798910D01*
X188743Y799160D01*
X188368Y799410D01*
G01X187410Y801677D02*
X187493Y801344D01*
X187702Y801094D01*
X187952Y800927D01*
X188285Y800802D01*
X188660Y800760D01*
X189035Y800802D01*
X189368Y800927D01*
X189618Y801094D01*
X189827Y801344D01*
X189910Y801677D01*
X189827Y802010D01*
X189618Y802260D01*
X189368Y802427D01*
X189035Y802552D01*
X188660Y802594D01*
X188285Y802552D01*
X187952Y802427D01*
X187702Y802260D01*
X187493Y802010D01*
X187410Y801677D01*
G01X197500Y787300D02*
X201500D01*
Y794700D01*
G01X181003Y787259D02*
Y789759D01*
X182044D01*
X182378Y789634D01*
X182586Y789467D01*
X182669Y789134D01*
X182586Y788801D01*
X182336Y788592D01*
X182044Y788467D01*
X181003D01*
G01X182044D02*
X182669Y787259D01*
G01X184936D02*
X185228Y787301D01*
X185561Y787426D01*
X185769Y787634D01*
X185853Y787926D01*
X185769Y788217D01*
X185519Y788467D01*
X185144Y788592D01*
X184728D01*
X184478Y788676D01*
X184269Y788884D01*
X184186Y789176D01*
X184311Y789467D01*
X184603Y789676D01*
X184936Y789759D01*
X185269Y789676D01*
X185561Y789467D01*
X185686Y789176D01*
X185603Y788884D01*
X185394Y788676D01*
X185144Y788592D01*
X184728D01*
X184353Y788467D01*
X184103Y788217D01*
X184019Y787926D01*
X184103Y787634D01*
X184311Y787426D01*
X184644Y787301D01*
X184936Y787259D01*
G01X188036D02*
X188328Y787301D01*
X188661Y787426D01*
X188869Y787634D01*
X188953Y787926D01*
X188869Y788217D01*
X188619Y788467D01*
X188244Y788592D01*
X187828D01*
X187578Y788676D01*
X187369Y788884D01*
X187286Y789176D01*
X187411Y789467D01*
X187703Y789676D01*
X188036Y789759D01*
X188369Y789676D01*
X188661Y789467D01*
X188786Y789176D01*
X188703Y788884D01*
X188494Y788676D01*
X188244Y788592D01*
X187828D01*
X187453Y788467D01*
X187203Y788217D01*
X187119Y787926D01*
X187203Y787634D01*
X187411Y787426D01*
X187744Y787301D01*
X188036Y787259D01*
G01X190344Y788301D02*
X190636Y788592D01*
X190886Y788759D01*
X191219Y788842D01*
X191511Y788759D01*
X191719Y788592D01*
X191886Y788342D01*
X191928Y788051D01*
X191886Y787801D01*
X191719Y787551D01*
X191469Y787342D01*
X191178Y787259D01*
X190844Y787342D01*
X190553Y787592D01*
X190386Y787967D01*
X190344Y788384D01*
X190428Y788926D01*
X190553Y789217D01*
X190761Y789509D01*
X191053Y789717D01*
X191344Y789759D01*
X191636Y789676D01*
X191844Y789467D01*
G01X194300Y787000D02*
Y783000D01*
X201700D01*
G01X183334Y796517D02*
X180834D01*
Y797558D01*
X180959Y797892D01*
X181126Y798100D01*
X181459Y798183D01*
X181792Y798100D01*
X182001Y797850D01*
X182126Y797558D01*
Y796517D01*
G01Y797558D02*
X183334Y798183D01*
G01Y800450D02*
X183292Y800742D01*
X183167Y801075D01*
X182959Y801283D01*
X182667Y801367D01*
X182376Y801283D01*
X182126Y801033D01*
X182001Y800658D01*
Y800242D01*
X181917Y799992D01*
X181709Y799783D01*
X181417Y799700D01*
X181126Y799825D01*
X180917Y800117D01*
X180834Y800450D01*
X180917Y800783D01*
X181126Y801075D01*
X181417Y801200D01*
X181709Y801117D01*
X181917Y800908D01*
X182001Y800658D01*
Y800242D01*
X182126Y799867D01*
X182376Y799617D01*
X182667Y799533D01*
X182959Y799617D01*
X183167Y799825D01*
X183292Y800158D01*
X183334Y800450D01*
G01Y803467D02*
X182792Y803550D01*
X182334Y803675D01*
X181917Y803842D01*
X181459Y804050D01*
X180834Y804383D01*
Y802717D01*
G01X182959Y805733D02*
X183167Y805983D01*
X183292Y806275D01*
X183334Y806650D01*
X183251Y807025D01*
X183084Y807317D01*
X182792Y807525D01*
X182459Y807567D01*
X182126Y807483D01*
X181917Y807275D01*
X181751Y806983D01*
X181709Y806692D01*
X181751Y806400D01*
X181917Y806025D01*
X180834Y806150D01*
Y807275D01*
G01X175500Y785800D02*
X179500D01*
Y793200D01*
G01X167767Y821492D02*
X167517Y821617D01*
X167225Y821700D01*
X166892D01*
X166517Y821575D01*
X166225Y821367D01*
X166017Y821117D01*
X165850Y820700D01*
X165808Y820325D01*
X165892Y819950D01*
X166017Y819700D01*
X166267Y819450D01*
X166558Y819283D01*
X166850Y819200D01*
X167142D01*
X167433Y819283D01*
X167683Y819408D01*
X167892Y819575D01*
G01X169158Y820242D02*
X169450Y820533D01*
X169700Y820700D01*
X170033Y820783D01*
X170325Y820700D01*
X170533Y820533D01*
X170700Y820283D01*
X170742Y819992D01*
X170700Y819742D01*
X170533Y819492D01*
X170283Y819283D01*
X169992Y819200D01*
X169658Y819283D01*
X169367Y819533D01*
X169200Y819908D01*
X169158Y820325D01*
X169242Y820867D01*
X169367Y821158D01*
X169575Y821450D01*
X169867Y821658D01*
X170158Y821700D01*
X170450Y821617D01*
X170658Y821408D01*
G01X172342Y819492D02*
X172633Y819283D01*
X172967Y819200D01*
X173300Y819283D01*
X173592Y819533D01*
X173800Y819908D01*
X173883Y820283D01*
Y820742D01*
X173800Y821117D01*
X173592Y821450D01*
X173342Y821617D01*
X173050Y821700D01*
X172717Y821617D01*
X172467Y821450D01*
X172300Y821200D01*
X172217Y820867D01*
X172300Y820575D01*
X172508Y820283D01*
X172758Y820117D01*
X173050Y820075D01*
X173383Y820158D01*
X173633Y820367D01*
X173883Y820742D01*
G01X176150Y819200D02*
X176442Y819242D01*
X176775Y819367D01*
X176983Y819575D01*
X177067Y819867D01*
X176983Y820158D01*
X176733Y820408D01*
X176358Y820533D01*
X175942D01*
X175692Y820617D01*
X175483Y820825D01*
X175400Y821117D01*
X175525Y821408D01*
X175817Y821617D01*
X176150Y821700D01*
X176483Y821617D01*
X176775Y821408D01*
X176900Y821117D01*
X176817Y820825D01*
X176608Y820617D01*
X176358Y820533D01*
X175942D01*
X175567Y820408D01*
X175317Y820158D01*
X175233Y819867D01*
X175317Y819575D01*
X175525Y819367D01*
X175858Y819242D01*
X176150Y819200D01*
G01X188608Y842967D02*
X188483Y842717D01*
X188400Y842425D01*
Y842092D01*
X188525Y841717D01*
X188733Y841425D01*
X188983Y841217D01*
X189400Y841050D01*
X189775Y841008D01*
X190150Y841092D01*
X190400Y841217D01*
X190650Y841467D01*
X190817Y841758D01*
X190900Y842050D01*
Y842342D01*
X190817Y842633D01*
X190692Y842883D01*
X190525Y843092D01*
G01X190400Y844233D02*
X190692Y844483D01*
X190858Y844817D01*
X190900Y845192D01*
X190858Y845525D01*
X190650Y845858D01*
X190400Y846067D01*
X190150Y846108D01*
X189858Y846025D01*
X189650Y845733D01*
X189567Y845442D01*
Y845067D01*
G01Y845442D02*
X189442Y845692D01*
X189233Y845900D01*
X188983Y845983D01*
X188733Y845900D01*
X188525Y845692D01*
X188400Y845317D01*
X188442Y844942D01*
X188608Y844567D01*
G01X189858Y847458D02*
X189567Y847750D01*
X189400Y848000D01*
X189317Y848333D01*
X189400Y848625D01*
X189567Y848833D01*
X189817Y849000D01*
X190108Y849042D01*
X190358Y849000D01*
X190608Y848833D01*
X190817Y848583D01*
X190900Y848292D01*
X190817Y847958D01*
X190567Y847667D01*
X190192Y847500D01*
X189775Y847458D01*
X189233Y847542D01*
X188942Y847667D01*
X188650Y847875D01*
X188442Y848167D01*
X188400Y848458D01*
X188483Y848750D01*
X188692Y848958D01*
G01X189858Y850558D02*
X189567Y850850D01*
X189400Y851100D01*
X189317Y851433D01*
X189400Y851725D01*
X189567Y851933D01*
X189817Y852100D01*
X190108Y852142D01*
X190358Y852100D01*
X190608Y851933D01*
X190817Y851683D01*
X190900Y851392D01*
X190817Y851058D01*
X190567Y850767D01*
X190192Y850600D01*
X189775Y850558D01*
X189233Y850642D01*
X188942Y850767D01*
X188650Y850975D01*
X188442Y851267D01*
X188400Y851558D01*
X188483Y851850D01*
X188692Y852058D01*
G01X194208Y842567D02*
X194083Y842317D01*
X194000Y842025D01*
Y841692D01*
X194125Y841317D01*
X194333Y841025D01*
X194583Y840817D01*
X195000Y840650D01*
X195375Y840608D01*
X195750Y840692D01*
X196000Y840817D01*
X196250Y841067D01*
X196417Y841358D01*
X196500Y841650D01*
Y841942D01*
X196417Y842233D01*
X196292Y842483D01*
X196125Y842692D01*
G01X196000Y843833D02*
X196292Y844083D01*
X196458Y844417D01*
X196500Y844792D01*
X196458Y845125D01*
X196250Y845458D01*
X196000Y845667D01*
X195750Y845708D01*
X195458Y845625D01*
X195250Y845333D01*
X195167Y845042D01*
Y844667D01*
G01Y845042D02*
X195042Y845292D01*
X194833Y845500D01*
X194583Y845583D01*
X194333Y845500D01*
X194125Y845292D01*
X194000Y844917D01*
X194042Y844542D01*
X194208Y844167D01*
G01X195458Y847058D02*
X195167Y847350D01*
X195000Y847600D01*
X194917Y847933D01*
X195000Y848225D01*
X195167Y848433D01*
X195417Y848600D01*
X195708Y848642D01*
X195958Y848600D01*
X196208Y848433D01*
X196417Y848183D01*
X196500Y847892D01*
X196417Y847558D01*
X196167Y847267D01*
X195792Y847100D01*
X195375Y847058D01*
X194833Y847142D01*
X194542Y847267D01*
X194250Y847475D01*
X194042Y847767D01*
X194000Y848058D01*
X194083Y848350D01*
X194292Y848558D01*
G01X196125Y850033D02*
X196333Y850283D01*
X196458Y850575D01*
X196500Y850950D01*
X196417Y851325D01*
X196250Y851617D01*
X195958Y851825D01*
X195625Y851867D01*
X195292Y851783D01*
X195083Y851575D01*
X194917Y851283D01*
X194875Y850992D01*
X194917Y850700D01*
X195083Y850325D01*
X194000Y850450D01*
Y851575D01*
G01X228229Y55654D02*
Y27854D01*
X256029D01*
Y55654D01*
X228229D01*
G01X218900Y70333D02*
X213900D01*
X218067Y72500D01*
X213900Y74667D01*
X218900D01*
G01X216233Y78767D02*
X215983Y79100D01*
X215567Y79350D01*
X214983Y79517D01*
X214483Y79350D01*
X214150Y79017D01*
X213900Y78433D01*
Y76183D01*
X218900D01*
Y78933D01*
X218567Y79517D01*
X218067Y79850D01*
X217483Y80017D01*
X216900Y79850D01*
X216400Y79350D01*
X216233Y78767D01*
Y76183D01*
G01X218900Y82033D02*
X213900D01*
Y84033D01*
X214150Y84700D01*
X214733Y85200D01*
X215400Y85367D01*
X216067Y85200D01*
X216567Y84783D01*
X216817Y84033D01*
Y82033D01*
G01X214317Y96733D02*
X214067Y96233D01*
X213900Y95650D01*
Y94983D01*
X214150Y94233D01*
X214567Y93650D01*
X215067Y93233D01*
X215900Y92900D01*
X216650Y92817D01*
X217400Y92983D01*
X217900Y93233D01*
X218400Y93733D01*
X218733Y94317D01*
X218900Y94900D01*
Y95483D01*
X218733Y96067D01*
X218483Y96567D01*
X218150Y96983D01*
G01X218900Y100500D02*
X218817Y99833D01*
X218483Y99250D01*
X217983Y98750D01*
X217400Y98417D01*
X216733Y98250D01*
X216067D01*
X215400Y98417D01*
X214817Y98750D01*
X214317Y99250D01*
X213983Y99833D01*
X213900Y100500D01*
X213983Y101167D01*
X214317Y101750D01*
X214817Y102250D01*
X215400Y102583D01*
X216067Y102750D01*
X216733D01*
X217400Y102583D01*
X217983Y102250D01*
X218483Y101750D01*
X218817Y101167D01*
X218900Y100500D01*
G01Y104183D02*
X213900D01*
X218900Y108017D01*
X213900D01*
G01X218900Y109783D02*
X213900D01*
X218900Y113617D01*
X213900D01*
G01X216317Y64459D02*
X216067Y64584D01*
X215775Y64667D01*
X215442D01*
X215067Y64542D01*
X214775Y64334D01*
X214567Y64084D01*
X214400Y63667D01*
X214358Y63292D01*
X214442Y62917D01*
X214567Y62667D01*
X214817Y62417D01*
X215108Y62250D01*
X215400Y62167D01*
X215692D01*
X215983Y62250D01*
X216233Y62375D01*
X216442Y62542D01*
G01X217542Y62167D02*
Y64667D01*
X219458Y62167D01*
Y64667D01*
G01X220808Y64250D02*
X221058Y64500D01*
X221350Y64625D01*
X221683Y64667D01*
X222100Y64584D01*
X222392Y64375D01*
X222475Y64125D01*
X222433Y63875D01*
X222267Y63667D01*
X221433Y63250D01*
X221058Y62959D01*
X220808Y62542D01*
X220725Y62167D01*
X222475D01*
G01X256747Y60489D02*
Y121689D01*
X229147D01*
Y60489D01*
X256747D01*
G01X210834Y108017D02*
X208334D01*
Y109058D01*
X208459Y109392D01*
X208626Y109600D01*
X208959Y109683D01*
X209292Y109600D01*
X209501Y109350D01*
X209626Y109058D01*
Y108017D01*
G01Y109058D02*
X210834Y109683D01*
G01X210459Y111033D02*
X210667Y111283D01*
X210792Y111575D01*
X210834Y111950D01*
X210751Y112325D01*
X210584Y112617D01*
X210292Y112825D01*
X209959Y112867D01*
X209626Y112783D01*
X209417Y112575D01*
X209251Y112283D01*
X209209Y111992D01*
X209251Y111700D01*
X209417Y111325D01*
X208334Y111450D01*
Y112575D01*
G01X209792Y114258D02*
X209501Y114550D01*
X209334Y114800D01*
X209251Y115133D01*
X209334Y115425D01*
X209501Y115633D01*
X209751Y115800D01*
X210042Y115842D01*
X210292Y115800D01*
X210542Y115633D01*
X210751Y115383D01*
X210834Y115092D01*
X210751Y114758D01*
X210501Y114467D01*
X210126Y114300D01*
X209709Y114258D01*
X209167Y114342D01*
X208876Y114467D01*
X208584Y114675D01*
X208376Y114967D01*
X208334Y115258D01*
X208417Y115550D01*
X208626Y115758D01*
G01X210542Y117442D02*
X210751Y117733D01*
X210834Y118067D01*
X210751Y118400D01*
X210501Y118692D01*
X210126Y118900D01*
X209751Y118983D01*
X209292D01*
X208917Y118900D01*
X208584Y118692D01*
X208417Y118442D01*
X208334Y118150D01*
X208417Y117817D01*
X208584Y117567D01*
X208834Y117400D01*
X209167Y117317D01*
X209459Y117400D01*
X209751Y117608D01*
X209917Y117858D01*
X209959Y118150D01*
X209876Y118483D01*
X209667Y118733D01*
X209292Y118983D01*
G01X226900Y114800D02*
X222900D01*
Y107400D01*
G01X225834Y86017D02*
X223334D01*
Y87058D01*
X223459Y87392D01*
X223626Y87600D01*
X223959Y87683D01*
X224292Y87600D01*
X224501Y87350D01*
X224626Y87058D01*
Y86017D01*
G01Y87058D02*
X225834Y87683D01*
G01Y89867D02*
X225292Y89950D01*
X224834Y90075D01*
X224417Y90242D01*
X223959Y90450D01*
X223334Y90783D01*
Y89117D01*
G01X225334Y92133D02*
X225626Y92383D01*
X225792Y92717D01*
X225834Y93092D01*
X225792Y93425D01*
X225584Y93758D01*
X225334Y93967D01*
X225084Y94008D01*
X224792Y93925D01*
X224584Y93633D01*
X224501Y93342D01*
Y92967D01*
G01Y93342D02*
X224376Y93592D01*
X224167Y93800D01*
X223917Y93883D01*
X223667Y93800D01*
X223459Y93592D01*
X223334Y93217D01*
X223376Y92842D01*
X223542Y92467D01*
G01X224792Y95358D02*
X224501Y95650D01*
X224334Y95900D01*
X224251Y96233D01*
X224334Y96525D01*
X224501Y96733D01*
X224751Y96900D01*
X225042Y96942D01*
X225292Y96900D01*
X225542Y96733D01*
X225751Y96483D01*
X225834Y96192D01*
X225751Y95858D01*
X225501Y95567D01*
X225126Y95400D01*
X224709Y95358D01*
X224167Y95442D01*
X223876Y95567D01*
X223584Y95775D01*
X223376Y96067D01*
X223334Y96358D01*
X223417Y96650D01*
X223626Y96858D01*
G01X223900Y99900D02*
X227900D01*
Y107300D01*
G01X229017Y133167D02*
Y135667D01*
X230017D01*
X230350Y135542D01*
X230600Y135250D01*
X230683Y134917D01*
X230600Y134584D01*
X230392Y134334D01*
X230017Y134209D01*
X229017D01*
G01X232117Y133167D02*
Y135667D01*
X233158D01*
X233492Y135542D01*
X233700Y135375D01*
X233783Y135042D01*
X233700Y134709D01*
X233450Y134500D01*
X233158Y134375D01*
X232117D01*
G01X233158D02*
X233783Y133167D01*
G01X235258Y135250D02*
X235508Y135500D01*
X235800Y135625D01*
X236133Y135667D01*
X236550Y135584D01*
X236842Y135375D01*
X236925Y135125D01*
X236883Y134875D01*
X236717Y134667D01*
X235883Y134250D01*
X235508Y133959D01*
X235258Y133542D01*
X235175Y133167D01*
X236925D01*
G01X238442Y133459D02*
X238733Y133250D01*
X239067Y133167D01*
X239400Y133250D01*
X239692Y133500D01*
X239900Y133875D01*
X239983Y134250D01*
Y134709D01*
X239900Y135084D01*
X239692Y135417D01*
X239442Y135584D01*
X239150Y135667D01*
X238817Y135584D01*
X238567Y135417D01*
X238400Y135167D01*
X238317Y134834D01*
X238400Y134542D01*
X238608Y134250D01*
X238858Y134084D01*
X239150Y134042D01*
X239483Y134125D01*
X239733Y134334D01*
X239983Y134709D01*
G01X227834Y128017D02*
X225334D01*
Y129017D01*
X225459Y129350D01*
X225751Y129600D01*
X226084Y129683D01*
X226417Y129600D01*
X226667Y129392D01*
X226792Y129017D01*
Y128017D01*
G01X227834Y131117D02*
X225334D01*
Y132158D01*
X225459Y132492D01*
X225626Y132700D01*
X225959Y132783D01*
X226292Y132700D01*
X226501Y132450D01*
X226626Y132158D01*
Y131117D01*
G01Y132158D02*
X227834Y132783D01*
G01X227334Y134133D02*
X227626Y134383D01*
X227792Y134717D01*
X227834Y135092D01*
X227792Y135425D01*
X227584Y135758D01*
X227334Y135967D01*
X227084Y136008D01*
X226792Y135925D01*
X226584Y135633D01*
X226501Y135342D01*
Y134967D01*
G01Y135342D02*
X226376Y135592D01*
X226167Y135800D01*
X225917Y135883D01*
X225667Y135800D01*
X225459Y135592D01*
X225334Y135217D01*
X225376Y134842D01*
X225542Y134467D01*
G01X225751Y137358D02*
X225501Y137608D01*
X225376Y137900D01*
X225334Y138233D01*
X225417Y138650D01*
X225626Y138942D01*
X225876Y139025D01*
X226126Y138983D01*
X226334Y138817D01*
X226751Y137983D01*
X227042Y137608D01*
X227459Y137358D01*
X227834Y137275D01*
Y139025D01*
G01X205749Y145587D02*
Y141587D01*
X213149D01*
G01X220334Y116517D02*
X217834D01*
Y117558D01*
X217959Y117892D01*
X218126Y118100D01*
X218459Y118183D01*
X218792Y118100D01*
X219001Y117850D01*
X219126Y117558D01*
Y116517D01*
G01Y117558D02*
X220334Y118183D01*
G01X219959Y119533D02*
X220167Y119783D01*
X220292Y120075D01*
X220334Y120450D01*
X220251Y120825D01*
X220084Y121117D01*
X219792Y121325D01*
X219459Y121367D01*
X219126Y121283D01*
X218917Y121075D01*
X218751Y120783D01*
X218709Y120492D01*
X218751Y120200D01*
X218917Y119825D01*
X217834Y119950D01*
Y121075D01*
G01X220334Y123467D02*
X219792Y123550D01*
X219334Y123675D01*
X218917Y123842D01*
X218459Y124050D01*
X217834Y124383D01*
Y122717D01*
G01Y126650D02*
X217917Y126317D01*
X218126Y126067D01*
X218376Y125900D01*
X218709Y125775D01*
X219084Y125733D01*
X219459Y125775D01*
X219792Y125900D01*
X220042Y126067D01*
X220251Y126317D01*
X220334Y126650D01*
X220251Y126983D01*
X220042Y127233D01*
X219792Y127400D01*
X219459Y127525D01*
X219084Y127567D01*
X218709Y127525D01*
X218376Y127400D01*
X218126Y127233D01*
X217917Y126983D01*
X217834Y126650D01*
G01X226600Y125500D02*
X222600D01*
Y118100D01*
G01X216857Y127800D02*
Y140800D01*
G01D02*
X202857D01*
G01D02*
Y127800D01*
G01D02*
X216857D01*
G01X203834Y148017D02*
X201334D01*
Y149058D01*
X201459Y149392D01*
X201626Y149600D01*
X201959Y149683D01*
X202292Y149600D01*
X202501Y149350D01*
X202626Y149058D01*
Y148017D01*
G01Y149058D02*
X203834Y149683D01*
G01X202792Y151158D02*
X202501Y151450D01*
X202334Y151700D01*
X202251Y152033D01*
X202334Y152325D01*
X202501Y152533D01*
X202751Y152700D01*
X203042Y152742D01*
X203292Y152700D01*
X203542Y152533D01*
X203751Y152283D01*
X203834Y151992D01*
X203751Y151658D01*
X203501Y151367D01*
X203126Y151200D01*
X202709Y151158D01*
X202167Y151242D01*
X201876Y151367D01*
X201584Y151575D01*
X201376Y151867D01*
X201334Y152158D01*
X201417Y152450D01*
X201626Y152658D01*
G01X203834Y155050D02*
X201334D01*
X201834Y154550D01*
G01X203834D02*
Y155550D01*
G01Y158150D02*
X203792Y158442D01*
X203667Y158775D01*
X203459Y158983D01*
X203167Y159067D01*
X202876Y158983D01*
X202626Y158733D01*
X202501Y158358D01*
Y157942D01*
X202417Y157692D01*
X202209Y157483D01*
X201917Y157400D01*
X201626Y157525D01*
X201417Y157817D01*
X201334Y158150D01*
X201417Y158483D01*
X201626Y158775D01*
X201917Y158900D01*
X202209Y158817D01*
X202417Y158608D01*
X202501Y158358D01*
Y157942D01*
X202626Y157567D01*
X202876Y157317D01*
X203167Y157233D01*
X203459Y157317D01*
X203667Y157525D01*
X203792Y157858D01*
X203834Y158150D01*
G01X209369Y153184D02*
X205369D01*
Y145784D01*
G01X201140Y161248D02*
X200807Y161290D01*
X200515Y161456D01*
X200265Y161706D01*
X200098Y161998D01*
X200015Y162331D01*
Y162665D01*
X200098Y162998D01*
X200265Y163290D01*
X200515Y163540D01*
X200807Y163706D01*
X201140Y163748D01*
X201473Y163706D01*
X201765Y163540D01*
X202015Y163290D01*
X202182Y162998D01*
X202265Y162665D01*
Y162331D01*
X202182Y161998D01*
X202015Y161706D01*
X201765Y161456D01*
X201473Y161290D01*
X201140Y161248D01*
G01X201473Y161915D02*
X201973Y161248D01*
G01X204740D02*
Y163748D01*
X203198Y161956D01*
X205282D01*
G01X206423Y161748D02*
X206673Y161456D01*
X207007Y161290D01*
X207382Y161248D01*
X207715Y161290D01*
X208048Y161498D01*
X208257Y161748D01*
X208298Y161998D01*
X208215Y162290D01*
X207923Y162498D01*
X207632Y162581D01*
X207257D01*
G01X207632D02*
X207882Y162706D01*
X208090Y162915D01*
X208173Y163165D01*
X208090Y163415D01*
X207882Y163623D01*
X207507Y163748D01*
X207132Y163706D01*
X206757Y163540D01*
G01X216354Y141761D02*
X229354D01*
G01D02*
Y155761D01*
G01D02*
X216354D01*
G01D02*
Y141761D01*
G01X200014Y165708D02*
Y168208D01*
X201055D01*
X201389Y168083D01*
X201597Y167916D01*
X201680Y167583D01*
X201597Y167250D01*
X201347Y167041D01*
X201055Y166916D01*
X200014D01*
G01X201055D02*
X201680Y165708D01*
G01X203155Y166750D02*
X203447Y167041D01*
X203697Y167208D01*
X204030Y167291D01*
X204322Y167208D01*
X204530Y167041D01*
X204697Y166791D01*
X204739Y166500D01*
X204697Y166250D01*
X204530Y166000D01*
X204280Y165791D01*
X203989Y165708D01*
X203655Y165791D01*
X203364Y166041D01*
X203197Y166416D01*
X203155Y166833D01*
X203239Y167375D01*
X203364Y167666D01*
X203572Y167958D01*
X203864Y168166D01*
X204155Y168208D01*
X204447Y168125D01*
X204655Y167916D01*
G01X206255Y167791D02*
X206505Y168041D01*
X206797Y168166D01*
X207130Y168208D01*
X207547Y168125D01*
X207839Y167916D01*
X207922Y167666D01*
X207880Y167416D01*
X207714Y167208D01*
X206880Y166791D01*
X206505Y166500D01*
X206255Y166083D01*
X206172Y165708D01*
X207922D01*
G01X210147D02*
X210439Y165750D01*
X210772Y165875D01*
X210980Y166083D01*
X211064Y166375D01*
X210980Y166666D01*
X210730Y166916D01*
X210355Y167041D01*
X209939D01*
X209689Y167125D01*
X209480Y167333D01*
X209397Y167625D01*
X209522Y167916D01*
X209814Y168125D01*
X210147Y168208D01*
X210480Y168125D01*
X210772Y167916D01*
X210897Y167625D01*
X210814Y167333D01*
X210605Y167125D01*
X210355Y167041D01*
X209939D01*
X209564Y166916D01*
X209314Y166666D01*
X209230Y166375D01*
X209314Y166083D01*
X209522Y165875D01*
X209855Y165750D01*
X210147Y165708D01*
G01X232100Y164600D02*
Y156600D01*
X214500D01*
Y164600D01*
X232100D01*
G01X212469Y182825D02*
X220469D01*
Y165225D01*
X212469D01*
Y182825D01*
G01X231717Y202100D02*
Y204600D01*
X232717D01*
X233050Y204475D01*
X233300Y204183D01*
X233383Y203850D01*
X233300Y203517D01*
X233092Y203267D01*
X232717Y203142D01*
X231717D01*
G01X236567Y204392D02*
X236317Y204517D01*
X236025Y204600D01*
X235692D01*
X235317Y204475D01*
X235025Y204267D01*
X234817Y204017D01*
X234650Y203600D01*
X234608Y203225D01*
X234692Y202850D01*
X234817Y202600D01*
X235067Y202350D01*
X235358Y202183D01*
X235650Y202100D01*
X235942D01*
X236233Y202183D01*
X236483Y202308D01*
X236692Y202475D01*
G01X237958Y204183D02*
X238208Y204433D01*
X238500Y204558D01*
X238833Y204600D01*
X239250Y204517D01*
X239542Y204308D01*
X239625Y204058D01*
X239583Y203808D01*
X239417Y203600D01*
X238583Y203183D01*
X238208Y202892D01*
X237958Y202475D01*
X237875Y202100D01*
X239625D01*
G01X242350D02*
Y204600D01*
X240808Y202808D01*
X242892D01*
G01X231617Y198100D02*
Y200600D01*
X232617D01*
X232950Y200475D01*
X233200Y200183D01*
X233283Y199850D01*
X233200Y199517D01*
X232992Y199267D01*
X232617Y199142D01*
X231617D01*
G01X236467Y200392D02*
X236217Y200517D01*
X235925Y200600D01*
X235592D01*
X235217Y200475D01*
X234925Y200267D01*
X234717Y200017D01*
X234550Y199600D01*
X234508Y199225D01*
X234592Y198850D01*
X234717Y198600D01*
X234967Y198350D01*
X235258Y198183D01*
X235550Y198100D01*
X235842D01*
X236133Y198183D01*
X236383Y198308D01*
X236592Y198475D01*
G01X237733Y198600D02*
X237983Y198308D01*
X238317Y198142D01*
X238692Y198100D01*
X239025Y198142D01*
X239358Y198350D01*
X239567Y198600D01*
X239608Y198850D01*
X239525Y199142D01*
X239233Y199350D01*
X238942Y199433D01*
X238567D01*
G01X238942D02*
X239192Y199558D01*
X239400Y199767D01*
X239483Y200017D01*
X239400Y200267D01*
X239192Y200475D01*
X238817Y200600D01*
X238442Y200558D01*
X238067Y200392D01*
G01X240833Y198600D02*
X241083Y198308D01*
X241417Y198142D01*
X241792Y198100D01*
X242125Y198142D01*
X242458Y198350D01*
X242667Y198600D01*
X242708Y198850D01*
X242625Y199142D01*
X242333Y199350D01*
X242042Y199433D01*
X241667D01*
G01X242042D02*
X242292Y199558D01*
X242500Y199767D01*
X242583Y200017D01*
X242500Y200267D01*
X242292Y200475D01*
X241917Y200600D01*
X241542Y200558D01*
X241167Y200392D01*
G01X231667Y205900D02*
Y208400D01*
X232667D01*
X233000Y208275D01*
X233250Y207983D01*
X233333Y207650D01*
X233250Y207317D01*
X233042Y207067D01*
X232667Y206942D01*
X231667D01*
G01X234767Y208400D02*
Y205900D01*
X236433D01*
G01X237908Y207983D02*
X238158Y208233D01*
X238450Y208358D01*
X238783Y208400D01*
X239200Y208317D01*
X239492Y208108D01*
X239575Y207858D01*
X239533Y207608D01*
X239367Y207400D01*
X238533Y206983D01*
X238158Y206692D01*
X237908Y206275D01*
X237825Y205900D01*
X239575D01*
G01X226300Y189600D02*
Y182400D01*
G01D02*
X239700D01*
G01Y189600D02*
X226300D01*
G01X201727Y181519D02*
X199227D01*
Y182560D01*
X199352Y182894D01*
X199519Y183102D01*
X199852Y183185D01*
X200185Y183102D01*
X200394Y182852D01*
X200519Y182560D01*
Y181519D01*
G01Y182560D02*
X201727Y183185D01*
G01X201352Y184535D02*
X201560Y184785D01*
X201685Y185077D01*
X201727Y185452D01*
X201644Y185827D01*
X201477Y186119D01*
X201185Y186327D01*
X200852Y186369D01*
X200519Y186285D01*
X200310Y186077D01*
X200144Y185785D01*
X200102Y185494D01*
X200144Y185202D01*
X200310Y184827D01*
X199227Y184952D01*
Y186077D01*
G01Y188552D02*
X199310Y188219D01*
X199519Y187969D01*
X199769Y187802D01*
X200102Y187677D01*
X200477Y187635D01*
X200852Y187677D01*
X201185Y187802D01*
X201435Y187969D01*
X201644Y188219D01*
X201727Y188552D01*
X201644Y188885D01*
X201435Y189135D01*
X201185Y189302D01*
X200852Y189427D01*
X200477Y189469D01*
X200102Y189427D01*
X199769Y189302D01*
X199519Y189135D01*
X199310Y188885D01*
X199227Y188552D01*
G01Y191652D02*
X199310Y191319D01*
X199519Y191069D01*
X199769Y190902D01*
X200102Y190777D01*
X200477Y190735D01*
X200852Y190777D01*
X201185Y190902D01*
X201435Y191069D01*
X201644Y191319D01*
X201727Y191652D01*
X201644Y191985D01*
X201435Y192235D01*
X201185Y192402D01*
X200852Y192527D01*
X200477Y192569D01*
X200102Y192527D01*
X199769Y192402D01*
X199519Y192235D01*
X199310Y191985D01*
X199227Y191652D01*
G01X204146Y182892D02*
X204021Y182642D01*
X203938Y182350D01*
Y182017D01*
X204063Y181642D01*
X204271Y181350D01*
X204521Y181142D01*
X204938Y180975D01*
X205313Y180933D01*
X205688Y181017D01*
X205938Y181142D01*
X206188Y181392D01*
X206355Y181683D01*
X206438Y181975D01*
Y182267D01*
X206355Y182558D01*
X206230Y182808D01*
X206063Y183017D01*
G01X204355Y184283D02*
X204105Y184533D01*
X203980Y184825D01*
X203938Y185158D01*
X204021Y185575D01*
X204230Y185867D01*
X204480Y185950D01*
X204730Y185908D01*
X204938Y185742D01*
X205355Y184908D01*
X205646Y184533D01*
X206063Y184283D01*
X206438Y184200D01*
Y185950D01*
G01X205938Y187258D02*
X206230Y187508D01*
X206396Y187842D01*
X206438Y188217D01*
X206396Y188550D01*
X206188Y188883D01*
X205938Y189092D01*
X205688Y189133D01*
X205396Y189050D01*
X205188Y188758D01*
X205105Y188467D01*
Y188092D01*
G01Y188467D02*
X204980Y188717D01*
X204771Y188925D01*
X204521Y189008D01*
X204271Y188925D01*
X204063Y188717D01*
X203938Y188342D01*
X203980Y187967D01*
X204146Y187592D01*
G01X205396Y190483D02*
X205105Y190775D01*
X204938Y191025D01*
X204855Y191358D01*
X204938Y191650D01*
X205105Y191858D01*
X205355Y192025D01*
X205646Y192067D01*
X205896Y192025D01*
X206146Y191858D01*
X206355Y191608D01*
X206438Y191317D01*
X206355Y190983D01*
X206105Y190692D01*
X205730Y190525D01*
X205313Y190483D01*
X204771Y190567D01*
X204480Y190692D01*
X204188Y190900D01*
X203980Y191192D01*
X203938Y191483D01*
X204021Y191775D01*
X204230Y191983D01*
G01X224897Y226097D02*
X222397D01*
Y227138D01*
X222522Y227472D01*
X222689Y227680D01*
X223022Y227763D01*
X223355Y227680D01*
X223564Y227430D01*
X223689Y227138D01*
Y226097D01*
G01Y227138D02*
X224897Y227763D01*
G01X222814Y229238D02*
X222564Y229488D01*
X222439Y229780D01*
X222397Y230113D01*
X222480Y230530D01*
X222689Y230822D01*
X222939Y230905D01*
X223189Y230863D01*
X223397Y230697D01*
X223814Y229863D01*
X224105Y229488D01*
X224522Y229238D01*
X224897Y229155D01*
Y230905D01*
G01X223855Y232338D02*
X223564Y232630D01*
X223397Y232880D01*
X223314Y233213D01*
X223397Y233505D01*
X223564Y233713D01*
X223814Y233880D01*
X224105Y233922D01*
X224355Y233880D01*
X224605Y233713D01*
X224814Y233463D01*
X224897Y233172D01*
X224814Y232838D01*
X224564Y232547D01*
X224189Y232380D01*
X223772Y232338D01*
X223230Y232422D01*
X222939Y232547D01*
X222647Y232755D01*
X222439Y233047D01*
X222397Y233338D01*
X222480Y233630D01*
X222689Y233838D01*
G01X224897Y236147D02*
X224355Y236230D01*
X223897Y236355D01*
X223480Y236522D01*
X223022Y236730D01*
X222397Y237063D01*
Y235397D01*
G01X228966Y226117D02*
X226466D01*
Y227158D01*
X226591Y227492D01*
X226758Y227700D01*
X227091Y227783D01*
X227424Y227700D01*
X227633Y227450D01*
X227758Y227158D01*
Y226117D01*
G01Y227158D02*
X228966Y227783D01*
G01X226883Y229258D02*
X226633Y229508D01*
X226508Y229800D01*
X226466Y230133D01*
X226549Y230550D01*
X226758Y230842D01*
X227008Y230925D01*
X227258Y230883D01*
X227466Y230717D01*
X227883Y229883D01*
X228174Y229508D01*
X228591Y229258D01*
X228966Y229175D01*
Y230925D01*
G01X227924Y232358D02*
X227633Y232650D01*
X227466Y232900D01*
X227383Y233233D01*
X227466Y233525D01*
X227633Y233733D01*
X227883Y233900D01*
X228174Y233942D01*
X228424Y233900D01*
X228674Y233733D01*
X228883Y233483D01*
X228966Y233192D01*
X228883Y232858D01*
X228633Y232567D01*
X228258Y232400D01*
X227841Y232358D01*
X227299Y232442D01*
X227008Y232567D01*
X226716Y232775D01*
X226508Y233067D01*
X226466Y233358D01*
X226549Y233650D01*
X226758Y233858D01*
G01X228591Y235333D02*
X228799Y235583D01*
X228924Y235875D01*
X228966Y236250D01*
X228883Y236625D01*
X228716Y236917D01*
X228424Y237125D01*
X228091Y237167D01*
X227758Y237083D01*
X227549Y236875D01*
X227383Y236583D01*
X227341Y236292D01*
X227383Y236000D01*
X227549Y235625D01*
X226466Y235750D01*
Y236875D01*
G01X230574Y227767D02*
X230449Y227517D01*
X230366Y227225D01*
Y226892D01*
X230491Y226517D01*
X230699Y226225D01*
X230949Y226017D01*
X231366Y225850D01*
X231741Y225808D01*
X232116Y225892D01*
X232366Y226017D01*
X232616Y226267D01*
X232783Y226558D01*
X232866Y226850D01*
Y227142D01*
X232783Y227433D01*
X232658Y227683D01*
X232491Y227892D01*
G01X230783Y229158D02*
X230533Y229408D01*
X230408Y229700D01*
X230366Y230033D01*
X230449Y230450D01*
X230658Y230742D01*
X230908Y230825D01*
X231158Y230783D01*
X231366Y230617D01*
X231783Y229783D01*
X232074Y229408D01*
X232491Y229158D01*
X232866Y229075D01*
Y230825D01*
G01Y233050D02*
X232824Y233342D01*
X232699Y233675D01*
X232491Y233883D01*
X232199Y233967D01*
X231908Y233883D01*
X231658Y233633D01*
X231533Y233258D01*
Y232842D01*
X231449Y232592D01*
X231241Y232383D01*
X230949Y232300D01*
X230658Y232425D01*
X230449Y232717D01*
X230366Y233050D01*
X230449Y233383D01*
X230658Y233675D01*
X230949Y233800D01*
X231241Y233717D01*
X231449Y233508D01*
X231533Y233258D01*
Y232842D01*
X231658Y232467D01*
X231908Y232217D01*
X232199Y232133D01*
X232491Y232217D01*
X232699Y232425D01*
X232824Y232758D01*
X232866Y233050D01*
G01Y236650D02*
X230366D01*
X232158Y235108D01*
Y237192D01*
G01X221397Y211724D02*
X223189D01*
X223564Y211891D01*
X223814Y212224D01*
X223897Y212641D01*
X223814Y213058D01*
X223564Y213391D01*
X223189Y213558D01*
X221397D01*
G01X223897Y216241D02*
X221397D01*
X223189Y214699D01*
Y216783D01*
G01X223897Y219341D02*
X221397D01*
X223189Y217799D01*
Y219883D01*
G01X207618Y225606D02*
X211218Y229206D01*
G01X207618Y225606D02*
X211218Y222006D01*
G01Y216206D02*
Y243606D01*
G01X222631Y239080D02*
X284831D01*
Y289480D01*
X222631D01*
Y239080D01*
G01X227440Y209737D02*
X227648Y210070D01*
X227773Y210445D01*
Y210779D01*
X227648Y211112D01*
X227440Y211362D01*
X227148Y211487D01*
X226856Y211404D01*
X226606Y211195D01*
X226440Y210820D01*
X226356Y210320D01*
X226190Y210029D01*
X225898Y209904D01*
X225606Y209987D01*
X225398Y210195D01*
X225273Y210487D01*
Y210779D01*
X225356Y211070D01*
X225565Y211320D01*
G01X227773Y212795D02*
X225273D01*
G01Y214379D02*
X226815Y212795D01*
G01X227773Y214629D02*
X226106Y213504D01*
G01X225273Y216812D02*
X227773D01*
G01X225273Y215854D02*
Y217770D01*
G01X226731Y219120D02*
X226440Y219412D01*
X226273Y219662D01*
X226190Y219995D01*
X226273Y220287D01*
X226440Y220495D01*
X226690Y220662D01*
X226981Y220704D01*
X227231Y220662D01*
X227481Y220495D01*
X227690Y220245D01*
X227773Y219954D01*
X227690Y219620D01*
X227440Y219329D01*
X227065Y219162D01*
X226648Y219120D01*
X226106Y219204D01*
X225815Y219329D01*
X225523Y219537D01*
X225315Y219829D01*
X225273Y220120D01*
X225356Y220412D01*
X225565Y220620D01*
G01X219918Y222606D02*
X216918Y225606D01*
X219918Y228606D01*
G01X210517Y249700D02*
Y252200D01*
X211558D01*
X211892Y252075D01*
X212100Y251908D01*
X212183Y251575D01*
X212100Y251242D01*
X211850Y251033D01*
X211558Y250908D01*
X210517D01*
G01X211558D02*
X212183Y249700D01*
G01X213533Y250075D02*
X213783Y249867D01*
X214075Y249742D01*
X214450Y249700D01*
X214825Y249783D01*
X215117Y249950D01*
X215325Y250242D01*
X215367Y250575D01*
X215283Y250908D01*
X215075Y251117D01*
X214783Y251283D01*
X214492Y251325D01*
X214200Y251283D01*
X213825Y251117D01*
X213950Y252200D01*
X215075D01*
G01X217550D02*
X217217Y252117D01*
X216967Y251908D01*
X216800Y251658D01*
X216675Y251325D01*
X216633Y250950D01*
X216675Y250575D01*
X216800Y250242D01*
X216967Y249992D01*
X217217Y249783D01*
X217550Y249700D01*
X217883Y249783D01*
X218133Y249992D01*
X218300Y250242D01*
X218425Y250575D01*
X218467Y250950D01*
X218425Y251325D01*
X218300Y251658D01*
X218133Y251908D01*
X217883Y252117D01*
X217550Y252200D01*
G01X220650Y249700D02*
Y252200D01*
X220150Y251700D01*
G01Y249700D02*
X221150D01*
G01X200900Y253000D02*
Y249000D01*
X208300D01*
G01X210700Y283950D02*
X211533D01*
Y283200D01*
X211283Y282950D01*
X210992Y282783D01*
X210575Y282700D01*
X210158Y282783D01*
X209867Y282950D01*
X209617Y283200D01*
X209450Y283492D01*
X209367Y283825D01*
Y284117D01*
X209450Y284367D01*
X209617Y284658D01*
X209867Y284908D01*
X210117Y285075D01*
X210450Y285200D01*
X210742D01*
X211075Y285117D01*
X211325Y284950D01*
G01X212592Y282700D02*
Y285200D01*
X214508Y282700D01*
Y285200D01*
G01X215733Y282700D02*
Y285200D01*
X216567D01*
X216900Y285075D01*
X217150Y284908D01*
X217358Y284658D01*
X217525Y284367D01*
X217567Y283950D01*
X217525Y283533D01*
X217358Y283242D01*
X217150Y282992D01*
X216900Y282825D01*
X216567Y282700D01*
X215733D01*
G01X201217Y282600D02*
Y285100D01*
X202258D01*
X202592Y284975D01*
X202800Y284808D01*
X202883Y284475D01*
X202800Y284142D01*
X202550Y283933D01*
X202258Y283808D01*
X201217D01*
G01X202258D02*
X202883Y282600D01*
G01X204275D02*
X206025Y285100D01*
G01X204275D02*
X206025Y282600D01*
G01X210611Y293158D02*
Y295658D01*
X211652D01*
X211986Y295533D01*
X212194Y295366D01*
X212277Y295033D01*
X212194Y294700D01*
X211944Y294491D01*
X211652Y294366D01*
X210611D01*
G01X211652D02*
X212277Y293158D01*
G01X213836Y293450D02*
X214127Y293241D01*
X214461Y293158D01*
X214794Y293241D01*
X215086Y293491D01*
X215294Y293866D01*
X215377Y294241D01*
Y294700D01*
X215294Y295075D01*
X215086Y295408D01*
X214836Y295575D01*
X214544Y295658D01*
X214211Y295575D01*
X213961Y295408D01*
X213794Y295158D01*
X213711Y294825D01*
X213794Y294533D01*
X214002Y294241D01*
X214252Y294075D01*
X214544Y294033D01*
X214877Y294116D01*
X215127Y294325D01*
X215377Y294700D01*
G01X218144Y293158D02*
Y295658D01*
X216602Y293866D01*
X218686D01*
G01X220744Y293158D02*
Y295658D01*
X220244Y295158D01*
G01Y293158D02*
X221244D01*
G01X232016Y295326D02*
X232349Y295118D01*
X232724Y294993D01*
X233058D01*
X233391Y295118D01*
X233641Y295326D01*
X233766Y295618D01*
X233683Y295910D01*
X233474Y296160D01*
X233099Y296326D01*
X232599Y296410D01*
X232308Y296576D01*
X232183Y296868D01*
X232266Y297160D01*
X232474Y297368D01*
X232766Y297493D01*
X233058D01*
X233349Y297410D01*
X233599Y297201D01*
G01X235074Y294993D02*
Y297493D01*
G01X236658D02*
X235074Y295951D01*
G01X236908Y294993D02*
X235783Y296660D01*
G01X239091Y297493D02*
Y294993D01*
G01X238133Y297493D02*
X240049D01*
G01X241274Y295493D02*
X241524Y295201D01*
X241858Y295035D01*
X242233Y294993D01*
X242566Y295035D01*
X242899Y295243D01*
X243108Y295493D01*
X243149Y295743D01*
X243066Y296035D01*
X242774Y296243D01*
X242483Y296326D01*
X242108D01*
G01X242483D02*
X242733Y296451D01*
X242941Y296660D01*
X243024Y296910D01*
X242941Y297160D01*
X242733Y297368D01*
X242358Y297493D01*
X241983Y297451D01*
X241608Y297285D01*
G01X208775Y288733D02*
X209108Y288525D01*
X209483Y288400D01*
X209817D01*
X210150Y288525D01*
X210400Y288733D01*
X210525Y289025D01*
X210442Y289317D01*
X210233Y289567D01*
X209858Y289733D01*
X209358Y289817D01*
X209067Y289983D01*
X208942Y290275D01*
X209025Y290567D01*
X209233Y290775D01*
X209525Y290900D01*
X209817D01*
X210108Y290817D01*
X210358Y290608D01*
G01X213667Y290692D02*
X213417Y290817D01*
X213125Y290900D01*
X212792D01*
X212417Y290775D01*
X212125Y290567D01*
X211917Y290317D01*
X211750Y289900D01*
X211708Y289525D01*
X211792Y289150D01*
X211917Y288900D01*
X212167Y288650D01*
X212458Y288483D01*
X212750Y288400D01*
X213042D01*
X213333Y288483D01*
X213583Y288608D01*
X213792Y288775D01*
G01X214892Y288400D02*
Y290900D01*
X216808Y288400D01*
Y290900D01*
G01X218950Y288400D02*
X219242Y288442D01*
X219575Y288567D01*
X219783Y288775D01*
X219867Y289067D01*
X219783Y289358D01*
X219533Y289608D01*
X219158Y289733D01*
X218742D01*
X218492Y289817D01*
X218283Y290025D01*
X218200Y290317D01*
X218325Y290608D01*
X218617Y290817D01*
X218950Y290900D01*
X219283Y290817D01*
X219575Y290608D01*
X219700Y290317D01*
X219617Y290025D01*
X219408Y289817D01*
X219158Y289733D01*
X218742D01*
X218367Y289608D01*
X218117Y289358D01*
X218033Y289067D01*
X218117Y288775D01*
X218325Y288567D01*
X218658Y288442D01*
X218950Y288400D01*
G01X233852Y361109D02*
X203933D01*
Y418300D01*
X236500D01*
Y398600D01*
X249100D01*
Y377102D01*
X235248D01*
Y361109D01*
X233852D01*
G01X224567Y373692D02*
X224317Y373817D01*
X224025Y373900D01*
X223692D01*
X223317Y373775D01*
X223025Y373567D01*
X222817Y373317D01*
X222650Y372900D01*
X222608Y372525D01*
X222692Y372150D01*
X222817Y371900D01*
X223067Y371650D01*
X223358Y371483D01*
X223650Y371400D01*
X223942D01*
X224233Y371483D01*
X224483Y371608D01*
X224692Y371775D01*
G01X226750Y371400D02*
Y373900D01*
X226250Y373400D01*
G01Y371400D02*
X227250D01*
G01X229850D02*
X230142Y371442D01*
X230475Y371567D01*
X230683Y371775D01*
X230767Y372067D01*
X230683Y372358D01*
X230433Y372608D01*
X230058Y372733D01*
X229642D01*
X229392Y372817D01*
X229183Y373025D01*
X229100Y373317D01*
X229225Y373608D01*
X229517Y373817D01*
X229850Y373900D01*
X230183Y373817D01*
X230475Y373608D01*
X230600Y373317D01*
X230517Y373025D01*
X230308Y372817D01*
X230058Y372733D01*
X229642D01*
X229267Y372608D01*
X229017Y372358D01*
X228933Y372067D01*
X229017Y371775D01*
X229225Y371567D01*
X229558Y371442D01*
X229850Y371400D01*
G01X232950D02*
X233242Y371442D01*
X233575Y371567D01*
X233783Y371775D01*
X233867Y372067D01*
X233783Y372358D01*
X233533Y372608D01*
X233158Y372733D01*
X232742D01*
X232492Y372817D01*
X232283Y373025D01*
X232200Y373317D01*
X232325Y373608D01*
X232617Y373817D01*
X232950Y373900D01*
X233283Y373817D01*
X233575Y373608D01*
X233700Y373317D01*
X233617Y373025D01*
X233408Y372817D01*
X233158Y372733D01*
X232742D01*
X232367Y372608D01*
X232117Y372358D01*
X232033Y372067D01*
X232117Y371775D01*
X232325Y371567D01*
X232658Y371442D01*
X232950Y371400D01*
G01X222486Y366634D02*
Y369134D01*
X223527D01*
X223861Y369009D01*
X224069Y368842D01*
X224152Y368509D01*
X224069Y368176D01*
X223819Y367967D01*
X223527Y367842D01*
X222486D01*
G01X223527D02*
X224152Y366634D01*
G01X225502Y367009D02*
X225752Y366801D01*
X226044Y366676D01*
X226419Y366634D01*
X226794Y366717D01*
X227086Y366884D01*
X227294Y367176D01*
X227336Y367509D01*
X227252Y367842D01*
X227044Y368051D01*
X226752Y368217D01*
X226461Y368259D01*
X226169Y368217D01*
X225794Y368051D01*
X225919Y369134D01*
X227044D01*
G01X229519Y366634D02*
X229811Y366676D01*
X230144Y366801D01*
X230352Y367009D01*
X230436Y367301D01*
X230352Y367592D01*
X230102Y367842D01*
X229727Y367967D01*
X229311D01*
X229061Y368051D01*
X228852Y368259D01*
X228769Y368551D01*
X228894Y368842D01*
X229186Y369051D01*
X229519Y369134D01*
X229852Y369051D01*
X230144Y368842D01*
X230269Y368551D01*
X230186Y368259D01*
X229977Y368051D01*
X229727Y367967D01*
X229311D01*
X228936Y367842D01*
X228686Y367592D01*
X228602Y367301D01*
X228686Y367009D01*
X228894Y366801D01*
X229227Y366676D01*
X229519Y366634D01*
G01X232619Y369134D02*
X232286Y369051D01*
X232036Y368842D01*
X231869Y368592D01*
X231744Y368259D01*
X231702Y367884D01*
X231744Y367509D01*
X231869Y367176D01*
X232036Y366926D01*
X232286Y366717D01*
X232619Y366634D01*
X232952Y366717D01*
X233202Y366926D01*
X233369Y367176D01*
X233494Y367509D01*
X233536Y367884D01*
X233494Y368259D01*
X233369Y368592D01*
X233202Y368842D01*
X232952Y369051D01*
X232619Y369134D01*
G01X220886Y362734D02*
Y365234D01*
X221927D01*
X222261Y365109D01*
X222469Y364942D01*
X222552Y364609D01*
X222469Y364276D01*
X222219Y364067D01*
X221927Y363942D01*
X220886D01*
G01X221927D02*
X222552Y362734D01*
G01X223902Y363109D02*
X224152Y362901D01*
X224444Y362776D01*
X224819Y362734D01*
X225194Y362817D01*
X225486Y362984D01*
X225694Y363276D01*
X225736Y363609D01*
X225652Y363942D01*
X225444Y364151D01*
X225152Y364317D01*
X224861Y364359D01*
X224569Y364317D01*
X224194Y364151D01*
X224319Y365234D01*
X225444D01*
G01X227919Y362734D02*
X228211Y362776D01*
X228544Y362901D01*
X228752Y363109D01*
X228836Y363401D01*
X228752Y363692D01*
X228502Y363942D01*
X228127Y364067D01*
X227711D01*
X227461Y364151D01*
X227252Y364359D01*
X227169Y364651D01*
X227294Y364942D01*
X227586Y365151D01*
X227919Y365234D01*
X228252Y365151D01*
X228544Y364942D01*
X228669Y364651D01*
X228586Y364359D01*
X228377Y364151D01*
X228127Y364067D01*
X227711D01*
X227336Y363942D01*
X227086Y363692D01*
X227002Y363401D01*
X227086Y363109D01*
X227294Y362901D01*
X227627Y362776D01*
X227919Y362734D01*
G01X231019D02*
Y365234D01*
X230519Y364734D01*
G01Y362734D02*
X231519D01*
G01X222717Y376300D02*
Y378800D01*
X223758D01*
X224092Y378675D01*
X224300Y378508D01*
X224383Y378175D01*
X224300Y377842D01*
X224050Y377633D01*
X223758Y377508D01*
X222717D01*
G01X223758D02*
X224383Y376300D01*
G01X225733Y376800D02*
X225983Y376508D01*
X226317Y376342D01*
X226692Y376300D01*
X227025Y376342D01*
X227358Y376550D01*
X227567Y376800D01*
X227608Y377050D01*
X227525Y377342D01*
X227233Y377550D01*
X226942Y377633D01*
X226567D01*
G01X226942D02*
X227192Y377758D01*
X227400Y377967D01*
X227483Y378217D01*
X227400Y378467D01*
X227192Y378675D01*
X226817Y378800D01*
X226442Y378758D01*
X226067Y378592D01*
G01X228833Y376800D02*
X229083Y376508D01*
X229417Y376342D01*
X229792Y376300D01*
X230125Y376342D01*
X230458Y376550D01*
X230667Y376800D01*
X230708Y377050D01*
X230625Y377342D01*
X230333Y377550D01*
X230042Y377633D01*
X229667D01*
G01X230042D02*
X230292Y377758D01*
X230500Y377967D01*
X230583Y378217D01*
X230500Y378467D01*
X230292Y378675D01*
X229917Y378800D01*
X229542Y378758D01*
X229167Y378592D01*
G01X232058Y377342D02*
X232350Y377633D01*
X232600Y377800D01*
X232933Y377883D01*
X233225Y377800D01*
X233433Y377633D01*
X233600Y377383D01*
X233642Y377092D01*
X233600Y376842D01*
X233433Y376592D01*
X233183Y376383D01*
X232892Y376300D01*
X232558Y376383D01*
X232267Y376633D01*
X232100Y377008D01*
X232058Y377425D01*
X232142Y377967D01*
X232267Y378258D01*
X232475Y378550D01*
X232767Y378758D01*
X233058Y378800D01*
X233350Y378717D01*
X233558Y378508D01*
G01X208186Y362734D02*
Y365234D01*
X209227D01*
X209561Y365109D01*
X209769Y364942D01*
X209852Y364609D01*
X209769Y364276D01*
X209519Y364067D01*
X209227Y363942D01*
X208186D01*
G01X209227D02*
X209852Y362734D01*
G01X212619D02*
Y365234D01*
X211077Y363442D01*
X213161D01*
G01X214427Y363776D02*
X214719Y364067D01*
X214969Y364234D01*
X215302Y364317D01*
X215594Y364234D01*
X215802Y364067D01*
X215969Y363817D01*
X216011Y363526D01*
X215969Y363276D01*
X215802Y363026D01*
X215552Y362817D01*
X215261Y362734D01*
X214927Y362817D01*
X214636Y363067D01*
X214469Y363442D01*
X214427Y363859D01*
X214511Y364401D01*
X214636Y364692D01*
X214844Y364984D01*
X215136Y365192D01*
X215427Y365234D01*
X215719Y365151D01*
X215927Y364942D01*
G01X218319Y365234D02*
X217986Y365151D01*
X217736Y364942D01*
X217569Y364692D01*
X217444Y364359D01*
X217402Y363984D01*
X217444Y363609D01*
X217569Y363276D01*
X217736Y363026D01*
X217986Y362817D01*
X218319Y362734D01*
X218652Y362817D01*
X218902Y363026D01*
X219069Y363276D01*
X219194Y363609D01*
X219236Y363984D01*
X219194Y364359D01*
X219069Y364692D01*
X218902Y364942D01*
X218652Y365151D01*
X218319Y365234D01*
G01X209786Y366634D02*
Y369134D01*
X210827D01*
X211161Y369009D01*
X211369Y368842D01*
X211452Y368509D01*
X211369Y368176D01*
X211119Y367967D01*
X210827Y367842D01*
X209786D01*
G01X210827D02*
X211452Y366634D01*
G01X214219D02*
Y369134D01*
X212677Y367342D01*
X214761D01*
G01X216027Y367676D02*
X216319Y367967D01*
X216569Y368134D01*
X216902Y368217D01*
X217194Y368134D01*
X217402Y367967D01*
X217569Y367717D01*
X217611Y367426D01*
X217569Y367176D01*
X217402Y366926D01*
X217152Y366717D01*
X216861Y366634D01*
X216527Y366717D01*
X216236Y366967D01*
X216069Y367342D01*
X216027Y367759D01*
X216111Y368301D01*
X216236Y368592D01*
X216444Y368884D01*
X216736Y369092D01*
X217027Y369134D01*
X217319Y369051D01*
X217527Y368842D01*
G01X219919Y366634D02*
Y369134D01*
X219419Y368634D01*
G01Y366634D02*
X220419D01*
G01X206967Y394900D02*
Y392400D01*
G01X206009Y394900D02*
X207925D01*
G01X209234Y392400D02*
Y394900D01*
X210234D01*
X210567Y394775D01*
X210817Y394483D01*
X210900Y394150D01*
X210817Y393817D01*
X210609Y393567D01*
X210234Y393442D01*
X209234D01*
G01X213167Y392400D02*
Y394900D01*
X212667Y394400D01*
G01Y392400D02*
X213667D01*
G01X216184D02*
X216267Y392942D01*
X216392Y393400D01*
X216559Y393817D01*
X216767Y394275D01*
X217100Y394900D01*
X215434D01*
G01X219367Y392400D02*
X219659Y392442D01*
X219992Y392567D01*
X220200Y392775D01*
X220284Y393067D01*
X220200Y393358D01*
X219950Y393608D01*
X219575Y393733D01*
X219159D01*
X218909Y393817D01*
X218700Y394025D01*
X218617Y394317D01*
X218742Y394608D01*
X219034Y394817D01*
X219367Y394900D01*
X219700Y394817D01*
X219992Y394608D01*
X220117Y394317D01*
X220034Y394025D01*
X219825Y393817D01*
X219575Y393733D01*
X219159D01*
X218784Y393608D01*
X218534Y393358D01*
X218450Y393067D01*
X218534Y392775D01*
X218742Y392567D01*
X219075Y392442D01*
X219367Y392400D01*
G01X207203Y389724D02*
Y387224D01*
G01X206245Y389724D02*
X208161D01*
G01X209470Y387224D02*
Y389724D01*
X210470D01*
X210803Y389599D01*
X211053Y389307D01*
X211136Y388974D01*
X211053Y388641D01*
X210845Y388391D01*
X210470Y388266D01*
X209470D01*
G01X213403Y387224D02*
Y389724D01*
X212903Y389224D01*
G01Y387224D02*
X213903D01*
G01X216420D02*
X216503Y387766D01*
X216628Y388224D01*
X216795Y388641D01*
X217003Y389099D01*
X217336Y389724D01*
X215670D01*
G01X218811Y389307D02*
X219061Y389557D01*
X219353Y389682D01*
X219686Y389724D01*
X220103Y389641D01*
X220395Y389432D01*
X220478Y389182D01*
X220436Y388932D01*
X220270Y388724D01*
X219436Y388307D01*
X219061Y388016D01*
X218811Y387599D01*
X218728Y387224D01*
X220478D01*
G01X207497Y384665D02*
Y382165D01*
G01X206539Y384665D02*
X208455D01*
G01X209764Y382165D02*
Y384665D01*
X210764D01*
X211097Y384540D01*
X211347Y384248D01*
X211430Y383915D01*
X211347Y383582D01*
X211139Y383332D01*
X210764Y383207D01*
X209764D01*
G01X213697Y382165D02*
Y384665D01*
X213197Y384165D01*
G01Y382165D02*
X214197D01*
G01X216714D02*
X216797Y382707D01*
X216922Y383165D01*
X217089Y383582D01*
X217297Y384040D01*
X217630Y384665D01*
X215964D01*
G01X218980Y382665D02*
X219230Y382373D01*
X219564Y382207D01*
X219939Y382165D01*
X220272Y382207D01*
X220605Y382415D01*
X220814Y382665D01*
X220855Y382915D01*
X220772Y383207D01*
X220480Y383415D01*
X220189Y383498D01*
X219814D01*
G01X220189D02*
X220439Y383623D01*
X220647Y383832D01*
X220730Y384082D01*
X220647Y384332D01*
X220439Y384540D01*
X220064Y384665D01*
X219689Y384623D01*
X219314Y384457D01*
G01X207084Y399017D02*
Y396517D01*
G01X206126Y399017D02*
X208042D01*
G01X209351Y396517D02*
Y399017D01*
X210351D01*
X210684Y398892D01*
X210934Y398600D01*
X211017Y398267D01*
X210934Y397934D01*
X210726Y397684D01*
X210351Y397559D01*
X209351D01*
G01X213284Y396517D02*
Y399017D01*
X212784Y398517D01*
G01Y396517D02*
X213784D01*
G01X216301D02*
X216384Y397059D01*
X216509Y397517D01*
X216676Y397934D01*
X216884Y398392D01*
X217217Y399017D01*
X215551D01*
G01X219401Y396517D02*
X219484Y397059D01*
X219609Y397517D01*
X219776Y397934D01*
X219984Y398392D01*
X220317Y399017D01*
X218651D01*
G01X222617Y397400D02*
Y399900D01*
X223658D01*
X223992Y399775D01*
X224200Y399608D01*
X224283Y399275D01*
X224200Y398942D01*
X223950Y398733D01*
X223658Y398608D01*
X222617D01*
G01X223658D02*
X224283Y397400D01*
G01X227050D02*
Y399900D01*
X225508Y398108D01*
X227592D01*
G01X228733Y397775D02*
X228983Y397567D01*
X229275Y397442D01*
X229650Y397400D01*
X230025Y397483D01*
X230317Y397650D01*
X230525Y397942D01*
X230567Y398275D01*
X230483Y398608D01*
X230275Y398817D01*
X229983Y398983D01*
X229692Y399025D01*
X229400Y398983D01*
X229025Y398817D01*
X229150Y399900D01*
X230275D01*
G01X232750Y397400D02*
Y399900D01*
X232250Y399400D01*
G01Y397400D02*
X233250D01*
G01X222717Y401200D02*
Y403700D01*
X223758D01*
X224092Y403575D01*
X224300Y403408D01*
X224383Y403075D01*
X224300Y402742D01*
X224050Y402533D01*
X223758Y402408D01*
X222717D01*
G01X223758D02*
X224383Y401200D01*
G01X227150D02*
Y403700D01*
X225608Y401908D01*
X227692D01*
G01X228833Y401575D02*
X229083Y401367D01*
X229375Y401242D01*
X229750Y401200D01*
X230125Y401283D01*
X230417Y401450D01*
X230625Y401742D01*
X230667Y402075D01*
X230583Y402408D01*
X230375Y402617D01*
X230083Y402783D01*
X229792Y402825D01*
X229500Y402783D01*
X229125Y402617D01*
X229250Y403700D01*
X230375D01*
G01X232058Y403283D02*
X232308Y403533D01*
X232600Y403658D01*
X232933Y403700D01*
X233350Y403617D01*
X233642Y403408D01*
X233725Y403158D01*
X233683Y402908D01*
X233517Y402700D01*
X232683Y402283D01*
X232308Y401992D01*
X232058Y401575D01*
X231975Y401200D01*
X233725D01*
G01X222717Y380300D02*
Y382800D01*
X223758D01*
X224092Y382675D01*
X224300Y382508D01*
X224383Y382175D01*
X224300Y381842D01*
X224050Y381633D01*
X223758Y381508D01*
X222717D01*
G01X223758D02*
X224383Y380300D01*
G01X226650D02*
X226942Y380342D01*
X227275Y380467D01*
X227483Y380675D01*
X227567Y380967D01*
X227483Y381258D01*
X227233Y381508D01*
X226858Y381633D01*
X226442D01*
X226192Y381717D01*
X225983Y381925D01*
X225900Y382217D01*
X226025Y382508D01*
X226317Y382717D01*
X226650Y382800D01*
X226983Y382717D01*
X227275Y382508D01*
X227400Y382217D01*
X227317Y381925D01*
X227108Y381717D01*
X226858Y381633D01*
X226442D01*
X226067Y381508D01*
X225817Y381258D01*
X225733Y380967D01*
X225817Y380675D01*
X226025Y380467D01*
X226358Y380342D01*
X226650Y380300D01*
G01X229750Y382800D02*
X229417Y382717D01*
X229167Y382508D01*
X229000Y382258D01*
X228875Y381925D01*
X228833Y381550D01*
X228875Y381175D01*
X229000Y380842D01*
X229167Y380592D01*
X229417Y380383D01*
X229750Y380300D01*
X230083Y380383D01*
X230333Y380592D01*
X230500Y380842D01*
X230625Y381175D01*
X230667Y381550D01*
X230625Y381925D01*
X230500Y382258D01*
X230333Y382508D01*
X230083Y382717D01*
X229750Y382800D01*
G01X232850Y380300D02*
Y382800D01*
X232350Y382300D01*
G01Y380300D02*
X233350D01*
G01X222717Y384300D02*
Y386800D01*
X223758D01*
X224092Y386675D01*
X224300Y386508D01*
X224383Y386175D01*
X224300Y385842D01*
X224050Y385633D01*
X223758Y385508D01*
X222717D01*
G01X223758D02*
X224383Y384300D01*
G01X226650D02*
X226942Y384342D01*
X227275Y384467D01*
X227483Y384675D01*
X227567Y384967D01*
X227483Y385258D01*
X227233Y385508D01*
X226858Y385633D01*
X226442D01*
X226192Y385717D01*
X225983Y385925D01*
X225900Y386217D01*
X226025Y386508D01*
X226317Y386717D01*
X226650Y386800D01*
X226983Y386717D01*
X227275Y386508D01*
X227400Y386217D01*
X227317Y385925D01*
X227108Y385717D01*
X226858Y385633D01*
X226442D01*
X226067Y385508D01*
X225817Y385258D01*
X225733Y384967D01*
X225817Y384675D01*
X226025Y384467D01*
X226358Y384342D01*
X226650Y384300D01*
G01X229750Y386800D02*
X229417Y386717D01*
X229167Y386508D01*
X229000Y386258D01*
X228875Y385925D01*
X228833Y385550D01*
X228875Y385175D01*
X229000Y384842D01*
X229167Y384592D01*
X229417Y384383D01*
X229750Y384300D01*
X230083Y384383D01*
X230333Y384592D01*
X230500Y384842D01*
X230625Y385175D01*
X230667Y385550D01*
X230625Y385925D01*
X230500Y386258D01*
X230333Y386508D01*
X230083Y386717D01*
X229750Y386800D01*
G01X232058Y386383D02*
X232308Y386633D01*
X232600Y386758D01*
X232933Y386800D01*
X233350Y386717D01*
X233642Y386508D01*
X233725Y386258D01*
X233683Y386008D01*
X233517Y385800D01*
X232683Y385383D01*
X232308Y385092D01*
X232058Y384675D01*
X231975Y384300D01*
X233725D01*
G01X222817Y392700D02*
Y395200D01*
X223858D01*
X224192Y395075D01*
X224400Y394908D01*
X224483Y394575D01*
X224400Y394242D01*
X224150Y394033D01*
X223858Y393908D01*
X222817D01*
G01X223858D02*
X224483Y392700D01*
G01X226750D02*
X227042Y392742D01*
X227375Y392867D01*
X227583Y393075D01*
X227667Y393367D01*
X227583Y393658D01*
X227333Y393908D01*
X226958Y394033D01*
X226542D01*
X226292Y394117D01*
X226083Y394325D01*
X226000Y394617D01*
X226125Y394908D01*
X226417Y395117D01*
X226750Y395200D01*
X227083Y395117D01*
X227375Y394908D01*
X227500Y394617D01*
X227417Y394325D01*
X227208Y394117D01*
X226958Y394033D01*
X226542D01*
X226167Y393908D01*
X225917Y393658D01*
X225833Y393367D01*
X225917Y393075D01*
X226125Y392867D01*
X226458Y392742D01*
X226750Y392700D01*
G01X229850Y395200D02*
X229517Y395117D01*
X229267Y394908D01*
X229100Y394658D01*
X228975Y394325D01*
X228933Y393950D01*
X228975Y393575D01*
X229100Y393242D01*
X229267Y392992D01*
X229517Y392783D01*
X229850Y392700D01*
X230183Y392783D01*
X230433Y392992D01*
X230600Y393242D01*
X230725Y393575D01*
X230767Y393950D01*
X230725Y394325D01*
X230600Y394658D01*
X230433Y394908D01*
X230183Y395117D01*
X229850Y395200D01*
G01X232033Y393200D02*
X232283Y392908D01*
X232617Y392742D01*
X232992Y392700D01*
X233325Y392742D01*
X233658Y392950D01*
X233867Y393200D01*
X233908Y393450D01*
X233825Y393742D01*
X233533Y393950D01*
X233242Y394033D01*
X232867D01*
G01X233242D02*
X233492Y394158D01*
X233700Y394367D01*
X233783Y394617D01*
X233700Y394867D01*
X233492Y395075D01*
X233117Y395200D01*
X232742Y395158D01*
X232367Y394992D01*
G01X222717Y388300D02*
Y390800D01*
X223758D01*
X224092Y390675D01*
X224300Y390508D01*
X224383Y390175D01*
X224300Y389842D01*
X224050Y389633D01*
X223758Y389508D01*
X222717D01*
G01X223758D02*
X224383Y388300D01*
G01X226650D02*
X226942Y388342D01*
X227275Y388467D01*
X227483Y388675D01*
X227567Y388967D01*
X227483Y389258D01*
X227233Y389508D01*
X226858Y389633D01*
X226442D01*
X226192Y389717D01*
X225983Y389925D01*
X225900Y390217D01*
X226025Y390508D01*
X226317Y390717D01*
X226650Y390800D01*
X226983Y390717D01*
X227275Y390508D01*
X227400Y390217D01*
X227317Y389925D01*
X227108Y389717D01*
X226858Y389633D01*
X226442D01*
X226067Y389508D01*
X225817Y389258D01*
X225733Y388967D01*
X225817Y388675D01*
X226025Y388467D01*
X226358Y388342D01*
X226650Y388300D01*
G01X229750Y390800D02*
X229417Y390717D01*
X229167Y390508D01*
X229000Y390258D01*
X228875Y389925D01*
X228833Y389550D01*
X228875Y389175D01*
X229000Y388842D01*
X229167Y388592D01*
X229417Y388383D01*
X229750Y388300D01*
X230083Y388383D01*
X230333Y388592D01*
X230500Y388842D01*
X230625Y389175D01*
X230667Y389550D01*
X230625Y389925D01*
X230500Y390258D01*
X230333Y390508D01*
X230083Y390717D01*
X229750Y390800D01*
G01X233350Y388300D02*
Y390800D01*
X231808Y389008D01*
X233892D01*
G01X228916Y407391D02*
X228791Y407141D01*
X228708Y406849D01*
Y406516D01*
X228833Y406141D01*
X229041Y405849D01*
X229291Y405641D01*
X229708Y405474D01*
X230083Y405432D01*
X230458Y405516D01*
X230708Y405641D01*
X230958Y405891D01*
X231125Y406182D01*
X231208Y406474D01*
Y406766D01*
X231125Y407057D01*
X231000Y407307D01*
X230833Y407516D01*
G01X231208Y409574D02*
X228708D01*
X229208Y409074D01*
G01X231208D02*
Y410074D01*
G01X230916Y411966D02*
X231125Y412257D01*
X231208Y412591D01*
X231125Y412924D01*
X230875Y413216D01*
X230500Y413424D01*
X230125Y413507D01*
X229666D01*
X229291Y413424D01*
X228958Y413216D01*
X228791Y412966D01*
X228708Y412674D01*
X228791Y412341D01*
X228958Y412091D01*
X229208Y411924D01*
X229541Y411841D01*
X229833Y411924D01*
X230125Y412132D01*
X230291Y412382D01*
X230333Y412674D01*
X230250Y413007D01*
X230041Y413257D01*
X229666Y413507D01*
G01X229125Y414982D02*
X228875Y415232D01*
X228750Y415524D01*
X228708Y415857D01*
X228791Y416274D01*
X229000Y416566D01*
X229250Y416649D01*
X229500Y416607D01*
X229708Y416441D01*
X230125Y415607D01*
X230416Y415232D01*
X230833Y414982D01*
X231208Y414899D01*
Y416649D01*
G01X223916Y407391D02*
X223791Y407141D01*
X223708Y406849D01*
Y406516D01*
X223833Y406141D01*
X224041Y405849D01*
X224291Y405641D01*
X224708Y405474D01*
X225083Y405432D01*
X225458Y405516D01*
X225708Y405641D01*
X225958Y405891D01*
X226125Y406182D01*
X226208Y406474D01*
Y406766D01*
X226125Y407057D01*
X226000Y407307D01*
X225833Y407516D01*
G01X226208Y409574D02*
X223708D01*
X224208Y409074D01*
G01X226208D02*
Y410074D01*
G01Y412674D02*
X226166Y412966D01*
X226041Y413299D01*
X225833Y413507D01*
X225541Y413591D01*
X225250Y413507D01*
X225000Y413257D01*
X224875Y412882D01*
Y412466D01*
X224791Y412216D01*
X224583Y412007D01*
X224291Y411924D01*
X224000Y412049D01*
X223791Y412341D01*
X223708Y412674D01*
X223791Y413007D01*
X224000Y413299D01*
X224291Y413424D01*
X224583Y413341D01*
X224791Y413132D01*
X224875Y412882D01*
Y412466D01*
X225000Y412091D01*
X225250Y411841D01*
X225541Y411757D01*
X225833Y411841D01*
X226041Y412049D01*
X226166Y412382D01*
X226208Y412674D01*
G01X225916Y415066D02*
X226125Y415357D01*
X226208Y415691D01*
X226125Y416024D01*
X225875Y416316D01*
X225500Y416524D01*
X225125Y416607D01*
X224666D01*
X224291Y416524D01*
X223958Y416316D01*
X223791Y416066D01*
X223708Y415774D01*
X223791Y415441D01*
X223958Y415191D01*
X224208Y415024D01*
X224541Y414941D01*
X224833Y415024D01*
X225125Y415232D01*
X225291Y415482D01*
X225333Y415774D01*
X225250Y416107D01*
X225041Y416357D01*
X224666Y416607D01*
G01X220108Y407667D02*
X219983Y407417D01*
X219900Y407125D01*
Y406792D01*
X220025Y406417D01*
X220233Y406125D01*
X220483Y405917D01*
X220900Y405750D01*
X221275Y405708D01*
X221650Y405792D01*
X221900Y405917D01*
X222150Y406167D01*
X222317Y406458D01*
X222400Y406750D01*
Y407042D01*
X222317Y407333D01*
X222192Y407583D01*
X222025Y407792D01*
G01X222400Y409850D02*
X219900D01*
X220400Y409350D01*
G01X222400D02*
Y410350D01*
G01X222108Y412242D02*
X222317Y412533D01*
X222400Y412867D01*
X222317Y413200D01*
X222067Y413492D01*
X221692Y413700D01*
X221317Y413783D01*
X220858D01*
X220483Y413700D01*
X220150Y413492D01*
X219983Y413242D01*
X219900Y412950D01*
X219983Y412617D01*
X220150Y412367D01*
X220400Y412200D01*
X220733Y412117D01*
X221025Y412200D01*
X221317Y412408D01*
X221483Y412658D01*
X221525Y412950D01*
X221442Y413283D01*
X221233Y413533D01*
X220858Y413783D01*
G01X222400Y416050D02*
X219900D01*
X220400Y415550D01*
G01X222400D02*
Y416550D01*
G01X232949Y418300D02*
Y431900D01*
X226085D01*
Y455977D01*
G01X239800Y435600D02*
X231200D01*
G01D02*
Y502400D01*
G01X218338Y439545D02*
X204938D01*
G01D02*
Y428145D01*
G01D02*
X218338D01*
G01D02*
Y439545D01*
G01X215438Y423645D02*
Y427645D01*
X208038D01*
G01X222969Y440372D02*
X218969D01*
Y432972D01*
G01X215238Y439945D02*
Y443945D01*
X207838D01*
G01X211500Y448000D02*
Y444000D01*
X218900D01*
G01X211400D02*
Y448000D01*
X204000D01*
G01X206600Y465095D02*
Y461400D01*
X230500D01*
Y499500D01*
G01X226100Y460307D02*
X227600Y458807D01*
X224600D01*
X226100Y460307D01*
G01X204094Y477593D02*
X206600D01*
Y470286D01*
G01X226085Y455977D02*
Y460207D01*
G01X217800Y471000D02*
Y467000D01*
X225200D01*
G01X217800D02*
Y463000D01*
X225200D01*
G01X207800Y480000D02*
Y476000D01*
X215200D01*
G01Y463000D02*
Y467000D01*
X207800D01*
G01X215200D02*
Y471000D01*
X207800D01*
G01X211400Y455500D02*
X207400D01*
Y448100D01*
G01X215500Y455500D02*
X211500D01*
Y448100D01*
G01X205900Y452817D02*
X203400D01*
Y453858D01*
X203525Y454192D01*
X203692Y454400D01*
X204025Y454483D01*
X204358Y454400D01*
X204567Y454150D01*
X204692Y453858D01*
Y452817D01*
G01Y453858D02*
X205900Y454483D01*
G01Y456750D02*
X205858Y457042D01*
X205733Y457375D01*
X205525Y457583D01*
X205233Y457667D01*
X204942Y457583D01*
X204692Y457333D01*
X204567Y456958D01*
Y456542D01*
X204483Y456292D01*
X204275Y456083D01*
X203983Y456000D01*
X203692Y456125D01*
X203483Y456417D01*
X203400Y456750D01*
X203483Y457083D01*
X203692Y457375D01*
X203983Y457500D01*
X204275Y457417D01*
X204483Y457208D01*
X204567Y456958D01*
Y456542D01*
X204692Y456167D01*
X204942Y455917D01*
X205233Y455833D01*
X205525Y455917D01*
X205733Y456125D01*
X205858Y456458D01*
X205900Y456750D01*
G01X203400Y459850D02*
X203483Y459517D01*
X203692Y459267D01*
X203942Y459100D01*
X204275Y458975D01*
X204650Y458933D01*
X205025Y458975D01*
X205358Y459100D01*
X205608Y459267D01*
X205817Y459517D01*
X205900Y459850D01*
X205817Y460183D01*
X205608Y460433D01*
X205358Y460600D01*
X205025Y460725D01*
X204650Y460767D01*
X204275Y460725D01*
X203942Y460600D01*
X203692Y460433D01*
X203483Y460183D01*
X203400Y459850D01*
G01X204858Y462158D02*
X204567Y462450D01*
X204400Y462700D01*
X204317Y463033D01*
X204400Y463325D01*
X204567Y463533D01*
X204817Y463700D01*
X205108Y463742D01*
X205358Y463700D01*
X205608Y463533D01*
X205817Y463283D01*
X205900Y462992D01*
X205817Y462658D01*
X205567Y462367D01*
X205192Y462200D01*
X204775Y462158D01*
X204233Y462242D01*
X203942Y462367D01*
X203650Y462575D01*
X203442Y462867D01*
X203400Y463158D01*
X203483Y463450D01*
X203692Y463658D01*
G01X202300Y452717D02*
X199800D01*
Y453758D01*
X199925Y454092D01*
X200092Y454300D01*
X200425Y454383D01*
X200758Y454300D01*
X200967Y454050D01*
X201092Y453758D01*
Y452717D01*
G01Y453758D02*
X202300Y454383D01*
G01X200217Y455858D02*
X199967Y456108D01*
X199842Y456400D01*
X199800Y456733D01*
X199883Y457150D01*
X200092Y457442D01*
X200342Y457525D01*
X200592Y457483D01*
X200800Y457317D01*
X201217Y456483D01*
X201508Y456108D01*
X201925Y455858D01*
X202300Y455775D01*
Y457525D01*
G01X200217Y458958D02*
X199967Y459208D01*
X199842Y459500D01*
X199800Y459833D01*
X199883Y460250D01*
X200092Y460542D01*
X200342Y460625D01*
X200592Y460583D01*
X200800Y460417D01*
X201217Y459583D01*
X201508Y459208D01*
X201925Y458958D01*
X202300Y458875D01*
Y460625D01*
G01Y463350D02*
X199800D01*
X201592Y461808D01*
Y463892D01*
G01X206600Y507500D02*
Y515400D01*
X206800D01*
G01D02*
X227600D01*
Y501500D01*
G01X199697Y481857D02*
X201285D01*
Y479916D01*
G01X231200Y502400D02*
X239800D01*
G01X241700Y513000D02*
Y506000D01*
X228300D01*
Y513000D01*
X241700D01*
G01X216300Y488600D02*
Y484600D01*
X223700D01*
G01X207800Y504000D02*
Y500000D01*
X215200D01*
G01X207800Y508000D02*
Y504000D01*
X215200D01*
G01Y480000D02*
Y484000D01*
X207800D01*
G01X215200D02*
Y488000D01*
X207800D01*
G01X215300Y492400D02*
Y496400D01*
X207900D01*
G01X215200Y488000D02*
Y492000D01*
X207800D01*
G01X221950Y493200D02*
Y489200D01*
X229350D01*
G01X221962Y497300D02*
Y493300D01*
X229362D01*
G01X203565Y540269D02*
X206065D01*
G01X203565Y539311D02*
Y541227D01*
G01X206065Y542536D02*
X203565D01*
Y543536D01*
X203690Y543869D01*
X203982Y544119D01*
X204315Y544202D01*
X204648Y544119D01*
X204898Y543911D01*
X205023Y543536D01*
Y542536D01*
G01X206065Y546469D02*
X203565D01*
X204065Y545969D01*
G01X206065D02*
Y546969D01*
G01X205023Y548777D02*
X204732Y549069D01*
X204565Y549319D01*
X204482Y549652D01*
X204565Y549944D01*
X204732Y550152D01*
X204982Y550319D01*
X205273Y550361D01*
X205523Y550319D01*
X205773Y550152D01*
X205982Y549902D01*
X206065Y549611D01*
X205982Y549277D01*
X205732Y548986D01*
X205357Y548819D01*
X204940Y548777D01*
X204398Y548861D01*
X204107Y548986D01*
X203815Y549194D01*
X203607Y549486D01*
X203565Y549777D01*
X203648Y550069D01*
X203857Y550277D01*
G01X203565Y552669D02*
X203648Y552336D01*
X203857Y552086D01*
X204107Y551919D01*
X204440Y551794D01*
X204815Y551752D01*
X205190Y551794D01*
X205523Y551919D01*
X205773Y552086D01*
X205982Y552336D01*
X206065Y552669D01*
X205982Y553002D01*
X205773Y553252D01*
X205523Y553419D01*
X205190Y553544D01*
X204815Y553586D01*
X204440Y553544D01*
X204107Y553419D01*
X203857Y553252D01*
X203648Y553002D01*
X203565Y552669D01*
G01X217017Y543500D02*
Y546000D01*
X218058D01*
X218392Y545875D01*
X218600Y545708D01*
X218683Y545375D01*
X218600Y545042D01*
X218350Y544833D01*
X218058Y544708D01*
X217017D01*
G01X218058D02*
X218683Y543500D01*
G01X220033Y544000D02*
X220283Y543708D01*
X220617Y543542D01*
X220992Y543500D01*
X221325Y543542D01*
X221658Y543750D01*
X221867Y544000D01*
X221908Y544250D01*
X221825Y544542D01*
X221533Y544750D01*
X221242Y544833D01*
X220867D01*
G01X221242D02*
X221492Y544958D01*
X221700Y545167D01*
X221783Y545417D01*
X221700Y545667D01*
X221492Y545875D01*
X221117Y546000D01*
X220742Y545958D01*
X220367Y545792D01*
G01X223133Y544000D02*
X223383Y543708D01*
X223717Y543542D01*
X224092Y543500D01*
X224425Y543542D01*
X224758Y543750D01*
X224967Y544000D01*
X225008Y544250D01*
X224925Y544542D01*
X224633Y544750D01*
X224342Y544833D01*
X223967D01*
G01X224342D02*
X224592Y544958D01*
X224800Y545167D01*
X224883Y545417D01*
X224800Y545667D01*
X224592Y545875D01*
X224217Y546000D01*
X223842Y545958D01*
X223467Y545792D01*
G01X227150Y543500D02*
X227442Y543542D01*
X227775Y543667D01*
X227983Y543875D01*
X228067Y544167D01*
X227983Y544458D01*
X227733Y544708D01*
X227358Y544833D01*
X226942D01*
X226692Y544917D01*
X226483Y545125D01*
X226400Y545417D01*
X226525Y545708D01*
X226817Y545917D01*
X227150Y546000D01*
X227483Y545917D01*
X227775Y545708D01*
X227900Y545417D01*
X227817Y545125D01*
X227608Y544917D01*
X227358Y544833D01*
X226942D01*
X226567Y544708D01*
X226317Y544458D01*
X226233Y544167D01*
X226317Y543875D01*
X226525Y543667D01*
X226858Y543542D01*
X227150Y543500D01*
G01X217017Y540000D02*
Y542500D01*
X218058D01*
X218392Y542375D01*
X218600Y542208D01*
X218683Y541875D01*
X218600Y541542D01*
X218350Y541333D01*
X218058Y541208D01*
X217017D01*
G01X218058D02*
X218683Y540000D01*
G01X220033Y540500D02*
X220283Y540208D01*
X220617Y540042D01*
X220992Y540000D01*
X221325Y540042D01*
X221658Y540250D01*
X221867Y540500D01*
X221908Y540750D01*
X221825Y541042D01*
X221533Y541250D01*
X221242Y541333D01*
X220867D01*
G01X221242D02*
X221492Y541458D01*
X221700Y541667D01*
X221783Y541917D01*
X221700Y542167D01*
X221492Y542375D01*
X221117Y542500D01*
X220742Y542458D01*
X220367Y542292D01*
G01X224050Y540000D02*
Y542500D01*
X223550Y542000D01*
G01Y540000D02*
X224550D01*
G01X226442Y540292D02*
X226733Y540083D01*
X227067Y540000D01*
X227400Y540083D01*
X227692Y540333D01*
X227900Y540708D01*
X227983Y541083D01*
Y541542D01*
X227900Y541917D01*
X227692Y542250D01*
X227442Y542417D01*
X227150Y542500D01*
X226817Y542417D01*
X226567Y542250D01*
X226400Y542000D01*
X226317Y541667D01*
X226400Y541375D01*
X226608Y541083D01*
X226858Y540917D01*
X227150Y540875D01*
X227483Y540958D01*
X227733Y541167D01*
X227983Y541542D01*
G01X215200Y523500D02*
Y527500D01*
X207800D01*
G01X217017Y536500D02*
Y539000D01*
X218058D01*
X218392Y538875D01*
X218600Y538708D01*
X218683Y538375D01*
X218600Y538042D01*
X218350Y537833D01*
X218058Y537708D01*
X217017D01*
G01X218058D02*
X218683Y536500D01*
G01X220033Y537000D02*
X220283Y536708D01*
X220617Y536542D01*
X220992Y536500D01*
X221325Y536542D01*
X221658Y536750D01*
X221867Y537000D01*
X221908Y537250D01*
X221825Y537542D01*
X221533Y537750D01*
X221242Y537833D01*
X220867D01*
G01X221242D02*
X221492Y537958D01*
X221700Y538167D01*
X221783Y538417D01*
X221700Y538667D01*
X221492Y538875D01*
X221117Y539000D01*
X220742Y538958D01*
X220367Y538792D01*
G01X223258Y538583D02*
X223508Y538833D01*
X223800Y538958D01*
X224133Y539000D01*
X224550Y538917D01*
X224842Y538708D01*
X224925Y538458D01*
X224883Y538208D01*
X224717Y538000D01*
X223883Y537583D01*
X223508Y537292D01*
X223258Y536875D01*
X223175Y536500D01*
X224925D01*
G01X227150Y539000D02*
X226817Y538917D01*
X226567Y538708D01*
X226400Y538458D01*
X226275Y538125D01*
X226233Y537750D01*
X226275Y537375D01*
X226400Y537042D01*
X226567Y536792D01*
X226817Y536583D01*
X227150Y536500D01*
X227483Y536583D01*
X227733Y536792D01*
X227900Y537042D01*
X228025Y537375D01*
X228067Y537750D01*
X228025Y538125D01*
X227900Y538458D01*
X227733Y538708D01*
X227483Y538917D01*
X227150Y539000D01*
G01X215200Y519500D02*
Y523500D01*
X207800D01*
G01X217017Y547000D02*
Y549500D01*
X218058D01*
X218392Y549375D01*
X218600Y549208D01*
X218683Y548875D01*
X218600Y548542D01*
X218350Y548333D01*
X218058Y548208D01*
X217017D01*
G01X218058D02*
X218683Y547000D01*
G01X220950D02*
Y549500D01*
X220450Y549000D01*
G01Y547000D02*
X221450D01*
G01X223133Y547375D02*
X223383Y547167D01*
X223675Y547042D01*
X224050Y547000D01*
X224425Y547083D01*
X224717Y547250D01*
X224925Y547542D01*
X224967Y547875D01*
X224883Y548208D01*
X224675Y548417D01*
X224383Y548583D01*
X224092Y548625D01*
X223800Y548583D01*
X223425Y548417D01*
X223550Y549500D01*
X224675D01*
G01X227150Y547000D02*
Y549500D01*
X226650Y549000D01*
G01Y547000D02*
X227650D01*
G01X207800Y536500D02*
Y532500D01*
X215200D01*
G01X207800Y544500D02*
Y540500D01*
X215200D01*
G01X207800D02*
Y536500D01*
X215200D01*
G01X227000Y523800D02*
X223000D01*
Y516400D01*
G01Y523800D02*
X227000D01*
Y531200D01*
G01Y516400D02*
X231000D01*
Y523800D01*
G01Y531200D02*
X227000D01*
Y523800D01*
G01X218767Y534792D02*
X218517Y534917D01*
X218225Y535000D01*
X217892D01*
X217517Y534875D01*
X217225Y534667D01*
X217017Y534417D01*
X216850Y534000D01*
X216808Y533625D01*
X216892Y533250D01*
X217017Y533000D01*
X217267Y532750D01*
X217558Y532583D01*
X217850Y532500D01*
X218142D01*
X218433Y532583D01*
X218683Y532708D01*
X218892Y532875D01*
G01X220950Y532500D02*
Y535000D01*
X220450Y534500D01*
G01Y532500D02*
X221450D01*
G01X223342Y532792D02*
X223633Y532583D01*
X223967Y532500D01*
X224300Y532583D01*
X224592Y532833D01*
X224800Y533208D01*
X224883Y533583D01*
Y534042D01*
X224800Y534417D01*
X224592Y534750D01*
X224342Y534917D01*
X224050Y535000D01*
X223717Y534917D01*
X223467Y534750D01*
X223300Y534500D01*
X223217Y534167D01*
X223300Y533875D01*
X223508Y533583D01*
X223758Y533417D01*
X224050Y533375D01*
X224383Y533458D01*
X224633Y533667D01*
X224883Y534042D01*
G01X227150Y535000D02*
X226817Y534917D01*
X226567Y534708D01*
X226400Y534458D01*
X226275Y534125D01*
X226233Y533750D01*
X226275Y533375D01*
X226400Y533042D01*
X226567Y532792D01*
X226817Y532583D01*
X227150Y532500D01*
X227483Y532583D01*
X227733Y532792D01*
X227900Y533042D01*
X228025Y533375D01*
X228067Y533750D01*
X228025Y534125D01*
X227900Y534458D01*
X227733Y534708D01*
X227483Y534917D01*
X227150Y535000D01*
G01X231534Y535067D02*
X231409Y534817D01*
X231326Y534525D01*
Y534192D01*
X231451Y533817D01*
X231659Y533525D01*
X231909Y533317D01*
X232326Y533150D01*
X232701Y533108D01*
X233076Y533192D01*
X233326Y533317D01*
X233576Y533567D01*
X233743Y533858D01*
X233826Y534150D01*
Y534442D01*
X233743Y534733D01*
X233618Y534983D01*
X233451Y535192D01*
G01X233826Y537250D02*
X233784Y537542D01*
X233659Y537875D01*
X233451Y538083D01*
X233159Y538167D01*
X232868Y538083D01*
X232618Y537833D01*
X232493Y537458D01*
Y537042D01*
X232409Y536792D01*
X232201Y536583D01*
X231909Y536500D01*
X231618Y536625D01*
X231409Y536917D01*
X231326Y537250D01*
X231409Y537583D01*
X231618Y537875D01*
X231909Y538000D01*
X232201Y537917D01*
X232409Y537708D01*
X232493Y537458D01*
Y537042D01*
X232618Y536667D01*
X232868Y536417D01*
X233159Y536333D01*
X233451Y536417D01*
X233659Y536625D01*
X233784Y536958D01*
X233826Y537250D01*
G01X231326Y540350D02*
X231409Y540017D01*
X231618Y539767D01*
X231868Y539600D01*
X232201Y539475D01*
X232576Y539433D01*
X232951Y539475D01*
X233284Y539600D01*
X233534Y539767D01*
X233743Y540017D01*
X233826Y540350D01*
X233743Y540683D01*
X233534Y540933D01*
X233284Y541100D01*
X232951Y541225D01*
X232576Y541267D01*
X232201Y541225D01*
X231868Y541100D01*
X231618Y540933D01*
X231409Y540683D01*
X231326Y540350D01*
G01X233826Y543450D02*
X233784Y543742D01*
X233659Y544075D01*
X233451Y544283D01*
X233159Y544367D01*
X232868Y544283D01*
X232618Y544033D01*
X232493Y543658D01*
Y543242D01*
X232409Y542992D01*
X232201Y542783D01*
X231909Y542700D01*
X231618Y542825D01*
X231409Y543117D01*
X231326Y543450D01*
X231409Y543783D01*
X231618Y544075D01*
X231909Y544200D01*
X232201Y544117D01*
X232409Y543908D01*
X232493Y543658D01*
Y543242D01*
X232618Y542867D01*
X232868Y542617D01*
X233159Y542533D01*
X233451Y542617D01*
X233659Y542825D01*
X233784Y543158D01*
X233826Y543450D01*
G01X232784Y545758D02*
X232493Y546050D01*
X232326Y546300D01*
X232243Y546633D01*
X232326Y546925D01*
X232493Y547133D01*
X232743Y547300D01*
X233034Y547342D01*
X233284Y547300D01*
X233534Y547133D01*
X233743Y546883D01*
X233826Y546592D01*
X233743Y546258D01*
X233493Y545967D01*
X233118Y545800D01*
X232701Y545758D01*
X232159Y545842D01*
X231868Y545967D01*
X231576Y546175D01*
X231368Y546467D01*
X231326Y546758D01*
X231409Y547050D01*
X231618Y547258D01*
G01X207800Y560288D02*
Y557788D01*
G01X206842Y560288D02*
X208758D01*
G01X210067Y557788D02*
Y560288D01*
X211067D01*
X211400Y560163D01*
X211650Y559871D01*
X211733Y559538D01*
X211650Y559205D01*
X211442Y558955D01*
X211067Y558830D01*
X210067D01*
G01X213208Y559871D02*
X213458Y560121D01*
X213750Y560246D01*
X214083Y560288D01*
X214500Y560205D01*
X214792Y559996D01*
X214875Y559746D01*
X214833Y559496D01*
X214667Y559288D01*
X213833Y558871D01*
X213458Y558580D01*
X213208Y558163D01*
X213125Y557788D01*
X214875D01*
G01X216308Y558830D02*
X216600Y559121D01*
X216850Y559288D01*
X217183Y559371D01*
X217475Y559288D01*
X217683Y559121D01*
X217850Y558871D01*
X217892Y558580D01*
X217850Y558330D01*
X217683Y558080D01*
X217433Y557871D01*
X217142Y557788D01*
X216808Y557871D01*
X216517Y558121D01*
X216350Y558496D01*
X216308Y558913D01*
X216392Y559455D01*
X216517Y559746D01*
X216725Y560038D01*
X217017Y560246D01*
X217308Y560288D01*
X217600Y560205D01*
X217808Y559996D01*
G01X219492Y558080D02*
X219783Y557871D01*
X220117Y557788D01*
X220450Y557871D01*
X220742Y558121D01*
X220950Y558496D01*
X221033Y558871D01*
Y559330D01*
X220950Y559705D01*
X220742Y560038D01*
X220492Y560205D01*
X220200Y560288D01*
X219867Y560205D01*
X219617Y560038D01*
X219450Y559788D01*
X219367Y559455D01*
X219450Y559163D01*
X219658Y558871D01*
X219908Y558705D01*
X220200Y558663D01*
X220533Y558746D01*
X220783Y558955D01*
X221033Y559330D01*
G01X217017Y554000D02*
Y556500D01*
X218058D01*
X218392Y556375D01*
X218600Y556208D01*
X218683Y555875D01*
X218600Y555542D01*
X218350Y555333D01*
X218058Y555208D01*
X217017D01*
G01X218058D02*
X218683Y554000D01*
G01X220950D02*
Y556500D01*
X220450Y556000D01*
G01Y554000D02*
X221450D01*
G01X223133Y554375D02*
X223383Y554167D01*
X223675Y554042D01*
X224050Y554000D01*
X224425Y554083D01*
X224717Y554250D01*
X224925Y554542D01*
X224967Y554875D01*
X224883Y555208D01*
X224675Y555417D01*
X224383Y555583D01*
X224092Y555625D01*
X223800Y555583D01*
X223425Y555417D01*
X223550Y556500D01*
X224675D01*
G01X226233Y554500D02*
X226483Y554208D01*
X226817Y554042D01*
X227192Y554000D01*
X227525Y554042D01*
X227858Y554250D01*
X228067Y554500D01*
X228108Y554750D01*
X228025Y555042D01*
X227733Y555250D01*
X227442Y555333D01*
X227067D01*
G01X227442D02*
X227692Y555458D01*
X227900Y555667D01*
X227983Y555917D01*
X227900Y556167D01*
X227692Y556375D01*
X227317Y556500D01*
X226942Y556458D01*
X226567Y556292D01*
G01X217017Y550500D02*
Y553000D01*
X218058D01*
X218392Y552875D01*
X218600Y552708D01*
X218683Y552375D01*
X218600Y552042D01*
X218350Y551833D01*
X218058Y551708D01*
X217017D01*
G01X218058D02*
X218683Y550500D01*
G01X220950D02*
Y553000D01*
X220450Y552500D01*
G01Y550500D02*
X221450D01*
G01X223133Y550875D02*
X223383Y550667D01*
X223675Y550542D01*
X224050Y550500D01*
X224425Y550583D01*
X224717Y550750D01*
X224925Y551042D01*
X224967Y551375D01*
X224883Y551708D01*
X224675Y551917D01*
X224383Y552083D01*
X224092Y552125D01*
X223800Y552083D01*
X223425Y551917D01*
X223550Y553000D01*
X224675D01*
G01X227650Y550500D02*
Y553000D01*
X226108Y551208D01*
X228192D01*
G01X203500Y568800D02*
X207500D01*
Y576200D01*
G01X207800Y552500D02*
Y548500D01*
X215200D01*
G01X207800Y572500D02*
Y568500D01*
X215200D01*
G01X205487Y577499D02*
X205820Y577291D01*
X206195Y577166D01*
X206529D01*
X206862Y577291D01*
X207112Y577499D01*
X207237Y577791D01*
X207154Y578083D01*
X206945Y578333D01*
X206570Y578499D01*
X206070Y578583D01*
X205779Y578749D01*
X205654Y579041D01*
X205737Y579333D01*
X205945Y579541D01*
X206237Y579666D01*
X206529D01*
X206820Y579583D01*
X207070Y579374D01*
G01X208629Y577166D02*
Y579666D01*
X209670D01*
X210004Y579541D01*
X210212Y579374D01*
X210295Y579041D01*
X210212Y578708D01*
X209962Y578499D01*
X209670Y578374D01*
X208629D01*
G01X209670D02*
X210295Y577166D01*
G01X211854Y577458D02*
X212145Y577249D01*
X212479Y577166D01*
X212812Y577249D01*
X213104Y577499D01*
X213312Y577874D01*
X213395Y578249D01*
Y578708D01*
X213312Y579083D01*
X213104Y579416D01*
X212854Y579583D01*
X212562Y579666D01*
X212229Y579583D01*
X211979Y579416D01*
X211812Y579166D01*
X211729Y578833D01*
X211812Y578541D01*
X212020Y578249D01*
X212270Y578083D01*
X212562Y578041D01*
X212895Y578124D01*
X213145Y578333D01*
X213395Y578708D01*
G01X216162Y577166D02*
Y579666D01*
X214620Y577874D01*
X216704D01*
G01X217845Y577666D02*
X218095Y577374D01*
X218429Y577208D01*
X218804Y577166D01*
X219137Y577208D01*
X219470Y577416D01*
X219679Y577666D01*
X219720Y577916D01*
X219637Y578208D01*
X219345Y578416D01*
X219054Y578499D01*
X218679D01*
G01X219054D02*
X219304Y578624D01*
X219512Y578833D01*
X219595Y579083D01*
X219512Y579333D01*
X219304Y579541D01*
X218929Y579666D01*
X218554Y579624D01*
X218179Y579458D01*
G01X203500Y575732D02*
X199500D01*
Y568332D01*
G01X215200Y552500D02*
Y556500D01*
X207800D01*
G01X231144Y573087D02*
Y575587D01*
X232185D01*
X232519Y575462D01*
X232727Y575295D01*
X232810Y574962D01*
X232727Y574629D01*
X232477Y574420D01*
X232185Y574295D01*
X231144D01*
G01X232185D02*
X232810Y573087D01*
G01X235577D02*
Y575587D01*
X234035Y573795D01*
X236119D01*
G01X238177Y573087D02*
Y575587D01*
X237677Y575087D01*
G01Y573087D02*
X238677D01*
G01X241777D02*
Y575587D01*
X240235Y573795D01*
X242319D01*
G01X228070Y566020D02*
Y570020D01*
X220670D01*
G01X231016Y569659D02*
Y572159D01*
X232057D01*
X232391Y572034D01*
X232599Y571867D01*
X232682Y571534D01*
X232599Y571201D01*
X232349Y570992D01*
X232057Y570867D01*
X231016D01*
G01X232057D02*
X232682Y569659D01*
G01X235449D02*
Y572159D01*
X233907Y570367D01*
X235991D01*
G01X238049Y569659D02*
Y572159D01*
X237549Y571659D01*
G01Y569659D02*
X238549D01*
G01X240232Y570034D02*
X240482Y569826D01*
X240774Y569701D01*
X241149Y569659D01*
X241524Y569742D01*
X241816Y569909D01*
X242024Y570201D01*
X242066Y570534D01*
X241982Y570867D01*
X241774Y571076D01*
X241482Y571242D01*
X241191Y571284D01*
X240899Y571242D01*
X240524Y571076D01*
X240649Y572159D01*
X241774D01*
G01X220672Y565994D02*
Y561994D01*
X228072D01*
G01X231251Y576909D02*
Y579409D01*
X232292D01*
X232626Y579284D01*
X232834Y579117D01*
X232917Y578784D01*
X232834Y578451D01*
X232584Y578242D01*
X232292Y578117D01*
X231251D01*
G01X232292D02*
X232917Y576909D01*
G01X235684D02*
Y579409D01*
X234142Y577617D01*
X236226D01*
G01X238284Y576909D02*
Y579409D01*
X237784Y578909D01*
G01Y576909D02*
X238784D01*
G01X241384D02*
X241676Y576951D01*
X242009Y577076D01*
X242217Y577284D01*
X242301Y577576D01*
X242217Y577867D01*
X241967Y578117D01*
X241592Y578242D01*
X241176D01*
X240926Y578326D01*
X240717Y578534D01*
X240634Y578826D01*
X240759Y579117D01*
X241051Y579326D01*
X241384Y579409D01*
X241717Y579326D01*
X242009Y579117D01*
X242134Y578826D01*
X242051Y578534D01*
X241842Y578326D01*
X241592Y578242D01*
X241176D01*
X240801Y578117D01*
X240551Y577867D01*
X240467Y577576D01*
X240551Y577284D01*
X240759Y577076D01*
X241092Y576951D01*
X241384Y576909D01*
G01X228200Y577862D02*
X224200D01*
Y570462D01*
G01X231946Y551293D02*
X231821Y551043D01*
X231738Y550751D01*
Y550418D01*
X231863Y550043D01*
X232071Y549751D01*
X232321Y549543D01*
X232738Y549376D01*
X233113Y549334D01*
X233488Y549418D01*
X233738Y549543D01*
X233988Y549793D01*
X234155Y550084D01*
X234238Y550376D01*
Y550668D01*
X234155Y550959D01*
X234030Y551209D01*
X233863Y551418D01*
G01X234238Y553476D02*
X234196Y553768D01*
X234071Y554101D01*
X233863Y554309D01*
X233571Y554393D01*
X233280Y554309D01*
X233030Y554059D01*
X232905Y553684D01*
Y553268D01*
X232821Y553018D01*
X232613Y552809D01*
X232321Y552726D01*
X232030Y552851D01*
X231821Y553143D01*
X231738Y553476D01*
X231821Y553809D01*
X232030Y554101D01*
X232321Y554226D01*
X232613Y554143D01*
X232821Y553934D01*
X232905Y553684D01*
Y553268D01*
X233030Y552893D01*
X233280Y552643D01*
X233571Y552559D01*
X233863Y552643D01*
X234071Y552851D01*
X234196Y553184D01*
X234238Y553476D01*
G01X231738Y556576D02*
X231821Y556243D01*
X232030Y555993D01*
X232280Y555826D01*
X232613Y555701D01*
X232988Y555659D01*
X233363Y555701D01*
X233696Y555826D01*
X233946Y555993D01*
X234155Y556243D01*
X234238Y556576D01*
X234155Y556909D01*
X233946Y557159D01*
X233696Y557326D01*
X233363Y557451D01*
X232988Y557493D01*
X232613Y557451D01*
X232280Y557326D01*
X232030Y557159D01*
X231821Y556909D01*
X231738Y556576D01*
G01X234238Y559676D02*
X234196Y559968D01*
X234071Y560301D01*
X233863Y560509D01*
X233571Y560593D01*
X233280Y560509D01*
X233030Y560259D01*
X232905Y559884D01*
Y559468D01*
X232821Y559218D01*
X232613Y559009D01*
X232321Y558926D01*
X232030Y559051D01*
X231821Y559343D01*
X231738Y559676D01*
X231821Y560009D01*
X232030Y560301D01*
X232321Y560426D01*
X232613Y560343D01*
X232821Y560134D01*
X232905Y559884D01*
Y559468D01*
X233030Y559093D01*
X233280Y558843D01*
X233571Y558759D01*
X233863Y558843D01*
X234071Y559051D01*
X234196Y559384D01*
X234238Y559676D01*
G01X233863Y561859D02*
X234071Y562109D01*
X234196Y562401D01*
X234238Y562776D01*
X234155Y563151D01*
X233988Y563443D01*
X233696Y563651D01*
X233363Y563693D01*
X233030Y563609D01*
X232821Y563401D01*
X232655Y563109D01*
X232613Y562818D01*
X232655Y562526D01*
X232821Y562151D01*
X231738Y562276D01*
Y563401D01*
G01X210689Y616490D02*
Y614698D01*
X210856Y614323D01*
X211189Y614073D01*
X211606Y613990D01*
X212023Y614073D01*
X212356Y614323D01*
X212523Y614698D01*
Y616490D01*
G01X214706Y613990D02*
Y616490D01*
X214206Y615990D01*
G01Y613990D02*
X215206D01*
G01X216889Y614490D02*
X217139Y614198D01*
X217473Y614032D01*
X217848Y613990D01*
X218181Y614032D01*
X218514Y614240D01*
X218723Y614490D01*
X218764Y614740D01*
X218681Y615032D01*
X218389Y615240D01*
X218098Y615323D01*
X217723D01*
G01X218098D02*
X218348Y615448D01*
X218556Y615657D01*
X218639Y615907D01*
X218556Y616157D01*
X218348Y616365D01*
X217973Y616490D01*
X217598Y616448D01*
X217223Y616282D01*
G01X221406Y613990D02*
Y616490D01*
X219864Y614698D01*
X221948D01*
G01X210850Y582800D02*
X212850Y584800D01*
X214850Y582800D01*
G01X217000Y594750D02*
X209000D01*
Y582800D01*
X217000D01*
Y594750D01*
G01X229500Y597800D02*
X232000D01*
G01X229500Y596842D02*
Y598758D01*
G01X232000Y600067D02*
X229500D01*
Y601067D01*
X229625Y601400D01*
X229917Y601650D01*
X230250Y601733D01*
X230583Y601650D01*
X230833Y601442D01*
X230958Y601067D01*
Y600067D01*
G01X232000Y604000D02*
X229500D01*
X230000Y603500D01*
G01X232000D02*
Y604500D01*
G01X230958Y606308D02*
X230667Y606600D01*
X230500Y606850D01*
X230417Y607183D01*
X230500Y607475D01*
X230667Y607683D01*
X230917Y607850D01*
X231208Y607892D01*
X231458Y607850D01*
X231708Y607683D01*
X231917Y607433D01*
X232000Y607142D01*
X231917Y606808D01*
X231667Y606517D01*
X231292Y606350D01*
X230875Y606308D01*
X230333Y606392D01*
X230042Y606517D01*
X229750Y606725D01*
X229542Y607017D01*
X229500Y607308D01*
X229583Y607600D01*
X229792Y607808D01*
G01X230958Y609408D02*
X230667Y609700D01*
X230500Y609950D01*
X230417Y610283D01*
X230500Y610575D01*
X230667Y610783D01*
X230917Y610950D01*
X231208Y610992D01*
X231458Y610950D01*
X231708Y610783D01*
X231917Y610533D01*
X232000Y610242D01*
X231917Y609908D01*
X231667Y609617D01*
X231292Y609450D01*
X230875Y609408D01*
X230333Y609492D01*
X230042Y609617D01*
X229750Y609825D01*
X229542Y610117D01*
X229500Y610408D01*
X229583Y610700D01*
X229792Y610908D01*
G01X207038Y605166D02*
Y607666D01*
X208079D01*
X208413Y607541D01*
X208621Y607374D01*
X208704Y607041D01*
X208621Y606708D01*
X208371Y606499D01*
X208079Y606374D01*
X207038D01*
G01X208079D02*
X208704Y605166D01*
G01X210054Y605666D02*
X210304Y605374D01*
X210638Y605208D01*
X211013Y605166D01*
X211346Y605208D01*
X211679Y605416D01*
X211888Y605666D01*
X211929Y605916D01*
X211846Y606208D01*
X211554Y606416D01*
X211263Y606499D01*
X210888D01*
G01X211263D02*
X211513Y606624D01*
X211721Y606833D01*
X211804Y607083D01*
X211721Y607333D01*
X211513Y607541D01*
X211138Y607666D01*
X210763Y607624D01*
X210388Y607458D01*
G01X214071Y605166D02*
Y607666D01*
X213571Y607166D01*
G01Y605166D02*
X214571D01*
G01X217171D02*
Y607666D01*
X216671Y607166D01*
G01Y605166D02*
X217671D01*
G01X209517Y600673D02*
Y603173D01*
X210558D01*
X210892Y603048D01*
X211100Y602881D01*
X211183Y602548D01*
X211100Y602215D01*
X210850Y602006D01*
X210558Y601881D01*
X209517D01*
G01X210558D02*
X211183Y600673D01*
G01X212658Y602756D02*
X212908Y603006D01*
X213200Y603131D01*
X213533Y603173D01*
X213950Y603090D01*
X214242Y602881D01*
X214325Y602631D01*
X214283Y602381D01*
X214117Y602173D01*
X213283Y601756D01*
X212908Y601465D01*
X212658Y601048D01*
X212575Y600673D01*
X214325D01*
G01X215633Y601048D02*
X215883Y600840D01*
X216175Y600715D01*
X216550Y600673D01*
X216925Y600756D01*
X217217Y600923D01*
X217425Y601215D01*
X217467Y601548D01*
X217383Y601881D01*
X217175Y602090D01*
X216883Y602256D01*
X216592Y602298D01*
X216300Y602256D01*
X215925Y602090D01*
X216050Y603173D01*
X217175D01*
G01X219567Y600673D02*
X219650Y601215D01*
X219775Y601673D01*
X219942Y602090D01*
X220150Y602548D01*
X220483Y603173D01*
X218817D01*
G01X235700Y584000D02*
Y588000D01*
X228300D01*
G01X235700D02*
Y592000D01*
X228300D01*
G01X205267Y611792D02*
X205017Y611917D01*
X204725Y612000D01*
X204392D01*
X204017Y611875D01*
X203725Y611667D01*
X203517Y611417D01*
X203350Y611000D01*
X203308Y610625D01*
X203392Y610250D01*
X203517Y610000D01*
X203767Y609750D01*
X204058Y609583D01*
X204350Y609500D01*
X204642D01*
X204933Y609583D01*
X205183Y609708D01*
X205392Y609875D01*
G01X206533Y610000D02*
X206783Y609708D01*
X207117Y609542D01*
X207492Y609500D01*
X207825Y609542D01*
X208158Y609750D01*
X208367Y610000D01*
X208408Y610250D01*
X208325Y610542D01*
X208033Y610750D01*
X207742Y610833D01*
X207367D01*
G01X207742D02*
X207992Y610958D01*
X208200Y611167D01*
X208283Y611417D01*
X208200Y611667D01*
X207992Y611875D01*
X207617Y612000D01*
X207242Y611958D01*
X206867Y611792D01*
G01X209758Y611583D02*
X210008Y611833D01*
X210300Y611958D01*
X210633Y612000D01*
X211050Y611917D01*
X211342Y611708D01*
X211425Y611458D01*
X211383Y611208D01*
X211217Y611000D01*
X210383Y610583D01*
X210008Y610292D01*
X209758Y609875D01*
X209675Y609500D01*
X211425D01*
G01X212858Y610542D02*
X213150Y610833D01*
X213400Y611000D01*
X213733Y611083D01*
X214025Y611000D01*
X214233Y610833D01*
X214400Y610583D01*
X214442Y610292D01*
X214400Y610042D01*
X214233Y609792D01*
X213983Y609583D01*
X213692Y609500D01*
X213358Y609583D01*
X213067Y609833D01*
X212900Y610208D01*
X212858Y610625D01*
X212942Y611167D01*
X213067Y611458D01*
X213275Y611750D01*
X213567Y611958D01*
X213858Y612000D01*
X214150Y611917D01*
X214358Y611708D01*
G01X225347Y631689D02*
X222847D01*
Y632689D01*
X222972Y633022D01*
X223264Y633272D01*
X223597Y633355D01*
X223930Y633272D01*
X224180Y633064D01*
X224305Y632689D01*
Y631689D01*
G01X225347Y634789D02*
X222847D01*
Y635830D01*
X222972Y636164D01*
X223139Y636372D01*
X223472Y636455D01*
X223805Y636372D01*
X224014Y636122D01*
X224139Y635830D01*
Y634789D01*
G01Y635830D02*
X225347Y636455D01*
G01X224305Y637930D02*
X224014Y638222D01*
X223847Y638472D01*
X223764Y638805D01*
X223847Y639097D01*
X224014Y639305D01*
X224264Y639472D01*
X224555Y639514D01*
X224805Y639472D01*
X225055Y639305D01*
X225264Y639055D01*
X225347Y638764D01*
X225264Y638430D01*
X225014Y638139D01*
X224639Y637972D01*
X224222Y637930D01*
X223680Y638014D01*
X223389Y638139D01*
X223097Y638347D01*
X222889Y638639D01*
X222847Y638930D01*
X222930Y639222D01*
X223139Y639430D01*
G01X223264Y641030D02*
X223014Y641280D01*
X222889Y641572D01*
X222847Y641905D01*
X222930Y642322D01*
X223139Y642614D01*
X223389Y642697D01*
X223639Y642655D01*
X223847Y642489D01*
X224264Y641655D01*
X224555Y641280D01*
X224972Y641030D01*
X225347Y640947D01*
Y642697D01*
G01X233347Y631689D02*
X230847D01*
Y632689D01*
X230972Y633022D01*
X231264Y633272D01*
X231597Y633355D01*
X231930Y633272D01*
X232180Y633064D01*
X232305Y632689D01*
Y631689D01*
G01X233347Y634789D02*
X230847D01*
Y635830D01*
X230972Y636164D01*
X231139Y636372D01*
X231472Y636455D01*
X231805Y636372D01*
X232014Y636122D01*
X232139Y635830D01*
Y634789D01*
G01Y635830D02*
X233347Y636455D01*
G01X232305Y637930D02*
X232014Y638222D01*
X231847Y638472D01*
X231764Y638805D01*
X231847Y639097D01*
X232014Y639305D01*
X232264Y639472D01*
X232555Y639514D01*
X232805Y639472D01*
X233055Y639305D01*
X233264Y639055D01*
X233347Y638764D01*
X233264Y638430D01*
X233014Y638139D01*
X232639Y637972D01*
X232222Y637930D01*
X231680Y638014D01*
X231389Y638139D01*
X231097Y638347D01*
X230889Y638639D01*
X230847Y638930D01*
X230930Y639222D01*
X231139Y639430D01*
G01X233347Y641739D02*
X232805Y641822D01*
X232347Y641947D01*
X231930Y642114D01*
X231472Y642322D01*
X230847Y642655D01*
Y640989D01*
G01X229347Y631689D02*
X226847D01*
Y632689D01*
X226972Y633022D01*
X227264Y633272D01*
X227597Y633355D01*
X227930Y633272D01*
X228180Y633064D01*
X228305Y632689D01*
Y631689D01*
G01X227055Y636539D02*
X226930Y636289D01*
X226847Y635997D01*
Y635664D01*
X226972Y635289D01*
X227180Y634997D01*
X227430Y634789D01*
X227847Y634622D01*
X228222Y634580D01*
X228597Y634664D01*
X228847Y634789D01*
X229097Y635039D01*
X229264Y635330D01*
X229347Y635622D01*
Y635914D01*
X229264Y636205D01*
X229139Y636455D01*
X228972Y636664D01*
G01X229347Y638722D02*
X226847D01*
X227347Y638222D01*
G01X229347D02*
Y639222D01*
G01Y641822D02*
X229305Y642114D01*
X229180Y642447D01*
X228972Y642655D01*
X228680Y642739D01*
X228389Y642655D01*
X228139Y642405D01*
X228014Y642030D01*
Y641614D01*
X227930Y641364D01*
X227722Y641155D01*
X227430Y641072D01*
X227139Y641197D01*
X226930Y641489D01*
X226847Y641822D01*
X226930Y642155D01*
X227139Y642447D01*
X227430Y642572D01*
X227722Y642489D01*
X227930Y642280D01*
X228014Y642030D01*
Y641614D01*
X228139Y641239D01*
X228389Y640989D01*
X228680Y640905D01*
X228972Y640989D01*
X229180Y641197D01*
X229305Y641530D01*
X229347Y641822D01*
G01X230522Y646909D02*
Y649409D01*
X231522D01*
X231855Y649284D01*
X232105Y648992D01*
X232188Y648659D01*
X232105Y648326D01*
X231897Y648076D01*
X231522Y647951D01*
X230522D01*
G01X235372Y649201D02*
X235122Y649326D01*
X234830Y649409D01*
X234497D01*
X234122Y649284D01*
X233830Y649076D01*
X233622Y648826D01*
X233455Y648409D01*
X233413Y648034D01*
X233497Y647659D01*
X233622Y647409D01*
X233872Y647159D01*
X234163Y646992D01*
X234455Y646909D01*
X234747D01*
X235038Y646992D01*
X235288Y647117D01*
X235497Y647284D01*
G01X237555Y646909D02*
Y649409D01*
X237055Y648909D01*
G01Y646909D02*
X238055D01*
G01X240572D02*
X240655Y647451D01*
X240780Y647909D01*
X240947Y648326D01*
X241155Y648784D01*
X241488Y649409D01*
X239822D01*
G01X204663Y674973D02*
X202163D01*
Y676014D01*
X202288Y676348D01*
X202455Y676556D01*
X202788Y676639D01*
X203121Y676556D01*
X203330Y676306D01*
X203455Y676014D01*
Y674973D01*
G01Y676014D02*
X204663Y676639D01*
G01X204371Y678198D02*
X204580Y678489D01*
X204663Y678823D01*
X204580Y679156D01*
X204330Y679448D01*
X203955Y679656D01*
X203580Y679739D01*
X203121D01*
X202746Y679656D01*
X202413Y679448D01*
X202246Y679198D01*
X202163Y678906D01*
X202246Y678573D01*
X202413Y678323D01*
X202663Y678156D01*
X202996Y678073D01*
X203288Y678156D01*
X203580Y678364D01*
X203746Y678614D01*
X203788Y678906D01*
X203705Y679239D01*
X203496Y679489D01*
X203121Y679739D01*
G01X202163Y682006D02*
X202246Y681673D01*
X202455Y681423D01*
X202705Y681256D01*
X203038Y681131D01*
X203413Y681089D01*
X203788Y681131D01*
X204121Y681256D01*
X204371Y681423D01*
X204580Y681673D01*
X204663Y682006D01*
X204580Y682339D01*
X204371Y682589D01*
X204121Y682756D01*
X203788Y682881D01*
X203413Y682923D01*
X203038Y682881D01*
X202705Y682756D01*
X202455Y682589D01*
X202246Y682339D01*
X202163Y682006D01*
G01X204663Y685606D02*
X202163D01*
X203955Y684064D01*
Y686148D01*
G01X224000Y707483D02*
X225792D01*
X226167Y707650D01*
X226417Y707983D01*
X226500Y708400D01*
X226417Y708817D01*
X226167Y709150D01*
X225792Y709317D01*
X224000D01*
G01X226000Y710583D02*
X226292Y710833D01*
X226458Y711167D01*
X226500Y711542D01*
X226458Y711875D01*
X226250Y712208D01*
X226000Y712417D01*
X225750Y712458D01*
X225458Y712375D01*
X225250Y712083D01*
X225167Y711792D01*
Y711417D01*
G01Y711792D02*
X225042Y712042D01*
X224833Y712250D01*
X224583Y712333D01*
X224333Y712250D01*
X224125Y712042D01*
X224000Y711667D01*
X224042Y711292D01*
X224208Y710917D01*
G01X226000Y713683D02*
X226292Y713933D01*
X226458Y714267D01*
X226500Y714642D01*
X226458Y714975D01*
X226250Y715308D01*
X226000Y715517D01*
X225750Y715558D01*
X225458Y715475D01*
X225250Y715183D01*
X225167Y714892D01*
Y714517D01*
G01Y714892D02*
X225042Y715142D01*
X224833Y715350D01*
X224583Y715433D01*
X224333Y715350D01*
X224125Y715142D01*
X224000Y714767D01*
X224042Y714392D01*
X224208Y714017D01*
G01X205500Y718800D02*
Y706900D01*
G01X201500Y708500D02*
X199900Y706900D01*
G01X201500Y708500D02*
X203100Y706900D01*
G01X203791Y689847D02*
X203541Y689972D01*
X203249Y690055D01*
X202916D01*
X202541Y689930D01*
X202249Y689722D01*
X202041Y689472D01*
X201874Y689055D01*
X201832Y688680D01*
X201916Y688305D01*
X202041Y688055D01*
X202291Y687805D01*
X202582Y687638D01*
X202874Y687555D01*
X203166D01*
X203457Y687638D01*
X203707Y687763D01*
X203916Y687930D01*
G01X205891Y687555D02*
X205974Y688097D01*
X206099Y688555D01*
X206266Y688972D01*
X206474Y689430D01*
X206807Y690055D01*
X205141D01*
G01X209074Y687555D02*
Y690055D01*
X208574Y689555D01*
G01Y687555D02*
X209574D01*
G01X212174Y690055D02*
X211841Y689972D01*
X211591Y689763D01*
X211424Y689513D01*
X211299Y689180D01*
X211257Y688805D01*
X211299Y688430D01*
X211424Y688097D01*
X211591Y687847D01*
X211841Y687638D01*
X212174Y687555D01*
X212507Y687638D01*
X212757Y687847D01*
X212924Y688097D01*
X213049Y688430D01*
X213091Y688805D01*
X213049Y689180D01*
X212924Y689513D01*
X212757Y689763D01*
X212507Y689972D01*
X212174Y690055D01*
G01X202000Y693800D02*
X206000D01*
Y701200D01*
G01X230500Y707517D02*
X228000D01*
Y708558D01*
X228125Y708892D01*
X228292Y709100D01*
X228625Y709183D01*
X228958Y709100D01*
X229167Y708850D01*
X229292Y708558D01*
Y707517D01*
G01Y708558D02*
X230500Y709183D01*
G01Y711450D02*
X230458Y711742D01*
X230333Y712075D01*
X230125Y712283D01*
X229833Y712367D01*
X229542Y712283D01*
X229292Y712033D01*
X229167Y711658D01*
Y711242D01*
X229083Y710992D01*
X228875Y710783D01*
X228583Y710700D01*
X228292Y710825D01*
X228083Y711117D01*
X228000Y711450D01*
X228083Y711783D01*
X228292Y712075D01*
X228583Y712200D01*
X228875Y712117D01*
X229083Y711908D01*
X229167Y711658D01*
Y711242D01*
X229292Y710867D01*
X229542Y710617D01*
X229833Y710533D01*
X230125Y710617D01*
X230333Y710825D01*
X230458Y711158D01*
X230500Y711450D01*
G01X230208Y713842D02*
X230417Y714133D01*
X230500Y714467D01*
X230417Y714800D01*
X230167Y715092D01*
X229792Y715300D01*
X229417Y715383D01*
X228958D01*
X228583Y715300D01*
X228250Y715092D01*
X228083Y714842D01*
X228000Y714550D01*
X228083Y714217D01*
X228250Y713967D01*
X228500Y713800D01*
X228833Y713717D01*
X229125Y713800D01*
X229417Y714008D01*
X229583Y714258D01*
X229625Y714550D01*
X229542Y714883D01*
X229333Y715133D01*
X228958Y715383D01*
G01X230125Y716733D02*
X230333Y716983D01*
X230458Y717275D01*
X230500Y717650D01*
X230417Y718025D01*
X230250Y718317D01*
X229958Y718525D01*
X229625Y718567D01*
X229292Y718483D01*
X229083Y718275D01*
X228917Y717983D01*
X228875Y717692D01*
X228917Y717400D01*
X229083Y717025D01*
X228000Y717150D01*
Y718275D01*
G01X215000Y706800D02*
X219000D01*
Y714200D01*
G01X226143Y730661D02*
X225893Y730786D01*
X225601Y730869D01*
X225268D01*
X224893Y730744D01*
X224601Y730536D01*
X224393Y730286D01*
X224226Y729869D01*
X224184Y729494D01*
X224268Y729119D01*
X224393Y728869D01*
X224643Y728619D01*
X224934Y728452D01*
X225226Y728369D01*
X225518D01*
X225809Y728452D01*
X226059Y728577D01*
X226268Y728744D01*
G01X228243Y728369D02*
X228326Y728911D01*
X228451Y729369D01*
X228618Y729786D01*
X228826Y730244D01*
X229159Y730869D01*
X227493D01*
G01X231426Y728369D02*
Y730869D01*
X230926Y730369D01*
G01Y728369D02*
X231926D01*
G01X234526D02*
Y730869D01*
X234026Y730369D01*
G01Y728369D02*
X235026D01*
G01X213143Y730661D02*
X212893Y730786D01*
X212601Y730869D01*
X212268D01*
X211893Y730744D01*
X211601Y730536D01*
X211393Y730286D01*
X211226Y729869D01*
X211184Y729494D01*
X211268Y729119D01*
X211393Y728869D01*
X211643Y728619D01*
X211934Y728452D01*
X212226Y728369D01*
X212518D01*
X212809Y728452D01*
X213059Y728577D01*
X213268Y728744D01*
G01X215243Y728369D02*
X215326Y728911D01*
X215451Y729369D01*
X215618Y729786D01*
X215826Y730244D01*
X216159Y730869D01*
X214493D01*
G01X218426D02*
X218093Y730786D01*
X217843Y730577D01*
X217676Y730327D01*
X217551Y729994D01*
X217509Y729619D01*
X217551Y729244D01*
X217676Y728911D01*
X217843Y728661D01*
X218093Y728452D01*
X218426Y728369D01*
X218759Y728452D01*
X219009Y728661D01*
X219176Y728911D01*
X219301Y729244D01*
X219343Y729619D01*
X219301Y729994D01*
X219176Y730327D01*
X219009Y730577D01*
X218759Y730786D01*
X218426Y730869D01*
G01X221526Y728369D02*
X221818Y728411D01*
X222151Y728536D01*
X222359Y728744D01*
X222443Y729036D01*
X222359Y729327D01*
X222109Y729577D01*
X221734Y729702D01*
X221318D01*
X221068Y729786D01*
X220859Y729994D01*
X220776Y730286D01*
X220901Y730577D01*
X221193Y730786D01*
X221526Y730869D01*
X221859Y730786D01*
X222151Y730577D01*
X222276Y730286D01*
X222193Y729994D01*
X221984Y729786D01*
X221734Y729702D01*
X221318D01*
X220943Y729577D01*
X220693Y729327D01*
X220609Y729036D01*
X220693Y728744D01*
X220901Y728536D01*
X221234Y728411D01*
X221526Y728369D01*
G01X226776Y736686D02*
X224276D01*
Y737727D01*
X224401Y738061D01*
X224568Y738269D01*
X224901Y738352D01*
X225234Y738269D01*
X225443Y738019D01*
X225568Y737727D01*
Y736686D01*
G01Y737727D02*
X226776Y738352D01*
G01X226484Y739911D02*
X226693Y740202D01*
X226776Y740536D01*
X226693Y740869D01*
X226443Y741161D01*
X226068Y741369D01*
X225693Y741452D01*
X225234D01*
X224859Y741369D01*
X224526Y741161D01*
X224359Y740911D01*
X224276Y740619D01*
X224359Y740286D01*
X224526Y740036D01*
X224776Y739869D01*
X225109Y739786D01*
X225401Y739869D01*
X225693Y740077D01*
X225859Y740327D01*
X225901Y740619D01*
X225818Y740952D01*
X225609Y741202D01*
X225234Y741452D01*
G01X224276Y743719D02*
X224359Y743386D01*
X224568Y743136D01*
X224818Y742969D01*
X225151Y742844D01*
X225526Y742802D01*
X225901Y742844D01*
X226234Y742969D01*
X226484Y743136D01*
X226693Y743386D01*
X226776Y743719D01*
X226693Y744052D01*
X226484Y744302D01*
X226234Y744469D01*
X225901Y744594D01*
X225526Y744636D01*
X225151Y744594D01*
X224818Y744469D01*
X224568Y744302D01*
X224359Y744052D01*
X224276Y743719D01*
G01X226276Y745902D02*
X226568Y746152D01*
X226734Y746486D01*
X226776Y746861D01*
X226734Y747194D01*
X226526Y747527D01*
X226276Y747736D01*
X226026Y747777D01*
X225734Y747694D01*
X225526Y747402D01*
X225443Y747111D01*
Y746736D01*
G01Y747111D02*
X225318Y747361D01*
X225109Y747569D01*
X224859Y747652D01*
X224609Y747569D01*
X224401Y747361D01*
X224276Y746986D01*
X224318Y746611D01*
X224484Y746236D01*
G01X206000Y739200D02*
X202000D01*
Y731800D01*
G01X222476Y736686D02*
X219976D01*
Y737727D01*
X220101Y738061D01*
X220268Y738269D01*
X220601Y738352D01*
X220934Y738269D01*
X221143Y738019D01*
X221268Y737727D01*
Y736686D01*
G01Y737727D02*
X222476Y738352D01*
G01X222184Y739911D02*
X222393Y740202D01*
X222476Y740536D01*
X222393Y740869D01*
X222143Y741161D01*
X221768Y741369D01*
X221393Y741452D01*
X220934D01*
X220559Y741369D01*
X220226Y741161D01*
X220059Y740911D01*
X219976Y740619D01*
X220059Y740286D01*
X220226Y740036D01*
X220476Y739869D01*
X220809Y739786D01*
X221101Y739869D01*
X221393Y740077D01*
X221559Y740327D01*
X221601Y740619D01*
X221518Y740952D01*
X221309Y741202D01*
X220934Y741452D01*
G01X219976Y743719D02*
X220059Y743386D01*
X220268Y743136D01*
X220518Y742969D01*
X220851Y742844D01*
X221226Y742802D01*
X221601Y742844D01*
X221934Y742969D01*
X222184Y743136D01*
X222393Y743386D01*
X222476Y743719D01*
X222393Y744052D01*
X222184Y744302D01*
X221934Y744469D01*
X221601Y744594D01*
X221226Y744636D01*
X220851Y744594D01*
X220518Y744469D01*
X220268Y744302D01*
X220059Y744052D01*
X219976Y743719D01*
G01Y746819D02*
X220059Y746486D01*
X220268Y746236D01*
X220518Y746069D01*
X220851Y745944D01*
X221226Y745902D01*
X221601Y745944D01*
X221934Y746069D01*
X222184Y746236D01*
X222393Y746486D01*
X222476Y746819D01*
X222393Y747152D01*
X222184Y747402D01*
X221934Y747569D01*
X221601Y747694D01*
X221226Y747736D01*
X220851Y747694D01*
X220518Y747569D01*
X220268Y747402D01*
X220059Y747152D01*
X219976Y746819D01*
G01X224393Y732369D02*
Y734869D01*
X225434D01*
X225768Y734744D01*
X225976Y734577D01*
X226059Y734244D01*
X225976Y733911D01*
X225726Y733702D01*
X225434Y733577D01*
X224393D01*
G01X225434D02*
X226059Y732369D01*
G01X228326D02*
X228618Y732411D01*
X228951Y732536D01*
X229159Y732744D01*
X229243Y733036D01*
X229159Y733327D01*
X228909Y733577D01*
X228534Y733702D01*
X228118D01*
X227868Y733786D01*
X227659Y733994D01*
X227576Y734286D01*
X227701Y734577D01*
X227993Y734786D01*
X228326Y734869D01*
X228659Y734786D01*
X228951Y734577D01*
X229076Y734286D01*
X228993Y733994D01*
X228784Y733786D01*
X228534Y733702D01*
X228118D01*
X227743Y733577D01*
X227493Y733327D01*
X227409Y733036D01*
X227493Y732744D01*
X227701Y732536D01*
X228034Y732411D01*
X228326Y732369D01*
G01X230718Y732661D02*
X231009Y732452D01*
X231343Y732369D01*
X231676Y732452D01*
X231968Y732702D01*
X232176Y733077D01*
X232259Y733452D01*
Y733911D01*
X232176Y734286D01*
X231968Y734619D01*
X231718Y734786D01*
X231426Y734869D01*
X231093Y734786D01*
X230843Y734619D01*
X230676Y734369D01*
X230593Y734036D01*
X230676Y733744D01*
X230884Y733452D01*
X231134Y733286D01*
X231426Y733244D01*
X231759Y733327D01*
X232009Y733536D01*
X232259Y733911D01*
G01X234526Y732369D02*
X234818Y732411D01*
X235151Y732536D01*
X235359Y732744D01*
X235443Y733036D01*
X235359Y733327D01*
X235109Y733577D01*
X234734Y733702D01*
X234318D01*
X234068Y733786D01*
X233859Y733994D01*
X233776Y734286D01*
X233901Y734577D01*
X234193Y734786D01*
X234526Y734869D01*
X234859Y734786D01*
X235151Y734577D01*
X235276Y734286D01*
X235193Y733994D01*
X234984Y733786D01*
X234734Y733702D01*
X234318D01*
X233943Y733577D01*
X233693Y733327D01*
X233609Y733036D01*
X233693Y732744D01*
X233901Y732536D01*
X234234Y732411D01*
X234526Y732369D01*
G01X209200Y727500D02*
Y731500D01*
X201800D01*
G01X211393Y732369D02*
Y734869D01*
X212434D01*
X212768Y734744D01*
X212976Y734577D01*
X213059Y734244D01*
X212976Y733911D01*
X212726Y733702D01*
X212434Y733577D01*
X211393D01*
G01X212434D02*
X213059Y732369D01*
G01X215326D02*
X215618Y732411D01*
X215951Y732536D01*
X216159Y732744D01*
X216243Y733036D01*
X216159Y733327D01*
X215909Y733577D01*
X215534Y733702D01*
X215118D01*
X214868Y733786D01*
X214659Y733994D01*
X214576Y734286D01*
X214701Y734577D01*
X214993Y734786D01*
X215326Y734869D01*
X215659Y734786D01*
X215951Y734577D01*
X216076Y734286D01*
X215993Y733994D01*
X215784Y733786D01*
X215534Y733702D01*
X215118D01*
X214743Y733577D01*
X214493Y733327D01*
X214409Y733036D01*
X214493Y732744D01*
X214701Y732536D01*
X215034Y732411D01*
X215326Y732369D01*
G01X217718Y732661D02*
X218009Y732452D01*
X218343Y732369D01*
X218676Y732452D01*
X218968Y732702D01*
X219176Y733077D01*
X219259Y733452D01*
Y733911D01*
X219176Y734286D01*
X218968Y734619D01*
X218718Y734786D01*
X218426Y734869D01*
X218093Y734786D01*
X217843Y734619D01*
X217676Y734369D01*
X217593Y734036D01*
X217676Y733744D01*
X217884Y733452D01*
X218134Y733286D01*
X218426Y733244D01*
X218759Y733327D01*
X219009Y733536D01*
X219259Y733911D01*
G01X221443Y732369D02*
X221526Y732911D01*
X221651Y733369D01*
X221818Y733786D01*
X222026Y734244D01*
X222359Y734869D01*
X220693D01*
G01X217503Y743534D02*
X215003D01*
Y744575D01*
X215128Y744909D01*
X215295Y745117D01*
X215628Y745200D01*
X215961Y745117D01*
X216170Y744867D01*
X216295Y744575D01*
Y743534D01*
G01Y744575D02*
X217503Y745200D01*
G01Y747467D02*
X217461Y747759D01*
X217336Y748092D01*
X217128Y748300D01*
X216836Y748384D01*
X216545Y748300D01*
X216295Y748050D01*
X216170Y747675D01*
Y747259D01*
X216086Y747009D01*
X215878Y746800D01*
X215586Y746717D01*
X215295Y746842D01*
X215086Y747134D01*
X215003Y747467D01*
X215086Y747800D01*
X215295Y748092D01*
X215586Y748217D01*
X215878Y748134D01*
X216086Y747925D01*
X216170Y747675D01*
Y747259D01*
X216295Y746884D01*
X216545Y746634D01*
X216836Y746550D01*
X217128Y746634D01*
X217336Y746842D01*
X217461Y747175D01*
X217503Y747467D01*
G01X217211Y749859D02*
X217420Y750150D01*
X217503Y750484D01*
X217420Y750817D01*
X217170Y751109D01*
X216795Y751317D01*
X216420Y751400D01*
X215961D01*
X215586Y751317D01*
X215253Y751109D01*
X215086Y750859D01*
X215003Y750567D01*
X215086Y750234D01*
X215253Y749984D01*
X215503Y749817D01*
X215836Y749734D01*
X216128Y749817D01*
X216420Y750025D01*
X216586Y750275D01*
X216628Y750567D01*
X216545Y750900D01*
X216336Y751150D01*
X215961Y751400D01*
G01X217003Y752750D02*
X217295Y753000D01*
X217461Y753334D01*
X217503Y753709D01*
X217461Y754042D01*
X217253Y754375D01*
X217003Y754584D01*
X216753Y754625D01*
X216461Y754542D01*
X216253Y754250D01*
X216170Y753959D01*
Y753584D01*
G01Y753959D02*
X216045Y754209D01*
X215836Y754417D01*
X215586Y754500D01*
X215336Y754417D01*
X215128Y754209D01*
X215003Y753834D01*
X215045Y753459D01*
X215211Y753084D01*
G01X213503Y743534D02*
X211003D01*
Y744575D01*
X211128Y744909D01*
X211295Y745117D01*
X211628Y745200D01*
X211961Y745117D01*
X212170Y744867D01*
X212295Y744575D01*
Y743534D01*
G01Y744575D02*
X213503Y745200D01*
G01Y747467D02*
X213461Y747759D01*
X213336Y748092D01*
X213128Y748300D01*
X212836Y748384D01*
X212545Y748300D01*
X212295Y748050D01*
X212170Y747675D01*
Y747259D01*
X212086Y747009D01*
X211878Y746800D01*
X211586Y746717D01*
X211295Y746842D01*
X211086Y747134D01*
X211003Y747467D01*
X211086Y747800D01*
X211295Y748092D01*
X211586Y748217D01*
X211878Y748134D01*
X212086Y747925D01*
X212170Y747675D01*
Y747259D01*
X212295Y746884D01*
X212545Y746634D01*
X212836Y746550D01*
X213128Y746634D01*
X213336Y746842D01*
X213461Y747175D01*
X213503Y747467D01*
G01Y750567D02*
X213461Y750859D01*
X213336Y751192D01*
X213128Y751400D01*
X212836Y751484D01*
X212545Y751400D01*
X212295Y751150D01*
X212170Y750775D01*
Y750359D01*
X212086Y750109D01*
X211878Y749900D01*
X211586Y749817D01*
X211295Y749942D01*
X211086Y750234D01*
X211003Y750567D01*
X211086Y750900D01*
X211295Y751192D01*
X211586Y751317D01*
X211878Y751234D01*
X212086Y751025D01*
X212170Y750775D01*
Y750359D01*
X212295Y749984D01*
X212545Y749734D01*
X212836Y749650D01*
X213128Y749734D01*
X213336Y749942D01*
X213461Y750275D01*
X213503Y750567D01*
G01X213211Y752959D02*
X213420Y753250D01*
X213503Y753584D01*
X213420Y753917D01*
X213170Y754209D01*
X212795Y754417D01*
X212420Y754500D01*
X211961D01*
X211586Y754417D01*
X211253Y754209D01*
X211086Y753959D01*
X211003Y753667D01*
X211086Y753334D01*
X211253Y753084D01*
X211503Y752917D01*
X211836Y752834D01*
X212128Y752917D01*
X212420Y753125D01*
X212586Y753375D01*
X212628Y753667D01*
X212545Y754000D01*
X212336Y754250D01*
X211961Y754500D01*
G01X215851Y776938D02*
Y775146D01*
X216018Y774771D01*
X216351Y774521D01*
X216768Y774438D01*
X217185Y774521D01*
X217518Y774771D01*
X217685Y775146D01*
Y776938D01*
G01X218951Y774938D02*
X219201Y774646D01*
X219535Y774480D01*
X219910Y774438D01*
X220243Y774480D01*
X220576Y774688D01*
X220785Y774938D01*
X220826Y775188D01*
X220743Y775480D01*
X220451Y775688D01*
X220160Y775771D01*
X219785D01*
G01X220160D02*
X220410Y775896D01*
X220618Y776105D01*
X220701Y776355D01*
X220618Y776605D01*
X220410Y776813D01*
X220035Y776938D01*
X219660Y776896D01*
X219285Y776730D01*
G01X222968Y774438D02*
Y776938D01*
X222468Y776438D01*
G01Y774438D02*
X223468D01*
G01X205500Y774300D02*
Y762400D01*
G01X201500Y764000D02*
X199900Y762400D01*
G01X201500Y764000D02*
X203100Y762400D01*
G01X216767Y781959D02*
X216517Y782084D01*
X216225Y782167D01*
X215892D01*
X215517Y782042D01*
X215225Y781834D01*
X215017Y781584D01*
X214850Y781167D01*
X214808Y780792D01*
X214892Y780417D01*
X215017Y780167D01*
X215267Y779917D01*
X215558Y779750D01*
X215850Y779667D01*
X216142D01*
X216433Y779750D01*
X216683Y779875D01*
X216892Y780042D01*
G01X218867Y779667D02*
X218950Y780209D01*
X219075Y780667D01*
X219242Y781084D01*
X219450Y781542D01*
X219783Y782167D01*
X218117D01*
G01X222050D02*
X221717Y782084D01*
X221467Y781875D01*
X221300Y781625D01*
X221175Y781292D01*
X221133Y780917D01*
X221175Y780542D01*
X221300Y780209D01*
X221467Y779959D01*
X221717Y779750D01*
X222050Y779667D01*
X222383Y779750D01*
X222633Y779959D01*
X222800Y780209D01*
X222925Y780542D01*
X222967Y780917D01*
X222925Y781292D01*
X222800Y781625D01*
X222633Y781875D01*
X222383Y782084D01*
X222050Y782167D01*
G01X224233Y780042D02*
X224483Y779834D01*
X224775Y779709D01*
X225150Y779667D01*
X225525Y779750D01*
X225817Y779917D01*
X226025Y780209D01*
X226067Y780542D01*
X225983Y780875D01*
X225775Y781084D01*
X225483Y781250D01*
X225192Y781292D01*
X224900Y781250D01*
X224525Y781084D01*
X224650Y782167D01*
X225775D01*
G01X215267Y759092D02*
X215017Y759217D01*
X214725Y759300D01*
X214392D01*
X214017Y759175D01*
X213725Y758967D01*
X213517Y758717D01*
X213350Y758300D01*
X213308Y757925D01*
X213392Y757550D01*
X213517Y757300D01*
X213767Y757050D01*
X214058Y756883D01*
X214350Y756800D01*
X214642D01*
X214933Y756883D01*
X215183Y757008D01*
X215392Y757175D01*
G01X217367Y756800D02*
X217450Y757342D01*
X217575Y757800D01*
X217742Y758217D01*
X217950Y758675D01*
X218283Y759300D01*
X216617D01*
G01X220550D02*
X220217Y759217D01*
X219967Y759008D01*
X219800Y758758D01*
X219675Y758425D01*
X219633Y758050D01*
X219675Y757675D01*
X219800Y757342D01*
X219967Y757092D01*
X220217Y756883D01*
X220550Y756800D01*
X220883Y756883D01*
X221133Y757092D01*
X221300Y757342D01*
X221425Y757675D01*
X221467Y758050D01*
X221425Y758425D01*
X221300Y758758D01*
X221133Y759008D01*
X220883Y759217D01*
X220550Y759300D01*
G01X224150Y756800D02*
Y759300D01*
X222608Y757508D01*
X224692D01*
G01X202000Y749300D02*
X206000D01*
Y756700D01*
G01X212517Y783500D02*
Y786000D01*
X213558D01*
X213892Y785875D01*
X214100Y785708D01*
X214183Y785375D01*
X214100Y785042D01*
X213850Y784833D01*
X213558Y784708D01*
X212517D01*
G01X213558D02*
X214183Y783500D01*
G01X216450D02*
X216742Y783542D01*
X217075Y783667D01*
X217283Y783875D01*
X217367Y784167D01*
X217283Y784458D01*
X217033Y784708D01*
X216658Y784833D01*
X216242D01*
X215992Y784917D01*
X215783Y785125D01*
X215700Y785417D01*
X215825Y785708D01*
X216117Y785917D01*
X216450Y786000D01*
X216783Y785917D01*
X217075Y785708D01*
X217200Y785417D01*
X217117Y785125D01*
X216908Y784917D01*
X216658Y784833D01*
X216242D01*
X215867Y784708D01*
X215617Y784458D01*
X215533Y784167D01*
X215617Y783875D01*
X215825Y783667D01*
X216158Y783542D01*
X216450Y783500D01*
G01X219550D02*
X219842Y783542D01*
X220175Y783667D01*
X220383Y783875D01*
X220467Y784167D01*
X220383Y784458D01*
X220133Y784708D01*
X219758Y784833D01*
X219342D01*
X219092Y784917D01*
X218883Y785125D01*
X218800Y785417D01*
X218925Y785708D01*
X219217Y785917D01*
X219550Y786000D01*
X219883Y785917D01*
X220175Y785708D01*
X220300Y785417D01*
X220217Y785125D01*
X220008Y784917D01*
X219758Y784833D01*
X219342D01*
X218967Y784708D01*
X218717Y784458D01*
X218633Y784167D01*
X218717Y783875D01*
X218925Y783667D01*
X219258Y783542D01*
X219550Y783500D01*
G01X222650D02*
X222942Y783542D01*
X223275Y783667D01*
X223483Y783875D01*
X223567Y784167D01*
X223483Y784458D01*
X223233Y784708D01*
X222858Y784833D01*
X222442D01*
X222192Y784917D01*
X221983Y785125D01*
X221900Y785417D01*
X222025Y785708D01*
X222317Y785917D01*
X222650Y786000D01*
X222983Y785917D01*
X223275Y785708D01*
X223400Y785417D01*
X223317Y785125D01*
X223108Y784917D01*
X222858Y784833D01*
X222442D01*
X222067Y784708D01*
X221817Y784458D01*
X221733Y784167D01*
X221817Y783875D01*
X222025Y783667D01*
X222358Y783542D01*
X222650Y783500D01*
G01X223334Y762017D02*
X220834D01*
Y763058D01*
X220959Y763392D01*
X221126Y763600D01*
X221459Y763683D01*
X221792Y763600D01*
X222001Y763350D01*
X222126Y763058D01*
Y762017D01*
G01Y763058D02*
X223334Y763683D01*
G01Y765950D02*
X223292Y766242D01*
X223167Y766575D01*
X222959Y766783D01*
X222667Y766867D01*
X222376Y766783D01*
X222126Y766533D01*
X222001Y766158D01*
Y765742D01*
X221917Y765492D01*
X221709Y765283D01*
X221417Y765200D01*
X221126Y765325D01*
X220917Y765617D01*
X220834Y765950D01*
X220917Y766283D01*
X221126Y766575D01*
X221417Y766700D01*
X221709Y766617D01*
X221917Y766408D01*
X222001Y766158D01*
Y765742D01*
X222126Y765367D01*
X222376Y765117D01*
X222667Y765033D01*
X222959Y765117D01*
X223167Y765325D01*
X223292Y765658D01*
X223334Y765950D01*
G01Y769050D02*
X223292Y769342D01*
X223167Y769675D01*
X222959Y769883D01*
X222667Y769967D01*
X222376Y769883D01*
X222126Y769633D01*
X222001Y769258D01*
Y768842D01*
X221917Y768592D01*
X221709Y768383D01*
X221417Y768300D01*
X221126Y768425D01*
X220917Y768717D01*
X220834Y769050D01*
X220917Y769383D01*
X221126Y769675D01*
X221417Y769800D01*
X221709Y769717D01*
X221917Y769508D01*
X222001Y769258D01*
Y768842D01*
X222126Y768467D01*
X222376Y768217D01*
X222667Y768133D01*
X222959Y768217D01*
X223167Y768425D01*
X223292Y768758D01*
X223334Y769050D01*
G01X222959Y771233D02*
X223167Y771483D01*
X223292Y771775D01*
X223334Y772150D01*
X223251Y772525D01*
X223084Y772817D01*
X222792Y773025D01*
X222459Y773067D01*
X222126Y772983D01*
X221917Y772775D01*
X221751Y772483D01*
X221709Y772192D01*
X221751Y771900D01*
X221917Y771525D01*
X220834Y771650D01*
Y772775D01*
G01X215000Y762300D02*
X219000D01*
Y769700D01*
G01X206000Y794700D02*
X202000D01*
Y787300D01*
G01X209200Y783000D02*
Y787000D01*
X201800D01*
G01X206698Y843473D02*
X206573Y843223D01*
X206490Y842931D01*
Y842598D01*
X206615Y842223D01*
X206823Y841931D01*
X207073Y841723D01*
X207490Y841556D01*
X207865Y841514D01*
X208240Y841598D01*
X208490Y841723D01*
X208740Y841973D01*
X208907Y842264D01*
X208990Y842556D01*
Y842848D01*
X208907Y843139D01*
X208782Y843389D01*
X208615Y843598D01*
G01X208490Y844739D02*
X208782Y844989D01*
X208948Y845323D01*
X208990Y845698D01*
X208948Y846031D01*
X208740Y846364D01*
X208490Y846573D01*
X208240Y846614D01*
X207948Y846531D01*
X207740Y846239D01*
X207657Y845948D01*
Y845573D01*
G01Y845948D02*
X207532Y846198D01*
X207323Y846406D01*
X207073Y846489D01*
X206823Y846406D01*
X206615Y846198D01*
X206490Y845823D01*
X206532Y845448D01*
X206698Y845073D01*
G01X207948Y847964D02*
X207657Y848256D01*
X207490Y848506D01*
X207407Y848839D01*
X207490Y849131D01*
X207657Y849339D01*
X207907Y849506D01*
X208198Y849548D01*
X208448Y849506D01*
X208698Y849339D01*
X208907Y849089D01*
X208990Y848798D01*
X208907Y848464D01*
X208657Y848173D01*
X208282Y848006D01*
X207865Y847964D01*
X207323Y848048D01*
X207032Y848173D01*
X206740Y848381D01*
X206532Y848673D01*
X206490Y848964D01*
X206573Y849256D01*
X206782Y849464D01*
G01X208990Y852356D02*
X206490D01*
X208282Y850814D01*
Y852898D01*
G01X201400Y843648D02*
X201275Y843398D01*
X201192Y843106D01*
Y842773D01*
X201317Y842398D01*
X201525Y842106D01*
X201775Y841898D01*
X202192Y841731D01*
X202567Y841689D01*
X202942Y841773D01*
X203192Y841898D01*
X203442Y842148D01*
X203609Y842439D01*
X203692Y842731D01*
Y843023D01*
X203609Y843314D01*
X203484Y843564D01*
X203317Y843773D01*
G01X203192Y844914D02*
X203484Y845164D01*
X203650Y845498D01*
X203692Y845873D01*
X203650Y846206D01*
X203442Y846539D01*
X203192Y846748D01*
X202942Y846789D01*
X202650Y846706D01*
X202442Y846414D01*
X202359Y846123D01*
Y845748D01*
G01Y846123D02*
X202234Y846373D01*
X202025Y846581D01*
X201775Y846664D01*
X201525Y846581D01*
X201317Y846373D01*
X201192Y845998D01*
X201234Y845623D01*
X201400Y845248D01*
G01X202650Y848139D02*
X202359Y848431D01*
X202192Y848681D01*
X202109Y849014D01*
X202192Y849306D01*
X202359Y849514D01*
X202609Y849681D01*
X202900Y849723D01*
X203150Y849681D01*
X203400Y849514D01*
X203609Y849264D01*
X203692Y848973D01*
X203609Y848639D01*
X203359Y848348D01*
X202984Y848181D01*
X202567Y848139D01*
X202025Y848223D01*
X201734Y848348D01*
X201442Y848556D01*
X201234Y848848D01*
X201192Y849139D01*
X201275Y849431D01*
X201484Y849639D01*
G01X203192Y851114D02*
X203484Y851364D01*
X203650Y851698D01*
X203692Y852073D01*
X203650Y852406D01*
X203442Y852739D01*
X203192Y852948D01*
X202942Y852989D01*
X202650Y852906D01*
X202442Y852614D01*
X202359Y852323D01*
Y851948D01*
G01Y852323D02*
X202234Y852573D01*
X202025Y852781D01*
X201775Y852864D01*
X201525Y852781D01*
X201317Y852573D01*
X201192Y852198D01*
X201234Y851823D01*
X201400Y851448D01*
G01X219908Y843467D02*
X219783Y843217D01*
X219700Y842925D01*
Y842592D01*
X219825Y842217D01*
X220033Y841925D01*
X220283Y841717D01*
X220700Y841550D01*
X221075Y841508D01*
X221450Y841592D01*
X221700Y841717D01*
X221950Y841967D01*
X222117Y842258D01*
X222200Y842550D01*
Y842842D01*
X222117Y843133D01*
X221992Y843383D01*
X221825Y843592D01*
G01X221700Y844733D02*
X221992Y844983D01*
X222158Y845317D01*
X222200Y845692D01*
X222158Y846025D01*
X221950Y846358D01*
X221700Y846567D01*
X221450Y846608D01*
X221158Y846525D01*
X220950Y846233D01*
X220867Y845942D01*
Y845567D01*
G01Y845942D02*
X220742Y846192D01*
X220533Y846400D01*
X220283Y846483D01*
X220033Y846400D01*
X219825Y846192D01*
X219700Y845817D01*
X219742Y845442D01*
X219908Y845067D01*
G01X221158Y847958D02*
X220867Y848250D01*
X220700Y848500D01*
X220617Y848833D01*
X220700Y849125D01*
X220867Y849333D01*
X221117Y849500D01*
X221408Y849542D01*
X221658Y849500D01*
X221908Y849333D01*
X222117Y849083D01*
X222200Y848792D01*
X222117Y848458D01*
X221867Y848167D01*
X221492Y848000D01*
X221075Y847958D01*
X220533Y848042D01*
X220242Y848167D01*
X219950Y848375D01*
X219742Y848667D01*
X219700Y848958D01*
X219783Y849250D01*
X219992Y849458D01*
G01X220117Y851058D02*
X219867Y851308D01*
X219742Y851600D01*
X219700Y851933D01*
X219783Y852350D01*
X219992Y852642D01*
X220242Y852725D01*
X220492Y852683D01*
X220700Y852517D01*
X221117Y851683D01*
X221408Y851308D01*
X221825Y851058D01*
X222200Y850975D01*
Y852725D01*
G01X213609Y843542D02*
X213484Y843292D01*
X213401Y843000D01*
Y842667D01*
X213526Y842292D01*
X213734Y842000D01*
X213984Y841792D01*
X214401Y841625D01*
X214776Y841583D01*
X215151Y841667D01*
X215401Y841792D01*
X215651Y842042D01*
X215818Y842333D01*
X215901Y842625D01*
Y842917D01*
X215818Y843208D01*
X215693Y843458D01*
X215526Y843667D01*
G01X215401Y844808D02*
X215693Y845058D01*
X215859Y845392D01*
X215901Y845767D01*
X215859Y846100D01*
X215651Y846433D01*
X215401Y846642D01*
X215151Y846683D01*
X214859Y846600D01*
X214651Y846308D01*
X214568Y846017D01*
Y845642D01*
G01Y846017D02*
X214443Y846267D01*
X214234Y846475D01*
X213984Y846558D01*
X213734Y846475D01*
X213526Y846267D01*
X213401Y845892D01*
X213443Y845517D01*
X213609Y845142D01*
G01X214859Y848033D02*
X214568Y848325D01*
X214401Y848575D01*
X214318Y848908D01*
X214401Y849200D01*
X214568Y849408D01*
X214818Y849575D01*
X215109Y849617D01*
X215359Y849575D01*
X215609Y849408D01*
X215818Y849158D01*
X215901Y848867D01*
X215818Y848533D01*
X215568Y848242D01*
X215193Y848075D01*
X214776Y848033D01*
X214234Y848117D01*
X213943Y848242D01*
X213651Y848450D01*
X213443Y848742D01*
X213401Y849033D01*
X213484Y849325D01*
X213693Y849533D01*
G01X215901Y851925D02*
X213401D01*
X213901Y851425D01*
G01X215901D02*
Y852425D01*
G01X231856Y843767D02*
X231731Y843517D01*
X231648Y843225D01*
Y842892D01*
X231773Y842517D01*
X231981Y842225D01*
X232231Y842017D01*
X232648Y841850D01*
X233023Y841808D01*
X233398Y841892D01*
X233648Y842017D01*
X233898Y842267D01*
X234065Y842558D01*
X234148Y842850D01*
Y843142D01*
X234065Y843433D01*
X233940Y843683D01*
X233773Y843892D01*
G01X233648Y845033D02*
X233940Y845283D01*
X234106Y845617D01*
X234148Y845992D01*
X234106Y846325D01*
X233898Y846658D01*
X233648Y846867D01*
X233398Y846908D01*
X233106Y846825D01*
X232898Y846533D01*
X232815Y846242D01*
Y845867D01*
G01Y846242D02*
X232690Y846492D01*
X232481Y846700D01*
X232231Y846783D01*
X231981Y846700D01*
X231773Y846492D01*
X231648Y846117D01*
X231690Y845742D01*
X231856Y845367D01*
G01X233106Y848258D02*
X232815Y848550D01*
X232648Y848800D01*
X232565Y849133D01*
X232648Y849425D01*
X232815Y849633D01*
X233065Y849800D01*
X233356Y849842D01*
X233606Y849800D01*
X233856Y849633D01*
X234065Y849383D01*
X234148Y849092D01*
X234065Y848758D01*
X233815Y848467D01*
X233440Y848300D01*
X233023Y848258D01*
X232481Y848342D01*
X232190Y848467D01*
X231898Y848675D01*
X231690Y848967D01*
X231648Y849258D01*
X231731Y849550D01*
X231940Y849758D01*
G01X231648Y852150D02*
X231731Y851817D01*
X231940Y851567D01*
X232190Y851400D01*
X232523Y851275D01*
X232898Y851233D01*
X233273Y851275D01*
X233606Y851400D01*
X233856Y851567D01*
X234065Y851817D01*
X234148Y852150D01*
X234065Y852483D01*
X233856Y852733D01*
X233606Y852900D01*
X233273Y853025D01*
X232898Y853067D01*
X232523Y853025D01*
X232190Y852900D01*
X231940Y852733D01*
X231731Y852483D01*
X231648Y852150D01*
G01X226455Y843542D02*
X226330Y843292D01*
X226247Y843000D01*
Y842667D01*
X226372Y842292D01*
X226580Y842000D01*
X226830Y841792D01*
X227247Y841625D01*
X227622Y841583D01*
X227997Y841667D01*
X228247Y841792D01*
X228497Y842042D01*
X228664Y842333D01*
X228747Y842625D01*
Y842917D01*
X228664Y843208D01*
X228539Y843458D01*
X228372Y843667D01*
G01X228247Y844808D02*
X228539Y845058D01*
X228705Y845392D01*
X228747Y845767D01*
X228705Y846100D01*
X228497Y846433D01*
X228247Y846642D01*
X227997Y846683D01*
X227705Y846600D01*
X227497Y846308D01*
X227414Y846017D01*
Y845642D01*
G01Y846017D02*
X227289Y846267D01*
X227080Y846475D01*
X226830Y846558D01*
X226580Y846475D01*
X226372Y846267D01*
X226247Y845892D01*
X226289Y845517D01*
X226455Y845142D01*
G01X228372Y847908D02*
X228580Y848158D01*
X228705Y848450D01*
X228747Y848825D01*
X228664Y849200D01*
X228497Y849492D01*
X228205Y849700D01*
X227872Y849742D01*
X227539Y849658D01*
X227330Y849450D01*
X227164Y849158D01*
X227122Y848867D01*
X227164Y848575D01*
X227330Y848200D01*
X226247Y848325D01*
Y849450D01*
G01X228455Y851217D02*
X228664Y851508D01*
X228747Y851842D01*
X228664Y852175D01*
X228414Y852467D01*
X228039Y852675D01*
X227664Y852758D01*
X227205D01*
X226830Y852675D01*
X226497Y852467D01*
X226330Y852217D01*
X226247Y851925D01*
X226330Y851592D01*
X226497Y851342D01*
X226747Y851175D01*
X227080Y851092D01*
X227372Y851175D01*
X227664Y851383D01*
X227830Y851633D01*
X227872Y851925D01*
X227789Y852258D01*
X227580Y852508D01*
X227205Y852758D01*
G01X263334Y86517D02*
X260834D01*
Y87558D01*
X260959Y87892D01*
X261126Y88100D01*
X261459Y88183D01*
X261792Y88100D01*
X262001Y87850D01*
X262126Y87558D01*
Y86517D01*
G01Y87558D02*
X263334Y88183D01*
G01Y90367D02*
X262792Y90450D01*
X262334Y90575D01*
X261917Y90742D01*
X261459Y90950D01*
X260834Y91283D01*
Y89617D01*
G01X262834Y92633D02*
X263126Y92883D01*
X263292Y93217D01*
X263334Y93592D01*
X263292Y93925D01*
X263084Y94258D01*
X262834Y94467D01*
X262584Y94508D01*
X262292Y94425D01*
X262084Y94133D01*
X262001Y93842D01*
Y93467D01*
G01Y93842D02*
X261876Y94092D01*
X261667Y94300D01*
X261417Y94383D01*
X261167Y94300D01*
X260959Y94092D01*
X260834Y93717D01*
X260876Y93342D01*
X261042Y92967D01*
G01X263334Y96567D02*
X262792Y96650D01*
X262334Y96775D01*
X261917Y96942D01*
X261459Y97150D01*
X260834Y97483D01*
Y95817D01*
G01X263200Y107300D02*
X259200D01*
Y99900D01*
G01X246267Y133800D02*
Y136300D01*
X247267D01*
X247600Y136175D01*
X247850Y135883D01*
X247933Y135550D01*
X247850Y135217D01*
X247642Y134967D01*
X247267Y134842D01*
X246267D01*
G01X249283Y136300D02*
Y134508D01*
X249450Y134133D01*
X249783Y133883D01*
X250200Y133800D01*
X250617Y133883D01*
X250950Y134133D01*
X251117Y134508D01*
Y136300D01*
G01X252508Y135883D02*
X252758Y136133D01*
X253050Y136258D01*
X253383Y136300D01*
X253800Y136217D01*
X254092Y136008D01*
X254175Y135758D01*
X254133Y135508D01*
X253967Y135300D01*
X253133Y134883D01*
X252758Y134592D01*
X252508Y134175D01*
X252425Y133800D01*
X254175D01*
G01X245650Y143000D02*
Y138000D01*
X250650D01*
G01X257567Y124667D02*
Y127167D01*
X258567D01*
X258900Y127042D01*
X259150Y126750D01*
X259233Y126417D01*
X259150Y126084D01*
X258942Y125834D01*
X258567Y125709D01*
X257567D01*
G01X261750Y125917D02*
X262583D01*
Y125167D01*
X262333Y124917D01*
X262042Y124750D01*
X261625Y124667D01*
X261208Y124750D01*
X260917Y124917D01*
X260667Y125167D01*
X260500Y125459D01*
X260417Y125792D01*
Y126084D01*
X260500Y126334D01*
X260667Y126625D01*
X260917Y126875D01*
X261167Y127042D01*
X261500Y127167D01*
X261792D01*
X262125Y127084D01*
X262375Y126917D01*
G01X263683Y125167D02*
X263933Y124875D01*
X264267Y124709D01*
X264642Y124667D01*
X264975Y124709D01*
X265308Y124917D01*
X265517Y125167D01*
X265558Y125417D01*
X265475Y125709D01*
X265183Y125917D01*
X264892Y126000D01*
X264517D01*
G01X264892D02*
X265142Y126125D01*
X265350Y126334D01*
X265433Y126584D01*
X265350Y126834D01*
X265142Y127042D01*
X264767Y127167D01*
X264392Y127125D01*
X264017Y126959D01*
G01X263417Y129100D02*
Y131600D01*
X264417D01*
X264750Y131475D01*
X265000Y131183D01*
X265083Y130850D01*
X265000Y130517D01*
X264792Y130267D01*
X264417Y130142D01*
X263417D01*
G01X266517Y129100D02*
Y131600D01*
X267558D01*
X267892Y131475D01*
X268100Y131308D01*
X268183Y130975D01*
X268100Y130642D01*
X267850Y130433D01*
X267558Y130308D01*
X266517D01*
G01X267558D02*
X268183Y129100D01*
G01X269533Y129600D02*
X269783Y129308D01*
X270117Y129142D01*
X270492Y129100D01*
X270825Y129142D01*
X271158Y129350D01*
X271367Y129600D01*
X271408Y129850D01*
X271325Y130142D01*
X271033Y130350D01*
X270742Y130433D01*
X270367D01*
G01X270742D02*
X270992Y130558D01*
X271200Y130767D01*
X271283Y131017D01*
X271200Y131267D01*
X270992Y131475D01*
X270617Y131600D01*
X270242Y131558D01*
X269867Y131392D01*
G01X273467Y129100D02*
X273550Y129642D01*
X273675Y130100D01*
X273842Y130517D01*
X274050Y130975D01*
X274383Y131600D01*
X272717D01*
G01X241700Y137500D02*
Y141500D01*
X234300D01*
G01X262017Y116000D02*
Y118500D01*
X263017D01*
X263350Y118375D01*
X263600Y118083D01*
X263683Y117750D01*
X263600Y117417D01*
X263392Y117167D01*
X263017Y117042D01*
X262017D01*
G01X265117Y116000D02*
Y118500D01*
X266158D01*
X266492Y118375D01*
X266700Y118208D01*
X266783Y117875D01*
X266700Y117542D01*
X266450Y117333D01*
X266158Y117208D01*
X265117D01*
G01X266158D02*
X266783Y116000D01*
G01X268133Y116500D02*
X268383Y116208D01*
X268717Y116042D01*
X269092Y116000D01*
X269425Y116042D01*
X269758Y116250D01*
X269967Y116500D01*
X270008Y116750D01*
X269925Y117042D01*
X269633Y117250D01*
X269342Y117333D01*
X268967D01*
G01X269342D02*
X269592Y117458D01*
X269800Y117667D01*
X269883Y117917D01*
X269800Y118167D01*
X269592Y118375D01*
X269217Y118500D01*
X268842Y118458D01*
X268467Y118292D01*
G01X271233Y116500D02*
X271483Y116208D01*
X271817Y116042D01*
X272192Y116000D01*
X272525Y116042D01*
X272858Y116250D01*
X273067Y116500D01*
X273108Y116750D01*
X273025Y117042D01*
X272733Y117250D01*
X272442Y117333D01*
X272067D01*
G01X272442D02*
X272692Y117458D01*
X272900Y117667D01*
X272983Y117917D01*
X272900Y118167D01*
X272692Y118375D01*
X272317Y118500D01*
X271942Y118458D01*
X271567Y118292D01*
G01X235317Y123700D02*
Y126200D01*
X236358D01*
X236692Y126075D01*
X236900Y125908D01*
X236983Y125575D01*
X236900Y125242D01*
X236650Y125033D01*
X236358Y124908D01*
X235317D01*
G01X236358D02*
X236983Y123700D01*
G01X239167D02*
X239250Y124242D01*
X239375Y124700D01*
X239542Y125117D01*
X239750Y125575D01*
X240083Y126200D01*
X238417D01*
G01X241433Y124200D02*
X241683Y123908D01*
X242017Y123742D01*
X242392Y123700D01*
X242725Y123742D01*
X243058Y123950D01*
X243267Y124200D01*
X243308Y124450D01*
X243225Y124742D01*
X242933Y124950D01*
X242642Y125033D01*
X242267D01*
G01X242642D02*
X242892Y125158D01*
X243100Y125367D01*
X243183Y125617D01*
X243100Y125867D01*
X242892Y126075D01*
X242517Y126200D01*
X242142Y126158D01*
X241767Y125992D01*
G01X244742Y123992D02*
X245033Y123783D01*
X245367Y123700D01*
X245700Y123783D01*
X245992Y124033D01*
X246200Y124408D01*
X246283Y124783D01*
Y125242D01*
X246200Y125617D01*
X245992Y125950D01*
X245742Y126117D01*
X245450Y126200D01*
X245117Y126117D01*
X244867Y125950D01*
X244700Y125700D01*
X244617Y125367D01*
X244700Y125075D01*
X244908Y124783D01*
X245158Y124617D01*
X245450Y124575D01*
X245783Y124658D01*
X246033Y124867D01*
X246283Y125242D01*
G01X255928Y122804D02*
Y126804D01*
X248528D01*
G01X262017Y120000D02*
Y122500D01*
X263017D01*
X263350Y122375D01*
X263600Y122083D01*
X263683Y121750D01*
X263600Y121417D01*
X263392Y121167D01*
X263017Y121042D01*
X262017D01*
G01X266867Y122292D02*
X266617Y122417D01*
X266325Y122500D01*
X265992D01*
X265617Y122375D01*
X265325Y122167D01*
X265117Y121917D01*
X264950Y121500D01*
X264908Y121125D01*
X264992Y120750D01*
X265117Y120500D01*
X265367Y120250D01*
X265658Y120083D01*
X265950Y120000D01*
X266242D01*
X266533Y120083D01*
X266783Y120208D01*
X266992Y120375D01*
G01X268133Y120500D02*
X268383Y120208D01*
X268717Y120042D01*
X269092Y120000D01*
X269425Y120042D01*
X269758Y120250D01*
X269967Y120500D01*
X270008Y120750D01*
X269925Y121042D01*
X269633Y121250D01*
X269342Y121333D01*
X268967D01*
G01X269342D02*
X269592Y121458D01*
X269800Y121667D01*
X269883Y121917D01*
X269800Y122167D01*
X269592Y122375D01*
X269217Y122500D01*
X268842Y122458D01*
X268467Y122292D01*
G01X272150Y120000D02*
Y122500D01*
X271650Y122000D01*
G01Y120000D02*
X272650D01*
G01X263767Y114292D02*
X263517Y114417D01*
X263225Y114500D01*
X262892D01*
X262517Y114375D01*
X262225Y114167D01*
X262017Y113917D01*
X261850Y113500D01*
X261808Y113125D01*
X261892Y112750D01*
X262017Y112500D01*
X262267Y112250D01*
X262558Y112083D01*
X262850Y112000D01*
X263142D01*
X263433Y112083D01*
X263683Y112208D01*
X263892Y112375D01*
G01X265158Y114083D02*
X265408Y114333D01*
X265700Y114458D01*
X266033Y114500D01*
X266450Y114417D01*
X266742Y114208D01*
X266825Y113958D01*
X266783Y113708D01*
X266617Y113500D01*
X265783Y113083D01*
X265408Y112792D01*
X265158Y112375D01*
X265075Y112000D01*
X266825D01*
G01X268258Y113042D02*
X268550Y113333D01*
X268800Y113500D01*
X269133Y113583D01*
X269425Y113500D01*
X269633Y113333D01*
X269800Y113083D01*
X269842Y112792D01*
X269800Y112542D01*
X269633Y112292D01*
X269383Y112083D01*
X269092Y112000D01*
X268758Y112083D01*
X268467Y112333D01*
X268300Y112708D01*
X268258Y113125D01*
X268342Y113667D01*
X268467Y113958D01*
X268675Y114250D01*
X268967Y114458D01*
X269258Y114500D01*
X269550Y114417D01*
X269758Y114208D01*
G01X272067Y112000D02*
X272150Y112542D01*
X272275Y113000D01*
X272442Y113417D01*
X272650Y113875D01*
X272983Y114500D01*
X271317D01*
G01X246657Y155937D02*
X244657D01*
G01X246657Y146094D02*
X243657D01*
G01X250650Y166000D02*
X245650D01*
Y161000D01*
G01X237505Y150062D02*
X233505D01*
Y142662D01*
G01X240834Y152517D02*
X238334D01*
Y153517D01*
X238459Y153850D01*
X238751Y154100D01*
X239084Y154183D01*
X239417Y154100D01*
X239667Y153892D01*
X239792Y153517D01*
Y152517D01*
G01X238542Y157367D02*
X238417Y157117D01*
X238334Y156825D01*
Y156492D01*
X238459Y156117D01*
X238667Y155825D01*
X238917Y155617D01*
X239334Y155450D01*
X239709Y155408D01*
X240084Y155492D01*
X240334Y155617D01*
X240584Y155867D01*
X240751Y156158D01*
X240834Y156450D01*
Y156742D01*
X240751Y157033D01*
X240626Y157283D01*
X240459Y157492D01*
G01X238751Y158758D02*
X238501Y159008D01*
X238376Y159300D01*
X238334Y159633D01*
X238417Y160050D01*
X238626Y160342D01*
X238876Y160425D01*
X239126Y160383D01*
X239334Y160217D01*
X239751Y159383D01*
X240042Y159008D01*
X240459Y158758D01*
X240834Y158675D01*
Y160425D01*
G01X240542Y161942D02*
X240751Y162233D01*
X240834Y162567D01*
X240751Y162900D01*
X240501Y163192D01*
X240126Y163400D01*
X239751Y163483D01*
X239292D01*
X238917Y163400D01*
X238584Y163192D01*
X238417Y162942D01*
X238334Y162650D01*
X238417Y162317D01*
X238584Y162067D01*
X238834Y161900D01*
X239167Y161817D01*
X239459Y161900D01*
X239751Y162108D01*
X239917Y162358D01*
X239959Y162650D01*
X239876Y162983D01*
X239667Y163233D01*
X239292Y163483D01*
G01X246372Y201890D02*
Y204390D01*
X247372D01*
X247705Y204265D01*
X247955Y203973D01*
X248038Y203640D01*
X247955Y203307D01*
X247747Y203057D01*
X247372Y202932D01*
X246372D01*
G01X251222Y204182D02*
X250972Y204307D01*
X250680Y204390D01*
X250347D01*
X249972Y204265D01*
X249680Y204057D01*
X249472Y203807D01*
X249305Y203390D01*
X249263Y203015D01*
X249347Y202640D01*
X249472Y202390D01*
X249722Y202140D01*
X250013Y201973D01*
X250305Y201890D01*
X250597D01*
X250888Y201973D01*
X251138Y202098D01*
X251347Y202265D01*
G01X252613Y203973D02*
X252863Y204223D01*
X253155Y204348D01*
X253488Y204390D01*
X253905Y204307D01*
X254197Y204098D01*
X254280Y203848D01*
X254238Y203598D01*
X254072Y203390D01*
X253238Y202973D01*
X252863Y202682D01*
X252613Y202265D01*
X252530Y201890D01*
X254280D01*
G01X256505D02*
Y204390D01*
X256005Y203890D01*
G01Y201890D02*
X257005D01*
G01X246372Y197744D02*
Y200244D01*
X247372D01*
X247705Y200119D01*
X247955Y199827D01*
X248038Y199494D01*
X247955Y199161D01*
X247747Y198911D01*
X247372Y198786D01*
X246372D01*
G01X251222Y200036D02*
X250972Y200161D01*
X250680Y200244D01*
X250347D01*
X249972Y200119D01*
X249680Y199911D01*
X249472Y199661D01*
X249305Y199244D01*
X249263Y198869D01*
X249347Y198494D01*
X249472Y198244D01*
X249722Y197994D01*
X250013Y197827D01*
X250305Y197744D01*
X250597D01*
X250888Y197827D01*
X251138Y197952D01*
X251347Y198119D01*
G01X252613Y199827D02*
X252863Y200077D01*
X253155Y200202D01*
X253488Y200244D01*
X253905Y200161D01*
X254197Y199952D01*
X254280Y199702D01*
X254238Y199452D01*
X254072Y199244D01*
X253238Y198827D01*
X252863Y198536D01*
X252613Y198119D01*
X252530Y197744D01*
X254280D01*
G01X255588Y198119D02*
X255838Y197911D01*
X256130Y197786D01*
X256505Y197744D01*
X256880Y197827D01*
X257172Y197994D01*
X257380Y198286D01*
X257422Y198619D01*
X257338Y198952D01*
X257130Y199161D01*
X256838Y199327D01*
X256547Y199369D01*
X256255Y199327D01*
X255880Y199161D01*
X256005Y200244D01*
X257130D01*
G01X246372Y205847D02*
Y208347D01*
X247372D01*
X247705Y208222D01*
X247955Y207930D01*
X248038Y207597D01*
X247955Y207264D01*
X247747Y207014D01*
X247372Y206889D01*
X246372D01*
G01X251222Y208139D02*
X250972Y208264D01*
X250680Y208347D01*
X250347D01*
X249972Y208222D01*
X249680Y208014D01*
X249472Y207764D01*
X249305Y207347D01*
X249263Y206972D01*
X249347Y206597D01*
X249472Y206347D01*
X249722Y206097D01*
X250013Y205930D01*
X250305Y205847D01*
X250597D01*
X250888Y205930D01*
X251138Y206055D01*
X251347Y206222D01*
G01X252488Y206347D02*
X252738Y206055D01*
X253072Y205889D01*
X253447Y205847D01*
X253780Y205889D01*
X254113Y206097D01*
X254322Y206347D01*
X254363Y206597D01*
X254280Y206889D01*
X253988Y207097D01*
X253697Y207180D01*
X253322D01*
G01X253697D02*
X253947Y207305D01*
X254155Y207514D01*
X254238Y207764D01*
X254155Y208014D01*
X253947Y208222D01*
X253572Y208347D01*
X253197Y208305D01*
X252822Y208139D01*
G01X255713Y207930D02*
X255963Y208180D01*
X256255Y208305D01*
X256588Y208347D01*
X257005Y208264D01*
X257297Y208055D01*
X257380Y207805D01*
X257338Y207555D01*
X257172Y207347D01*
X256338Y206930D01*
X255963Y206639D01*
X255713Y206222D01*
X255630Y205847D01*
X257380D01*
G01X239700Y182400D02*
Y189600D01*
G01X261625Y215899D02*
X261958Y215691D01*
X262333Y215566D01*
X262667D01*
X263000Y215691D01*
X263250Y215899D01*
X263375Y216191D01*
X263292Y216483D01*
X263083Y216733D01*
X262708Y216899D01*
X262208Y216983D01*
X261917Y217149D01*
X261792Y217441D01*
X261875Y217733D01*
X262083Y217941D01*
X262375Y218066D01*
X262667D01*
X262958Y217983D01*
X263208Y217774D01*
G01X266433Y215566D02*
X264767D01*
Y218066D01*
X266433D01*
G01X265767Y216858D02*
X264767D01*
G01X269617Y217858D02*
X269367Y217983D01*
X269075Y218066D01*
X268742D01*
X268367Y217941D01*
X268075Y217733D01*
X267867Y217483D01*
X267700Y217066D01*
X267658Y216691D01*
X267742Y216316D01*
X267867Y216066D01*
X268117Y215816D01*
X268408Y215649D01*
X268700Y215566D01*
X268992D01*
X269283Y215649D01*
X269533Y215774D01*
X269742Y215941D01*
G01X270883Y218066D02*
Y216274D01*
X271050Y215899D01*
X271383Y215649D01*
X271800Y215566D01*
X272217Y215649D01*
X272550Y215899D01*
X272717Y216274D01*
Y218066D01*
G01X274067Y215566D02*
Y218066D01*
X275108D01*
X275442Y217941D01*
X275650Y217774D01*
X275733Y217441D01*
X275650Y217108D01*
X275400Y216899D01*
X275108Y216774D01*
X274067D01*
G01X275108D02*
X275733Y215566D01*
G01X278833D02*
X277167D01*
Y218066D01*
X278833D01*
G01X278167Y216858D02*
X277167D01*
G01X285117Y217858D02*
X284867Y217983D01*
X284575Y218066D01*
X284242D01*
X283867Y217941D01*
X283575Y217733D01*
X283367Y217483D01*
X283200Y217066D01*
X283158Y216691D01*
X283242Y216316D01*
X283367Y216066D01*
X283617Y215816D01*
X283908Y215649D01*
X284200Y215566D01*
X284492D01*
X284783Y215649D01*
X285033Y215774D01*
X285242Y215941D01*
G01X286425Y215899D02*
X286758Y215691D01*
X287133Y215566D01*
X287467D01*
X287800Y215691D01*
X288050Y215899D01*
X288175Y216191D01*
X288092Y216483D01*
X287883Y216733D01*
X287508Y216899D01*
X287008Y216983D01*
X286717Y217149D01*
X286592Y217441D01*
X286675Y217733D01*
X286883Y217941D01*
X287175Y218066D01*
X287467D01*
X287758Y217983D01*
X288008Y217774D01*
G01X235763Y223016D02*
X236096Y223266D01*
X236346Y223682D01*
X236513Y224266D01*
X236346Y224766D01*
X236013Y225099D01*
X235429Y225349D01*
X233179D01*
Y220349D01*
X235929D01*
X236513Y220682D01*
X236846Y221182D01*
X237013Y221766D01*
X236846Y222349D01*
X236346Y222849D01*
X235763Y223016D01*
X233179D01*
G01X238529Y220349D02*
Y225349D01*
X240696Y221182D01*
X242863Y225349D01*
Y220349D01*
G01X248129Y224932D02*
X247629Y225182D01*
X247046Y225349D01*
X246379D01*
X245629Y225099D01*
X245046Y224682D01*
X244629Y224182D01*
X244296Y223349D01*
X244213Y222599D01*
X244379Y221849D01*
X244629Y221349D01*
X245129Y220849D01*
X245713Y220516D01*
X246296Y220349D01*
X246879D01*
X247463Y220516D01*
X247963Y220766D01*
X248379Y221099D01*
G01X255913Y220349D02*
Y225349D01*
X259079D01*
G01X257913Y222932D02*
X255913D01*
G01X261429Y225349D02*
Y220349D01*
X264763D01*
G01X266613D02*
X268696Y225349D01*
X270779Y220349D01*
G01X270029Y222099D02*
X267363D01*
G01X272546Y221016D02*
X273213Y220599D01*
X273963Y220349D01*
X274629D01*
X275296Y220599D01*
X275796Y221016D01*
X276046Y221599D01*
X275879Y222182D01*
X275463Y222682D01*
X274713Y223016D01*
X273713Y223182D01*
X273129Y223516D01*
X272879Y224099D01*
X273046Y224682D01*
X273463Y225099D01*
X274046Y225349D01*
X274629D01*
X275213Y225182D01*
X275713Y224766D01*
G01X278146Y220349D02*
Y225349D01*
G01X281646D02*
Y220349D01*
G01Y222849D02*
X278146D01*
G01X238331Y235780D02*
X234331D01*
Y228380D01*
G01X238400Y228400D02*
X242400D01*
Y235800D01*
G01X235031Y251580D02*
Y276980D01*
G01X275731Y251580D02*
X235031D01*
G01X265766Y302617D02*
X263266D01*
Y303658D01*
X263391Y303992D01*
X263558Y304200D01*
X263891Y304283D01*
X264224Y304200D01*
X264433Y303950D01*
X264558Y303658D01*
Y302617D01*
G01Y303658D02*
X265766Y304283D01*
G01Y306467D02*
X265224Y306550D01*
X264766Y306675D01*
X264349Y306842D01*
X263891Y307050D01*
X263266Y307383D01*
Y305717D01*
G01X265266Y308733D02*
X265558Y308983D01*
X265724Y309317D01*
X265766Y309692D01*
X265724Y310025D01*
X265516Y310358D01*
X265266Y310567D01*
X265016Y310608D01*
X264724Y310525D01*
X264516Y310233D01*
X264433Y309942D01*
Y309567D01*
G01Y309942D02*
X264308Y310192D01*
X264099Y310400D01*
X263849Y310483D01*
X263599Y310400D01*
X263391Y310192D01*
X263266Y309817D01*
X263308Y309442D01*
X263474Y309067D01*
G01X265266Y311833D02*
X265558Y312083D01*
X265724Y312417D01*
X265766Y312792D01*
X265724Y313125D01*
X265516Y313458D01*
X265266Y313667D01*
X265016Y313708D01*
X264724Y313625D01*
X264516Y313333D01*
X264433Y313042D01*
Y312667D01*
G01Y313042D02*
X264308Y313292D01*
X264099Y313500D01*
X263849Y313583D01*
X263599Y313500D01*
X263391Y313292D01*
X263266Y312917D01*
X263308Y312542D01*
X263474Y312167D01*
G01X260900Y299000D02*
X256900D01*
Y291600D01*
G01X265000Y298800D02*
X261000D01*
Y291400D01*
G01X234021Y293389D02*
Y291597D01*
X234188Y291222D01*
X234521Y290972D01*
X234938Y290889D01*
X235355Y290972D01*
X235688Y291222D01*
X235855Y291597D01*
Y293389D01*
G01X238038Y290889D02*
Y293389D01*
X237538Y292889D01*
G01Y290889D02*
X238538D01*
G01X240430Y291181D02*
X240721Y290972D01*
X241055Y290889D01*
X241388Y290972D01*
X241680Y291222D01*
X241888Y291597D01*
X241971Y291972D01*
Y292431D01*
X241888Y292806D01*
X241680Y293139D01*
X241430Y293306D01*
X241138Y293389D01*
X240805Y293306D01*
X240555Y293139D01*
X240388Y292889D01*
X240305Y292556D01*
X240388Y292264D01*
X240596Y291972D01*
X240846Y291806D01*
X241138Y291764D01*
X241471Y291847D01*
X241721Y292056D01*
X241971Y292431D01*
G01X235031Y276980D02*
X275731D01*
G01X268729Y351340D02*
X264729D01*
Y343940D01*
G01X244017Y332667D02*
Y335167D01*
X245058D01*
X245392Y335042D01*
X245600Y334875D01*
X245683Y334542D01*
X245600Y334209D01*
X245350Y334000D01*
X245058Y333875D01*
X244017D01*
G01X245058D02*
X245683Y332667D01*
G01X248450D02*
Y335167D01*
X246908Y333375D01*
X248992D01*
G01X251050Y332667D02*
X251342Y332709D01*
X251675Y332834D01*
X251883Y333042D01*
X251967Y333334D01*
X251883Y333625D01*
X251633Y333875D01*
X251258Y334000D01*
X250842D01*
X250592Y334084D01*
X250383Y334292D01*
X250300Y334584D01*
X250425Y334875D01*
X250717Y335084D01*
X251050Y335167D01*
X251383Y335084D01*
X251675Y334875D01*
X251800Y334584D01*
X251717Y334292D01*
X251508Y334084D01*
X251258Y334000D01*
X250842D01*
X250467Y333875D01*
X250217Y333625D01*
X250133Y333334D01*
X250217Y333042D01*
X250425Y332834D01*
X250758Y332709D01*
X251050Y332667D01*
G01X254150Y335167D02*
X253817Y335084D01*
X253567Y334875D01*
X253400Y334625D01*
X253275Y334292D01*
X253233Y333917D01*
X253275Y333542D01*
X253400Y333209D01*
X253567Y332959D01*
X253817Y332750D01*
X254150Y332667D01*
X254483Y332750D01*
X254733Y332959D01*
X254900Y333209D01*
X255025Y333542D01*
X255067Y333917D01*
X255025Y334292D01*
X254900Y334625D01*
X254733Y334875D01*
X254483Y335084D01*
X254150Y335167D01*
G01X246400Y341700D02*
Y337700D01*
X253800D01*
G01X255646Y319340D02*
Y321840D01*
X256687D01*
X257021Y321715D01*
X257229Y321548D01*
X257312Y321215D01*
X257229Y320882D01*
X256979Y320673D01*
X256687Y320548D01*
X255646D01*
G01X256687D02*
X257312Y319340D01*
G01X260079D02*
Y321840D01*
X258537Y320048D01*
X260621D01*
G01X262596Y319340D02*
X262679Y319882D01*
X262804Y320340D01*
X262971Y320757D01*
X263179Y321215D01*
X263512Y321840D01*
X261846D01*
G01X265779Y319340D02*
X266071Y319382D01*
X266404Y319507D01*
X266612Y319715D01*
X266696Y320007D01*
X266612Y320298D01*
X266362Y320548D01*
X265987Y320673D01*
X265571D01*
X265321Y320757D01*
X265112Y320965D01*
X265029Y321257D01*
X265154Y321548D01*
X265446Y321757D01*
X265779Y321840D01*
X266112Y321757D01*
X266404Y321548D01*
X266529Y321257D01*
X266446Y320965D01*
X266237Y320757D01*
X265987Y320673D01*
X265571D01*
X265196Y320548D01*
X264946Y320298D01*
X264862Y320007D01*
X264946Y319715D01*
X265154Y319507D01*
X265487Y319382D01*
X265779Y319340D01*
G01X259529Y336140D02*
Y332140D01*
X266929D01*
G01X257396Y326132D02*
X257146Y326257D01*
X256854Y326340D01*
X256521D01*
X256146Y326215D01*
X255854Y326007D01*
X255646Y325757D01*
X255479Y325340D01*
X255437Y324965D01*
X255521Y324590D01*
X255646Y324340D01*
X255896Y324090D01*
X256187Y323923D01*
X256479Y323840D01*
X256771D01*
X257062Y323923D01*
X257312Y324048D01*
X257521Y324215D01*
G01X258662Y324340D02*
X258912Y324048D01*
X259246Y323882D01*
X259621Y323840D01*
X259954Y323882D01*
X260287Y324090D01*
X260496Y324340D01*
X260537Y324590D01*
X260454Y324882D01*
X260162Y325090D01*
X259871Y325173D01*
X259496D01*
G01X259871D02*
X260121Y325298D01*
X260329Y325507D01*
X260412Y325757D01*
X260329Y326007D01*
X260121Y326215D01*
X259746Y326340D01*
X259371Y326298D01*
X258996Y326132D01*
G01X262679Y326340D02*
X262346Y326257D01*
X262096Y326048D01*
X261929Y325798D01*
X261804Y325465D01*
X261762Y325090D01*
X261804Y324715D01*
X261929Y324382D01*
X262096Y324132D01*
X262346Y323923D01*
X262679Y323840D01*
X263012Y323923D01*
X263262Y324132D01*
X263429Y324382D01*
X263554Y324715D01*
X263596Y325090D01*
X263554Y325465D01*
X263429Y325798D01*
X263262Y326048D01*
X263012Y326257D01*
X262679Y326340D01*
G01X266279Y323840D02*
Y326340D01*
X264737Y324548D01*
X266821D01*
G01X245334Y348400D02*
X245292Y348067D01*
X245126Y347775D01*
X244876Y347525D01*
X244584Y347358D01*
X244251Y347275D01*
X243917D01*
X243584Y347358D01*
X243292Y347525D01*
X243042Y347775D01*
X242876Y348067D01*
X242834Y348400D01*
X242876Y348733D01*
X243042Y349025D01*
X243292Y349275D01*
X243584Y349442D01*
X243917Y349525D01*
X244251D01*
X244584Y349442D01*
X244876Y349275D01*
X245126Y349025D01*
X245292Y348733D01*
X245334Y348400D01*
G01X244667Y348733D02*
X245334Y349233D01*
G01Y351500D02*
X242834D01*
X243334Y351000D01*
G01X245334D02*
Y352000D01*
G01X242834Y354600D02*
X242917Y354267D01*
X243126Y354017D01*
X243376Y353850D01*
X243709Y353725D01*
X244084Y353683D01*
X244459Y353725D01*
X244792Y353850D01*
X245042Y354017D01*
X245251Y354267D01*
X245334Y354600D01*
X245251Y354933D01*
X245042Y355183D01*
X244792Y355350D01*
X244459Y355475D01*
X244084Y355517D01*
X243709Y355475D01*
X243376Y355350D01*
X243126Y355183D01*
X242917Y354933D01*
X242834Y354600D01*
G01X246800Y345700D02*
X260200D01*
G01D02*
Y357100D01*
G01D02*
X246800D01*
G01D02*
Y345700D01*
G01X263834Y355517D02*
X261334D01*
Y356558D01*
X261459Y356892D01*
X261626Y357100D01*
X261959Y357183D01*
X262292Y357100D01*
X262501Y356850D01*
X262626Y356558D01*
Y355517D01*
G01Y356558D02*
X263834Y357183D01*
G01Y359950D02*
X261334D01*
X263126Y358408D01*
Y360492D01*
G01X263834Y362550D02*
X263792Y362842D01*
X263667Y363175D01*
X263459Y363383D01*
X263167Y363467D01*
X262876Y363383D01*
X262626Y363133D01*
X262501Y362758D01*
Y362342D01*
X262417Y362092D01*
X262209Y361883D01*
X261917Y361800D01*
X261626Y361925D01*
X261417Y362217D01*
X261334Y362550D01*
X261417Y362883D01*
X261626Y363175D01*
X261917Y363300D01*
X262209Y363217D01*
X262417Y363008D01*
X262501Y362758D01*
Y362342D01*
X262626Y361967D01*
X262876Y361717D01*
X263167Y361633D01*
X263459Y361717D01*
X263667Y361925D01*
X263792Y362258D01*
X263834Y362550D01*
G01X261751Y364858D02*
X261501Y365108D01*
X261376Y365400D01*
X261334Y365733D01*
X261417Y366150D01*
X261626Y366442D01*
X261876Y366525D01*
X262126Y366483D01*
X262334Y366317D01*
X262751Y365483D01*
X263042Y365108D01*
X263459Y364858D01*
X263834Y364775D01*
Y366525D01*
G01X268186Y371783D02*
X265686D01*
Y372824D01*
X265811Y373158D01*
X265978Y373366D01*
X266311Y373449D01*
X266644Y373366D01*
X266853Y373116D01*
X266978Y372824D01*
Y371783D01*
G01Y372824D02*
X268186Y373449D01*
G01Y376216D02*
X265686D01*
X267478Y374674D01*
Y376758D01*
G01X268186Y378816D02*
X268144Y379108D01*
X268019Y379441D01*
X267811Y379649D01*
X267519Y379733D01*
X267228Y379649D01*
X266978Y379399D01*
X266853Y379024D01*
Y378608D01*
X266769Y378358D01*
X266561Y378149D01*
X266269Y378066D01*
X265978Y378191D01*
X265769Y378483D01*
X265686Y378816D01*
X265769Y379149D01*
X265978Y379441D01*
X266269Y379566D01*
X266561Y379483D01*
X266769Y379274D01*
X266853Y379024D01*
Y378608D01*
X266978Y378233D01*
X267228Y377983D01*
X267519Y377899D01*
X267811Y377983D01*
X268019Y378191D01*
X268144Y378524D01*
X268186Y378816D01*
G01X267686Y380999D02*
X267978Y381249D01*
X268144Y381583D01*
X268186Y381958D01*
X268144Y382291D01*
X267936Y382624D01*
X267686Y382833D01*
X267436Y382874D01*
X267144Y382791D01*
X266936Y382499D01*
X266853Y382208D01*
Y381833D01*
G01Y382208D02*
X266728Y382458D01*
X266519Y382666D01*
X266269Y382749D01*
X266019Y382666D01*
X265811Y382458D01*
X265686Y382083D01*
X265728Y381708D01*
X265894Y381333D01*
G01X264729Y351940D02*
X268729D01*
Y359340D01*
G01X236617Y385200D02*
Y387700D01*
X237658D01*
X237992Y387575D01*
X238200Y387408D01*
X238283Y387075D01*
X238200Y386742D01*
X237950Y386533D01*
X237658Y386408D01*
X236617D01*
G01X237658D02*
X238283Y385200D01*
G01X239758Y387283D02*
X240008Y387533D01*
X240300Y387658D01*
X240633Y387700D01*
X241050Y387617D01*
X241342Y387408D01*
X241425Y387158D01*
X241383Y386908D01*
X241217Y386700D01*
X240383Y386283D01*
X240008Y385992D01*
X239758Y385575D01*
X239675Y385200D01*
X241425D01*
G01X243567D02*
X243650Y385742D01*
X243775Y386200D01*
X243942Y386617D01*
X244150Y387075D01*
X244483Y387700D01*
X242817D01*
G01X246042Y385492D02*
X246333Y385283D01*
X246667Y385200D01*
X247000Y385283D01*
X247292Y385533D01*
X247500Y385908D01*
X247583Y386283D01*
Y386742D01*
X247500Y387117D01*
X247292Y387450D01*
X247042Y387617D01*
X246750Y387700D01*
X246417Y387617D01*
X246167Y387450D01*
X246000Y387200D01*
X245917Y386867D01*
X246000Y386575D01*
X246208Y386283D01*
X246458Y386117D01*
X246750Y386075D01*
X247083Y386158D01*
X247333Y386367D01*
X247583Y386742D01*
G01X236867Y389500D02*
Y392000D01*
X237908D01*
X238242Y391875D01*
X238450Y391708D01*
X238533Y391375D01*
X238450Y391042D01*
X238200Y390833D01*
X237908Y390708D01*
X236867D01*
G01X237908D02*
X238533Y389500D01*
G01X240717D02*
X240800Y390042D01*
X240925Y390500D01*
X241092Y390917D01*
X241300Y391375D01*
X241633Y392000D01*
X239967D01*
G01X243900D02*
X243567Y391917D01*
X243317Y391708D01*
X243150Y391458D01*
X243025Y391125D01*
X242983Y390750D01*
X243025Y390375D01*
X243150Y390042D01*
X243317Y389792D01*
X243567Y389583D01*
X243900Y389500D01*
X244233Y389583D01*
X244483Y389792D01*
X244650Y390042D01*
X244775Y390375D01*
X244817Y390750D01*
X244775Y391125D01*
X244650Y391458D01*
X244483Y391708D01*
X244233Y391917D01*
X243900Y392000D01*
G01X247000Y389500D02*
X247292Y389542D01*
X247625Y389667D01*
X247833Y389875D01*
X247917Y390167D01*
X247833Y390458D01*
X247583Y390708D01*
X247208Y390833D01*
X246792D01*
X246542Y390917D01*
X246333Y391125D01*
X246250Y391417D01*
X246375Y391708D01*
X246667Y391917D01*
X247000Y392000D01*
X247333Y391917D01*
X247625Y391708D01*
X247750Y391417D01*
X247667Y391125D01*
X247458Y390917D01*
X247208Y390833D01*
X246792D01*
X246417Y390708D01*
X246167Y390458D01*
X246083Y390167D01*
X246167Y389875D01*
X246375Y389667D01*
X246708Y389542D01*
X247000Y389500D01*
G01X236879Y393600D02*
Y396100D01*
X237920D01*
X238254Y395975D01*
X238462Y395808D01*
X238545Y395475D01*
X238462Y395142D01*
X238212Y394933D01*
X237920Y394808D01*
X236879D01*
G01X237920D02*
X238545Y393600D01*
G01X240729D02*
X240812Y394142D01*
X240937Y394600D01*
X241104Y395017D01*
X241312Y395475D01*
X241645Y396100D01*
X239979D01*
G01X243912D02*
X243579Y396017D01*
X243329Y395808D01*
X243162Y395558D01*
X243037Y395225D01*
X242995Y394850D01*
X243037Y394475D01*
X243162Y394142D01*
X243329Y393892D01*
X243579Y393683D01*
X243912Y393600D01*
X244245Y393683D01*
X244495Y393892D01*
X244662Y394142D01*
X244787Y394475D01*
X244829Y394850D01*
X244787Y395225D01*
X244662Y395558D01*
X244495Y395808D01*
X244245Y396017D01*
X243912Y396100D01*
G01X246929Y393600D02*
X247012Y394142D01*
X247137Y394600D01*
X247304Y395017D01*
X247512Y395475D01*
X247845Y396100D01*
X246179D01*
G01X232916Y407391D02*
X232791Y407141D01*
X232708Y406849D01*
Y406516D01*
X232833Y406141D01*
X233041Y405849D01*
X233291Y405641D01*
X233708Y405474D01*
X234083Y405432D01*
X234458Y405516D01*
X234708Y405641D01*
X234958Y405891D01*
X235125Y406182D01*
X235208Y406474D01*
Y406766D01*
X235125Y407057D01*
X235000Y407307D01*
X234833Y407516D01*
G01X235208Y409574D02*
X232708D01*
X233208Y409074D01*
G01X235208D02*
Y410074D01*
G01X234916Y411966D02*
X235125Y412257D01*
X235208Y412591D01*
X235125Y412924D01*
X234875Y413216D01*
X234500Y413424D01*
X234125Y413507D01*
X233666D01*
X233291Y413424D01*
X232958Y413216D01*
X232791Y412966D01*
X232708Y412674D01*
X232791Y412341D01*
X232958Y412091D01*
X233208Y411924D01*
X233541Y411841D01*
X233833Y411924D01*
X234125Y412132D01*
X234291Y412382D01*
X234333Y412674D01*
X234250Y413007D01*
X234041Y413257D01*
X233666Y413507D01*
G01X234708Y414857D02*
X235000Y415107D01*
X235166Y415441D01*
X235208Y415816D01*
X235166Y416149D01*
X234958Y416482D01*
X234708Y416691D01*
X234458Y416732D01*
X234166Y416649D01*
X233958Y416357D01*
X233875Y416066D01*
Y415691D01*
G01Y416066D02*
X233750Y416316D01*
X233541Y416524D01*
X233291Y416607D01*
X233041Y416524D01*
X232833Y416316D01*
X232708Y415941D01*
X232750Y415566D01*
X232916Y415191D01*
G01X235100Y433150D02*
X235933D01*
Y432400D01*
X235683Y432150D01*
X235392Y431983D01*
X234975Y431900D01*
X234558Y431983D01*
X234267Y432150D01*
X234017Y432400D01*
X233850Y432692D01*
X233767Y433025D01*
Y433317D01*
X233850Y433567D01*
X234017Y433858D01*
X234267Y434108D01*
X234517Y434275D01*
X234850Y434400D01*
X235142D01*
X235475Y434317D01*
X235725Y434150D01*
G01X237950Y431900D02*
Y434400D01*
X237450Y433900D01*
G01Y431900D02*
X238450D01*
G01X239800Y502400D02*
Y435600D01*
G01X250483Y420100D02*
Y418308D01*
X250650Y417933D01*
X250983Y417683D01*
X251400Y417600D01*
X251817Y417683D01*
X252150Y417933D01*
X252317Y418308D01*
Y420100D01*
G01X253708Y419683D02*
X253958Y419933D01*
X254250Y420058D01*
X254583Y420100D01*
X255000Y420017D01*
X255292Y419808D01*
X255375Y419558D01*
X255333Y419308D01*
X255167Y419100D01*
X254333Y418683D01*
X253958Y418392D01*
X253708Y417975D01*
X253625Y417600D01*
X255375D01*
G01X257600D02*
X257892Y417642D01*
X258225Y417767D01*
X258433Y417975D01*
X258517Y418267D01*
X258433Y418558D01*
X258183Y418808D01*
X257808Y418933D01*
X257392D01*
X257142Y419017D01*
X256933Y419225D01*
X256850Y419517D01*
X256975Y419808D01*
X257267Y420017D01*
X257600Y420100D01*
X257933Y420017D01*
X258225Y419808D01*
X258350Y419517D01*
X258267Y419225D01*
X258058Y419017D01*
X257808Y418933D01*
X257392D01*
X257017Y418808D01*
X256767Y418558D01*
X256683Y418267D01*
X256767Y417975D01*
X256975Y417767D01*
X257308Y417642D01*
X257600Y417600D01*
G01X260600Y436300D02*
X247200D01*
G01D02*
Y424900D01*
G01D02*
X260600D01*
G01D02*
Y436300D01*
G01X264467Y437600D02*
Y440100D01*
X265508D01*
X265842Y439975D01*
X266050Y439808D01*
X266133Y439475D01*
X266050Y439142D01*
X265800Y438933D01*
X265508Y438808D01*
X264467D01*
G01X265508D02*
X266133Y437600D01*
G01X267483Y438100D02*
X267733Y437808D01*
X268067Y437642D01*
X268442Y437600D01*
X268775Y437642D01*
X269108Y437850D01*
X269317Y438100D01*
X269358Y438350D01*
X269275Y438642D01*
X268983Y438850D01*
X268692Y438933D01*
X268317D01*
G01X268692D02*
X268942Y439058D01*
X269150Y439267D01*
X269233Y439517D01*
X269150Y439767D01*
X268942Y439975D01*
X268567Y440100D01*
X268192Y440058D01*
X267817Y439892D01*
G01X270708Y439683D02*
X270958Y439933D01*
X271250Y440058D01*
X271583Y440100D01*
X272000Y440017D01*
X272292Y439808D01*
X272375Y439558D01*
X272333Y439308D01*
X272167Y439100D01*
X271333Y438683D01*
X270958Y438392D01*
X270708Y437975D01*
X270625Y437600D01*
X272375D01*
G01X258600Y436600D02*
Y440600D01*
X251200D01*
G01X252667Y413300D02*
Y415800D01*
X253708D01*
X254042Y415675D01*
X254250Y415508D01*
X254333Y415175D01*
X254250Y414842D01*
X254000Y414633D01*
X253708Y414508D01*
X252667D01*
G01X253708D02*
X254333Y413300D01*
G01X255683Y413800D02*
X255933Y413508D01*
X256267Y413342D01*
X256642Y413300D01*
X256975Y413342D01*
X257308Y413550D01*
X257517Y413800D01*
X257558Y414050D01*
X257475Y414342D01*
X257183Y414550D01*
X256892Y414633D01*
X256517D01*
G01X256892D02*
X257142Y414758D01*
X257350Y414967D01*
X257433Y415217D01*
X257350Y415467D01*
X257142Y415675D01*
X256767Y415800D01*
X256392Y415758D01*
X256017Y415592D01*
G01X258992Y413592D02*
X259283Y413383D01*
X259617Y413300D01*
X259950Y413383D01*
X260242Y413633D01*
X260450Y414008D01*
X260533Y414383D01*
Y414842D01*
X260450Y415217D01*
X260242Y415550D01*
X259992Y415717D01*
X259700Y415800D01*
X259367Y415717D01*
X259117Y415550D01*
X258950Y415300D01*
X258867Y414967D01*
X258950Y414675D01*
X259158Y414383D01*
X259408Y414217D01*
X259700Y414175D01*
X260033Y414258D01*
X260283Y414467D01*
X260533Y414842D01*
G01X261300Y420500D02*
Y424500D01*
X253900D01*
G01X245400Y437917D02*
X242900D01*
Y438958D01*
X243025Y439292D01*
X243192Y439500D01*
X243525Y439583D01*
X243858Y439500D01*
X244067Y439250D01*
X244192Y438958D01*
Y437917D01*
G01Y438958D02*
X245400Y439583D01*
G01X244900Y440933D02*
X245192Y441183D01*
X245358Y441517D01*
X245400Y441892D01*
X245358Y442225D01*
X245150Y442558D01*
X244900Y442767D01*
X244650Y442808D01*
X244358Y442725D01*
X244150Y442433D01*
X244067Y442142D01*
Y441767D01*
G01Y442142D02*
X243942Y442392D01*
X243733Y442600D01*
X243483Y442683D01*
X243233Y442600D01*
X243025Y442392D01*
X242900Y442017D01*
X242942Y441642D01*
X243108Y441267D01*
G01X245400Y444950D02*
X242900D01*
X243400Y444450D01*
G01X245400D02*
Y445450D01*
G01X244900Y447133D02*
X245192Y447383D01*
X245358Y447717D01*
X245400Y448092D01*
X245358Y448425D01*
X245150Y448758D01*
X244900Y448967D01*
X244650Y449008D01*
X244358Y448925D01*
X244150Y448633D01*
X244067Y448342D01*
Y447967D01*
G01Y448342D02*
X243942Y448592D01*
X243733Y448800D01*
X243483Y448883D01*
X243233Y448800D01*
X243025Y448592D01*
X242900Y448217D01*
X242942Y447842D01*
X243108Y447467D01*
G01X246900Y436300D02*
X242900D01*
Y428900D01*
G01X264900Y435800D02*
X260900D01*
Y428400D01*
G01X255400Y441300D02*
Y445300D01*
X248000D01*
G01X255500D02*
Y441300D01*
X262900D01*
G01X263400Y483000D02*
Y469600D01*
G01D02*
X274800D01*
G01X263495Y461378D02*
Y463878D01*
X264536D01*
X264870Y463753D01*
X265078Y463586D01*
X265161Y463253D01*
X265078Y462920D01*
X264828Y462711D01*
X264536Y462586D01*
X263495D01*
G01X264536D02*
X265161Y461378D01*
G01X266511Y461878D02*
X266761Y461586D01*
X267095Y461420D01*
X267470Y461378D01*
X267803Y461420D01*
X268136Y461628D01*
X268345Y461878D01*
X268386Y462128D01*
X268303Y462420D01*
X268011Y462628D01*
X267720Y462711D01*
X267345D01*
G01X267720D02*
X267970Y462836D01*
X268178Y463045D01*
X268261Y463295D01*
X268178Y463545D01*
X267970Y463753D01*
X267595Y463878D01*
X267220Y463836D01*
X266845Y463670D01*
G01X270528Y463878D02*
X270195Y463795D01*
X269945Y463586D01*
X269778Y463336D01*
X269653Y463003D01*
X269611Y462628D01*
X269653Y462253D01*
X269778Y461920D01*
X269945Y461670D01*
X270195Y461461D01*
X270528Y461378D01*
X270861Y461461D01*
X271111Y461670D01*
X271278Y461920D01*
X271403Y462253D01*
X271445Y462628D01*
X271403Y463003D01*
X271278Y463336D01*
X271111Y463586D01*
X270861Y463795D01*
X270528Y463878D01*
G01X273545Y461378D02*
X273628Y461920D01*
X273753Y462378D01*
X273920Y462795D01*
X274128Y463253D01*
X274461Y463878D01*
X272795D01*
G01X254834Y470116D02*
X252334D01*
Y471157D01*
X252459Y471491D01*
X252626Y471699D01*
X252959Y471782D01*
X253292Y471699D01*
X253501Y471449D01*
X253626Y471157D01*
Y470116D01*
G01Y471157D02*
X254834Y471782D01*
G01X252751Y473257D02*
X252501Y473507D01*
X252376Y473799D01*
X252334Y474132D01*
X252417Y474549D01*
X252626Y474841D01*
X252876Y474924D01*
X253126Y474882D01*
X253334Y474716D01*
X253751Y473882D01*
X254042Y473507D01*
X254459Y473257D01*
X254834Y473174D01*
Y474924D01*
G01X253792Y476357D02*
X253501Y476649D01*
X253334Y476899D01*
X253251Y477232D01*
X253334Y477524D01*
X253501Y477732D01*
X253751Y477899D01*
X254042Y477941D01*
X254292Y477899D01*
X254542Y477732D01*
X254751Y477482D01*
X254834Y477191D01*
X254751Y476857D01*
X254501Y476566D01*
X254126Y476399D01*
X253709Y476357D01*
X253167Y476441D01*
X252876Y476566D01*
X252584Y476774D01*
X252376Y477066D01*
X252334Y477357D01*
X252417Y477649D01*
X252626Y477857D01*
G01X258600Y471100D02*
X262600D01*
Y478500D01*
G01X260417Y446400D02*
Y448900D01*
X261458D01*
X261792Y448775D01*
X262000Y448608D01*
X262083Y448275D01*
X262000Y447942D01*
X261750Y447733D01*
X261458Y447608D01*
X260417D01*
G01X261458D02*
X262083Y446400D01*
G01X264850D02*
Y448900D01*
X263308Y447108D01*
X265392D01*
G01X266533Y446900D02*
X266783Y446608D01*
X267117Y446442D01*
X267492Y446400D01*
X267825Y446442D01*
X268158Y446650D01*
X268367Y446900D01*
X268408Y447150D01*
X268325Y447442D01*
X268033Y447650D01*
X267742Y447733D01*
X267367D01*
G01X267742D02*
X267992Y447858D01*
X268200Y448067D01*
X268283Y448317D01*
X268200Y448567D01*
X267992Y448775D01*
X267617Y448900D01*
X267242Y448858D01*
X266867Y448692D01*
G01X269842Y446692D02*
X270133Y446483D01*
X270467Y446400D01*
X270800Y446483D01*
X271092Y446733D01*
X271300Y447108D01*
X271383Y447483D01*
Y447942D01*
X271300Y448317D01*
X271092Y448650D01*
X270842Y448817D01*
X270550Y448900D01*
X270217Y448817D01*
X269967Y448650D01*
X269800Y448400D01*
X269717Y448067D01*
X269800Y447775D01*
X270008Y447483D01*
X270258Y447317D01*
X270550Y447275D01*
X270883Y447358D01*
X271133Y447567D01*
X271383Y447942D01*
G01X258700Y454655D02*
X256200D01*
Y455696D01*
X256325Y456030D01*
X256492Y456238D01*
X256825Y456321D01*
X257158Y456238D01*
X257367Y455988D01*
X257492Y455696D01*
Y454655D01*
G01Y455696D02*
X258700Y456321D01*
G01Y459088D02*
X256200D01*
X257992Y457546D01*
Y459630D01*
G01X258700Y461688D02*
X258658Y461980D01*
X258533Y462313D01*
X258325Y462521D01*
X258033Y462605D01*
X257742Y462521D01*
X257492Y462271D01*
X257367Y461896D01*
Y461480D01*
X257283Y461230D01*
X257075Y461021D01*
X256783Y460938D01*
X256492Y461063D01*
X256283Y461355D01*
X256200Y461688D01*
X256283Y462021D01*
X256492Y462313D01*
X256783Y462438D01*
X257075Y462355D01*
X257283Y462146D01*
X257367Y461896D01*
Y461480D01*
X257492Y461105D01*
X257742Y460855D01*
X258033Y460771D01*
X258325Y460855D01*
X258533Y461063D01*
X258658Y461396D01*
X258700Y461688D01*
G01Y464788D02*
X258658Y465080D01*
X258533Y465413D01*
X258325Y465621D01*
X258033Y465705D01*
X257742Y465621D01*
X257492Y465371D01*
X257367Y464996D01*
Y464580D01*
X257283Y464330D01*
X257075Y464121D01*
X256783Y464038D01*
X256492Y464163D01*
X256283Y464455D01*
X256200Y464788D01*
X256283Y465121D01*
X256492Y465413D01*
X256783Y465538D01*
X257075Y465455D01*
X257283Y465246D01*
X257367Y464996D01*
Y464580D01*
X257492Y464205D01*
X257742Y463955D01*
X258033Y463871D01*
X258325Y463955D01*
X258533Y464163D01*
X258658Y464496D01*
X258700Y464788D01*
G01X259500Y452938D02*
X255500D01*
Y445538D01*
G01X254600Y454617D02*
X252100D01*
Y455658D01*
X252225Y455992D01*
X252392Y456200D01*
X252725Y456283D01*
X253058Y456200D01*
X253267Y455950D01*
X253392Y455658D01*
Y454617D01*
G01Y455658D02*
X254600Y456283D01*
G01Y459050D02*
X252100D01*
X253892Y457508D01*
Y459592D01*
G01X254600Y461650D02*
X254558Y461942D01*
X254433Y462275D01*
X254225Y462483D01*
X253933Y462567D01*
X253642Y462483D01*
X253392Y462233D01*
X253267Y461858D01*
Y461442D01*
X253183Y461192D01*
X252975Y460983D01*
X252683Y460900D01*
X252392Y461025D01*
X252183Y461317D01*
X252100Y461650D01*
X252183Y461983D01*
X252392Y462275D01*
X252683Y462400D01*
X252975Y462317D01*
X253183Y462108D01*
X253267Y461858D01*
Y461442D01*
X253392Y461067D01*
X253642Y460817D01*
X253933Y460733D01*
X254225Y460817D01*
X254433Y461025D01*
X254558Y461358D01*
X254600Y461650D01*
G01Y464667D02*
X254058Y464750D01*
X253600Y464875D01*
X253183Y465042D01*
X252725Y465250D01*
X252100Y465583D01*
Y463917D01*
G01X255400Y452900D02*
X251400D01*
Y445500D01*
G01X244417Y497500D02*
Y500000D01*
X245417D01*
X245750Y499875D01*
X246000Y499583D01*
X246083Y499250D01*
X246000Y498917D01*
X245792Y498667D01*
X245417Y498542D01*
X244417D01*
G01X247850Y500000D02*
X248850D01*
G01X248350D02*
Y497500D01*
G01X247850D02*
X248850D01*
G01X250492D02*
Y500000D01*
X252408Y497500D01*
Y500000D01*
G01X254550Y497500D02*
Y500000D01*
X254050Y499500D01*
G01Y497500D02*
X255050D01*
G01X245702Y510796D02*
Y508296D01*
X247368D01*
G01X250135D02*
Y510796D01*
X248593Y509004D01*
X250677D01*
G01X259334Y480309D02*
X261126D01*
X261501Y480476D01*
X261751Y480809D01*
X261834Y481226D01*
X261751Y481643D01*
X261501Y481976D01*
X261126Y482143D01*
X259334D01*
G01X259751Y483534D02*
X259501Y483784D01*
X259376Y484076D01*
X259334Y484409D01*
X259417Y484826D01*
X259626Y485118D01*
X259876Y485201D01*
X260126Y485159D01*
X260334Y484993D01*
X260751Y484159D01*
X261042Y483784D01*
X261459Y483534D01*
X261834Y483451D01*
Y485201D01*
G01X261334Y486509D02*
X261626Y486759D01*
X261792Y487093D01*
X261834Y487468D01*
X261792Y487801D01*
X261584Y488134D01*
X261334Y488343D01*
X261084Y488384D01*
X260792Y488301D01*
X260584Y488009D01*
X260501Y487718D01*
Y487343D01*
G01Y487718D02*
X260376Y487968D01*
X260167Y488176D01*
X259917Y488259D01*
X259667Y488176D01*
X259459Y487968D01*
X259334Y487593D01*
X259376Y487218D01*
X259542Y486843D01*
G01X274800Y483000D02*
X263400D01*
G01X260676Y489268D02*
Y491768D01*
X261717D01*
X262051Y491643D01*
X262259Y491476D01*
X262342Y491143D01*
X262259Y490810D01*
X262009Y490601D01*
X261717Y490476D01*
X260676D01*
G01X261717D02*
X262342Y489268D01*
G01X263692Y489768D02*
X263942Y489476D01*
X264276Y489310D01*
X264651Y489268D01*
X264984Y489310D01*
X265317Y489518D01*
X265526Y489768D01*
X265567Y490018D01*
X265484Y490310D01*
X265192Y490518D01*
X264901Y490601D01*
X264526D01*
G01X264901D02*
X265151Y490726D01*
X265359Y490935D01*
X265442Y491185D01*
X265359Y491435D01*
X265151Y491643D01*
X264776Y491768D01*
X264401Y491726D01*
X264026Y491560D01*
G01X267709Y491768D02*
X267376Y491685D01*
X267126Y491476D01*
X266959Y491226D01*
X266834Y490893D01*
X266792Y490518D01*
X266834Y490143D01*
X266959Y489810D01*
X267126Y489560D01*
X267376Y489351D01*
X267709Y489268D01*
X268042Y489351D01*
X268292Y489560D01*
X268459Y489810D01*
X268584Y490143D01*
X268626Y490518D01*
X268584Y490893D01*
X268459Y491226D01*
X268292Y491476D01*
X268042Y491685D01*
X267709Y491768D01*
G01X270101Y489560D02*
X270392Y489351D01*
X270726Y489268D01*
X271059Y489351D01*
X271351Y489601D01*
X271559Y489976D01*
X271642Y490351D01*
Y490810D01*
X271559Y491185D01*
X271351Y491518D01*
X271101Y491685D01*
X270809Y491768D01*
X270476Y491685D01*
X270226Y491518D01*
X270059Y491268D01*
X269976Y490935D01*
X270059Y490643D01*
X270267Y490351D01*
X270517Y490185D01*
X270809Y490143D01*
X271142Y490226D01*
X271392Y490435D01*
X271642Y490810D01*
G01X262333Y510415D02*
X262208Y510165D01*
X262125Y509873D01*
Y509540D01*
X262250Y509165D01*
X262458Y508873D01*
X262708Y508665D01*
X263125Y508498D01*
X263500Y508456D01*
X263875Y508540D01*
X264125Y508665D01*
X264375Y508915D01*
X264542Y509206D01*
X264625Y509498D01*
Y509790D01*
X264542Y510081D01*
X264417Y510331D01*
X264250Y510540D01*
G01X262542Y511806D02*
X262292Y512056D01*
X262167Y512348D01*
X262125Y512681D01*
X262208Y513098D01*
X262417Y513390D01*
X262667Y513473D01*
X262917Y513431D01*
X263125Y513265D01*
X263542Y512431D01*
X263833Y512056D01*
X264250Y511806D01*
X264625Y511723D01*
Y513473D01*
G01Y515698D02*
X264583Y515990D01*
X264458Y516323D01*
X264250Y516531D01*
X263958Y516615D01*
X263667Y516531D01*
X263417Y516281D01*
X263292Y515906D01*
Y515490D01*
X263208Y515240D01*
X263000Y515031D01*
X262708Y514948D01*
X262417Y515073D01*
X262208Y515365D01*
X262125Y515698D01*
X262208Y516031D01*
X262417Y516323D01*
X262708Y516448D01*
X263000Y516365D01*
X263208Y516156D01*
X263292Y515906D01*
Y515490D01*
X263417Y515115D01*
X263667Y514865D01*
X263958Y514781D01*
X264250Y514865D01*
X264458Y515073D01*
X264583Y515406D01*
X264625Y515698D01*
G01X262125Y518798D02*
X262208Y518465D01*
X262417Y518215D01*
X262667Y518048D01*
X263000Y517923D01*
X263375Y517881D01*
X263750Y517923D01*
X264083Y518048D01*
X264333Y518215D01*
X264542Y518465D01*
X264625Y518798D01*
X264542Y519131D01*
X264333Y519381D01*
X264083Y519548D01*
X263750Y519673D01*
X263375Y519715D01*
X263000Y519673D01*
X262667Y519548D01*
X262417Y519381D01*
X262208Y519131D01*
X262125Y518798D01*
G01X266000Y504500D02*
Y493100D01*
G01X279400Y504500D02*
X266000D01*
G01Y493100D02*
X279400D01*
G01X266000Y505300D02*
X279400D01*
G01X266000Y516700D02*
Y505300D01*
G01X247500Y533017D02*
X245000D01*
Y534058D01*
X245125Y534392D01*
X245292Y534600D01*
X245625Y534683D01*
X245958Y534600D01*
X246167Y534350D01*
X246292Y534058D01*
Y533017D01*
G01Y534058D02*
X247500Y534683D01*
G01X247000Y536033D02*
X247292Y536283D01*
X247458Y536617D01*
X247500Y536992D01*
X247458Y537325D01*
X247250Y537658D01*
X247000Y537867D01*
X246750Y537908D01*
X246458Y537825D01*
X246250Y537533D01*
X246167Y537242D01*
Y536867D01*
G01Y537242D02*
X246042Y537492D01*
X245833Y537700D01*
X245583Y537783D01*
X245333Y537700D01*
X245125Y537492D01*
X245000Y537117D01*
X245042Y536742D01*
X245208Y536367D01*
G01X247500Y540050D02*
X245000D01*
X245500Y539550D01*
G01X247500D02*
Y540550D01*
G01X247125Y542233D02*
X247333Y542483D01*
X247458Y542775D01*
X247500Y543150D01*
X247417Y543525D01*
X247250Y543817D01*
X246958Y544025D01*
X246625Y544067D01*
X246292Y543983D01*
X246083Y543775D01*
X245917Y543483D01*
X245875Y543192D01*
X245917Y542900D01*
X246083Y542525D01*
X245000Y542650D01*
Y543775D01*
G01X240500Y515800D02*
X244500D01*
Y523200D01*
G01Y531200D02*
X240500D01*
Y523800D01*
G01X255500D02*
X259500D01*
Y531200D01*
G01X255500D02*
X251500D01*
Y523800D01*
G01X258403Y533550D02*
X255903D01*
Y534591D01*
X256028Y534925D01*
X256195Y535133D01*
X256528Y535216D01*
X256861Y535133D01*
X257070Y534883D01*
X257195Y534591D01*
Y533550D01*
G01Y534591D02*
X258403Y535216D01*
G01X258028Y536566D02*
X258236Y536816D01*
X258361Y537108D01*
X258403Y537483D01*
X258320Y537858D01*
X258153Y538150D01*
X257861Y538358D01*
X257528Y538400D01*
X257195Y538316D01*
X256986Y538108D01*
X256820Y537816D01*
X256778Y537525D01*
X256820Y537233D01*
X256986Y536858D01*
X255903Y536983D01*
Y538108D01*
G01X258403Y540500D02*
X257861Y540583D01*
X257403Y540708D01*
X256986Y540875D01*
X256528Y541083D01*
X255903Y541416D01*
Y539750D01*
G01X257361Y542891D02*
X257070Y543183D01*
X256903Y543433D01*
X256820Y543766D01*
X256903Y544058D01*
X257070Y544266D01*
X257320Y544433D01*
X257611Y544475D01*
X257861Y544433D01*
X258111Y544266D01*
X258320Y544016D01*
X258403Y543725D01*
X258320Y543391D01*
X258070Y543100D01*
X257695Y542933D01*
X257278Y542891D01*
X256736Y542975D01*
X256445Y543100D01*
X256153Y543308D01*
X255945Y543600D01*
X255903Y543891D01*
X255986Y544183D01*
X256195Y544391D01*
G01X257361Y545991D02*
X257070Y546283D01*
X256903Y546533D01*
X256820Y546866D01*
X256903Y547158D01*
X257070Y547366D01*
X257320Y547533D01*
X257611Y547575D01*
X257861Y547533D01*
X258111Y547366D01*
X258320Y547116D01*
X258403Y546825D01*
X258320Y546491D01*
X258070Y546200D01*
X257695Y546033D01*
X257278Y545991D01*
X256736Y546075D01*
X256445Y546200D01*
X256153Y546408D01*
X255945Y546700D01*
X255903Y546991D01*
X255986Y547283D01*
X256195Y547491D01*
G01X251500Y515800D02*
X255500D01*
Y523200D01*
G01X262403Y533550D02*
X259903D01*
Y534591D01*
X260028Y534925D01*
X260195Y535133D01*
X260528Y535216D01*
X260861Y535133D01*
X261070Y534883D01*
X261195Y534591D01*
Y533550D01*
G01Y534591D02*
X262403Y535216D01*
G01X262028Y536566D02*
X262236Y536816D01*
X262361Y537108D01*
X262403Y537483D01*
X262320Y537858D01*
X262153Y538150D01*
X261861Y538358D01*
X261528Y538400D01*
X261195Y538316D01*
X260986Y538108D01*
X260820Y537816D01*
X260778Y537525D01*
X260820Y537233D01*
X260986Y536858D01*
X259903Y536983D01*
Y538108D01*
G01X262403Y540500D02*
X261861Y540583D01*
X261403Y540708D01*
X260986Y540875D01*
X260528Y541083D01*
X259903Y541416D01*
Y539750D01*
G01X261361Y542891D02*
X261070Y543183D01*
X260903Y543433D01*
X260820Y543766D01*
X260903Y544058D01*
X261070Y544266D01*
X261320Y544433D01*
X261611Y544475D01*
X261861Y544433D01*
X262111Y544266D01*
X262320Y544016D01*
X262403Y543725D01*
X262320Y543391D01*
X262070Y543100D01*
X261695Y542933D01*
X261278Y542891D01*
X260736Y542975D01*
X260445Y543100D01*
X260153Y543308D01*
X259945Y543600D01*
X259903Y543891D01*
X259986Y544183D01*
X260195Y544391D01*
G01X262403Y547283D02*
X259903D01*
X261695Y545741D01*
Y547825D01*
G01X260000Y523200D02*
X256000D01*
Y515800D01*
G01X237826Y533317D02*
X235326D01*
Y534358D01*
X235451Y534692D01*
X235618Y534900D01*
X235951Y534983D01*
X236284Y534900D01*
X236493Y534650D01*
X236618Y534358D01*
Y533317D01*
G01Y534358D02*
X237826Y534983D01*
G01X237326Y536333D02*
X237618Y536583D01*
X237784Y536917D01*
X237826Y537292D01*
X237784Y537625D01*
X237576Y537958D01*
X237326Y538167D01*
X237076Y538208D01*
X236784Y538125D01*
X236576Y537833D01*
X236493Y537542D01*
Y537167D01*
G01Y537542D02*
X236368Y537792D01*
X236159Y538000D01*
X235909Y538083D01*
X235659Y538000D01*
X235451Y537792D01*
X235326Y537417D01*
X235368Y537042D01*
X235534Y536667D01*
G01X235326Y540350D02*
X235409Y540017D01*
X235618Y539767D01*
X235868Y539600D01*
X236201Y539475D01*
X236576Y539433D01*
X236951Y539475D01*
X237284Y539600D01*
X237534Y539767D01*
X237743Y540017D01*
X237826Y540350D01*
X237743Y540683D01*
X237534Y540933D01*
X237284Y541100D01*
X236951Y541225D01*
X236576Y541267D01*
X236201Y541225D01*
X235868Y541100D01*
X235618Y540933D01*
X235409Y540683D01*
X235326Y540350D01*
G01X237534Y542742D02*
X237743Y543033D01*
X237826Y543367D01*
X237743Y543700D01*
X237493Y543992D01*
X237118Y544200D01*
X236743Y544283D01*
X236284D01*
X235909Y544200D01*
X235576Y543992D01*
X235409Y543742D01*
X235326Y543450D01*
X235409Y543117D01*
X235576Y542867D01*
X235826Y542700D01*
X236159Y542617D01*
X236451Y542700D01*
X236743Y542908D01*
X236909Y543158D01*
X236951Y543450D01*
X236868Y543783D01*
X236659Y544033D01*
X236284Y544283D01*
G01X237826Y546550D02*
X237784Y546842D01*
X237659Y547175D01*
X237451Y547383D01*
X237159Y547467D01*
X236868Y547383D01*
X236618Y547133D01*
X236493Y546758D01*
Y546342D01*
X236409Y546092D01*
X236201Y545883D01*
X235909Y545800D01*
X235618Y545925D01*
X235409Y546217D01*
X235326Y546550D01*
X235409Y546883D01*
X235618Y547175D01*
X235909Y547300D01*
X236201Y547217D01*
X236409Y547008D01*
X236493Y546758D01*
Y546342D01*
X236618Y545967D01*
X236868Y545717D01*
X237159Y545633D01*
X237451Y545717D01*
X237659Y545925D01*
X237784Y546258D01*
X237826Y546550D01*
G01X241826Y533317D02*
X239326D01*
Y534358D01*
X239451Y534692D01*
X239618Y534900D01*
X239951Y534983D01*
X240284Y534900D01*
X240493Y534650D01*
X240618Y534358D01*
Y533317D01*
G01Y534358D02*
X241826Y534983D01*
G01X241451Y536333D02*
X241659Y536583D01*
X241784Y536875D01*
X241826Y537250D01*
X241743Y537625D01*
X241576Y537917D01*
X241284Y538125D01*
X240951Y538167D01*
X240618Y538083D01*
X240409Y537875D01*
X240243Y537583D01*
X240201Y537292D01*
X240243Y537000D01*
X240409Y536625D01*
X239326Y536750D01*
Y537875D01*
G01X241826Y540267D02*
X241284Y540350D01*
X240826Y540475D01*
X240409Y540642D01*
X239951Y540850D01*
X239326Y541183D01*
Y539517D01*
G01X240784Y542658D02*
X240493Y542950D01*
X240326Y543200D01*
X240243Y543533D01*
X240326Y543825D01*
X240493Y544033D01*
X240743Y544200D01*
X241034Y544242D01*
X241284Y544200D01*
X241534Y544033D01*
X241743Y543783D01*
X241826Y543492D01*
X241743Y543158D01*
X241493Y542867D01*
X241118Y542700D01*
X240701Y542658D01*
X240159Y542742D01*
X239868Y542867D01*
X239576Y543075D01*
X239368Y543367D01*
X239326Y543658D01*
X239409Y543950D01*
X239618Y544158D01*
G01X241534Y545842D02*
X241743Y546133D01*
X241826Y546467D01*
X241743Y546800D01*
X241493Y547092D01*
X241118Y547300D01*
X240743Y547383D01*
X240284D01*
X239909Y547300D01*
X239576Y547092D01*
X239409Y546842D01*
X239326Y546550D01*
X239409Y546217D01*
X239576Y545967D01*
X239826Y545800D01*
X240159Y545717D01*
X240451Y545800D01*
X240743Y546008D01*
X240909Y546258D01*
X240951Y546550D01*
X240868Y546883D01*
X240659Y547133D01*
X240284Y547383D01*
G01X252111Y535300D02*
X251986Y535050D01*
X251903Y534758D01*
Y534425D01*
X252028Y534050D01*
X252236Y533758D01*
X252486Y533550D01*
X252903Y533383D01*
X253278Y533341D01*
X253653Y533425D01*
X253903Y533550D01*
X254153Y533800D01*
X254320Y534091D01*
X254403Y534383D01*
Y534675D01*
X254320Y534966D01*
X254195Y535216D01*
X254028Y535425D01*
G01X254403Y537483D02*
X254361Y537775D01*
X254236Y538108D01*
X254028Y538316D01*
X253736Y538400D01*
X253445Y538316D01*
X253195Y538066D01*
X253070Y537691D01*
Y537275D01*
X252986Y537025D01*
X252778Y536816D01*
X252486Y536733D01*
X252195Y536858D01*
X251986Y537150D01*
X251903Y537483D01*
X251986Y537816D01*
X252195Y538108D01*
X252486Y538233D01*
X252778Y538150D01*
X252986Y537941D01*
X253070Y537691D01*
Y537275D01*
X253195Y536900D01*
X253445Y536650D01*
X253736Y536566D01*
X254028Y536650D01*
X254236Y536858D01*
X254361Y537191D01*
X254403Y537483D01*
G01X251903Y540583D02*
X251986Y540250D01*
X252195Y540000D01*
X252445Y539833D01*
X252778Y539708D01*
X253153Y539666D01*
X253528Y539708D01*
X253861Y539833D01*
X254111Y540000D01*
X254320Y540250D01*
X254403Y540583D01*
X254320Y540916D01*
X254111Y541166D01*
X253861Y541333D01*
X253528Y541458D01*
X253153Y541500D01*
X252778Y541458D01*
X252445Y541333D01*
X252195Y541166D01*
X251986Y540916D01*
X251903Y540583D01*
G01X254403Y543683D02*
X254361Y543975D01*
X254236Y544308D01*
X254028Y544516D01*
X253736Y544600D01*
X253445Y544516D01*
X253195Y544266D01*
X253070Y543891D01*
Y543475D01*
X252986Y543225D01*
X252778Y543016D01*
X252486Y542933D01*
X252195Y543058D01*
X251986Y543350D01*
X251903Y543683D01*
X251986Y544016D01*
X252195Y544308D01*
X252486Y544433D01*
X252778Y544350D01*
X252986Y544141D01*
X253070Y543891D01*
Y543475D01*
X253195Y543100D01*
X253445Y542850D01*
X253736Y542766D01*
X254028Y542850D01*
X254236Y543058D01*
X254361Y543391D01*
X254403Y543683D01*
G01Y547283D02*
X251903D01*
X253695Y545741D01*
Y547825D01*
G01X279400Y516700D02*
X266000D01*
G01X246238Y549543D02*
X243738D01*
Y550584D01*
X243863Y550918D01*
X244030Y551126D01*
X244363Y551209D01*
X244696Y551126D01*
X244905Y550876D01*
X245030Y550584D01*
Y549543D01*
G01Y550584D02*
X246238Y551209D01*
G01X245738Y552559D02*
X246030Y552809D01*
X246196Y553143D01*
X246238Y553518D01*
X246196Y553851D01*
X245988Y554184D01*
X245738Y554393D01*
X245488Y554434D01*
X245196Y554351D01*
X244988Y554059D01*
X244905Y553768D01*
Y553393D01*
G01Y553768D02*
X244780Y554018D01*
X244571Y554226D01*
X244321Y554309D01*
X244071Y554226D01*
X243863Y554018D01*
X243738Y553643D01*
X243780Y553268D01*
X243946Y552893D01*
G01X244155Y555784D02*
X243905Y556034D01*
X243780Y556326D01*
X243738Y556659D01*
X243821Y557076D01*
X244030Y557368D01*
X244280Y557451D01*
X244530Y557409D01*
X244738Y557243D01*
X245155Y556409D01*
X245446Y556034D01*
X245863Y555784D01*
X246238Y555701D01*
Y557451D01*
G01Y559676D02*
X243738D01*
X244238Y559176D01*
G01X246238D02*
Y560176D01*
G01X258238Y549543D02*
X255738D01*
Y550584D01*
X255863Y550918D01*
X256030Y551126D01*
X256363Y551209D01*
X256696Y551126D01*
X256905Y550876D01*
X257030Y550584D01*
Y549543D01*
G01Y550584D02*
X258238Y551209D01*
G01X257738Y552559D02*
X258030Y552809D01*
X258196Y553143D01*
X258238Y553518D01*
X258196Y553851D01*
X257988Y554184D01*
X257738Y554393D01*
X257488Y554434D01*
X257196Y554351D01*
X256988Y554059D01*
X256905Y553768D01*
Y553393D01*
G01Y553768D02*
X256780Y554018D01*
X256571Y554226D01*
X256321Y554309D01*
X256071Y554226D01*
X255863Y554018D01*
X255738Y553643D01*
X255780Y553268D01*
X255946Y552893D01*
G01X255738Y556576D02*
X255821Y556243D01*
X256030Y555993D01*
X256280Y555826D01*
X256613Y555701D01*
X256988Y555659D01*
X257363Y555701D01*
X257696Y555826D01*
X257946Y555993D01*
X258155Y556243D01*
X258238Y556576D01*
X258155Y556909D01*
X257946Y557159D01*
X257696Y557326D01*
X257363Y557451D01*
X256988Y557493D01*
X256613Y557451D01*
X256280Y557326D01*
X256030Y557159D01*
X255821Y556909D01*
X255738Y556576D01*
G01X256155Y558884D02*
X255905Y559134D01*
X255780Y559426D01*
X255738Y559759D01*
X255821Y560176D01*
X256030Y560468D01*
X256280Y560551D01*
X256530Y560509D01*
X256738Y560343D01*
X257155Y559509D01*
X257446Y559134D01*
X257863Y558884D01*
X258238Y558801D01*
Y560551D01*
G01X257946Y562068D02*
X258155Y562359D01*
X258238Y562693D01*
X258155Y563026D01*
X257905Y563318D01*
X257530Y563526D01*
X257155Y563609D01*
X256696D01*
X256321Y563526D01*
X255988Y563318D01*
X255821Y563068D01*
X255738Y562776D01*
X255821Y562443D01*
X255988Y562193D01*
X256238Y562026D01*
X256571Y561943D01*
X256863Y562026D01*
X257155Y562234D01*
X257321Y562484D01*
X257363Y562776D01*
X257280Y563109D01*
X257071Y563359D01*
X256696Y563609D01*
G01X254238Y549543D02*
X251738D01*
Y550584D01*
X251863Y550918D01*
X252030Y551126D01*
X252363Y551209D01*
X252696Y551126D01*
X252905Y550876D01*
X253030Y550584D01*
Y549543D01*
G01Y550584D02*
X254238Y551209D01*
G01X253863Y552559D02*
X254071Y552809D01*
X254196Y553101D01*
X254238Y553476D01*
X254155Y553851D01*
X253988Y554143D01*
X253696Y554351D01*
X253363Y554393D01*
X253030Y554309D01*
X252821Y554101D01*
X252655Y553809D01*
X252613Y553518D01*
X252655Y553226D01*
X252821Y552851D01*
X251738Y552976D01*
Y554101D01*
G01X254238Y556493D02*
X253696Y556576D01*
X253238Y556701D01*
X252821Y556868D01*
X252363Y557076D01*
X251738Y557409D01*
Y555743D01*
G01X253196Y558884D02*
X252905Y559176D01*
X252738Y559426D01*
X252655Y559759D01*
X252738Y560051D01*
X252905Y560259D01*
X253155Y560426D01*
X253446Y560468D01*
X253696Y560426D01*
X253946Y560259D01*
X254155Y560009D01*
X254238Y559718D01*
X254155Y559384D01*
X253905Y559093D01*
X253530Y558926D01*
X253113Y558884D01*
X252571Y558968D01*
X252280Y559093D01*
X251988Y559301D01*
X251780Y559593D01*
X251738Y559884D01*
X251821Y560176D01*
X252030Y560384D01*
G01X252155Y561984D02*
X251905Y562234D01*
X251780Y562526D01*
X251738Y562859D01*
X251821Y563276D01*
X252030Y563568D01*
X252280Y563651D01*
X252530Y563609D01*
X252738Y563443D01*
X253155Y562609D01*
X253446Y562234D01*
X253863Y561984D01*
X254238Y561901D01*
Y563651D01*
G01X249894Y569705D02*
Y572205D01*
X250935D01*
X251269Y572080D01*
X251477Y571913D01*
X251560Y571580D01*
X251477Y571247D01*
X251227Y571038D01*
X250935Y570913D01*
X249894D01*
G01X250935D02*
X251560Y569705D01*
G01X253035Y571788D02*
X253285Y572038D01*
X253577Y572163D01*
X253910Y572205D01*
X254327Y572122D01*
X254619Y571913D01*
X254702Y571663D01*
X254660Y571413D01*
X254494Y571205D01*
X253660Y570788D01*
X253285Y570497D01*
X253035Y570080D01*
X252952Y569705D01*
X254702D01*
G01X256927Y572205D02*
X256594Y572122D01*
X256344Y571913D01*
X256177Y571663D01*
X256052Y571330D01*
X256010Y570955D01*
X256052Y570580D01*
X256177Y570247D01*
X256344Y569997D01*
X256594Y569788D01*
X256927Y569705D01*
X257260Y569788D01*
X257510Y569997D01*
X257677Y570247D01*
X257802Y570580D01*
X257844Y570955D01*
X257802Y571330D01*
X257677Y571663D01*
X257510Y571913D01*
X257260Y572122D01*
X256927Y572205D01*
G01X260027D02*
X259694Y572122D01*
X259444Y571913D01*
X259277Y571663D01*
X259152Y571330D01*
X259110Y570955D01*
X259152Y570580D01*
X259277Y570247D01*
X259444Y569997D01*
X259694Y569788D01*
X260027Y569705D01*
X260360Y569788D01*
X260610Y569997D01*
X260777Y570247D01*
X260902Y570580D01*
X260944Y570955D01*
X260902Y571330D01*
X260777Y571663D01*
X260610Y571913D01*
X260360Y572122D01*
X260027Y572205D01*
G01X257720Y579381D02*
Y583381D01*
X250320D01*
G01X238238Y549543D02*
X235738D01*
Y550584D01*
X235863Y550918D01*
X236030Y551126D01*
X236363Y551209D01*
X236696Y551126D01*
X236905Y550876D01*
X237030Y550584D01*
Y549543D01*
G01Y550584D02*
X238238Y551209D01*
G01X237863Y552559D02*
X238071Y552809D01*
X238196Y553101D01*
X238238Y553476D01*
X238155Y553851D01*
X237988Y554143D01*
X237696Y554351D01*
X237363Y554393D01*
X237030Y554309D01*
X236821Y554101D01*
X236655Y553809D01*
X236613Y553518D01*
X236655Y553226D01*
X236821Y552851D01*
X235738Y552976D01*
Y554101D01*
G01X238238Y556493D02*
X237696Y556576D01*
X237238Y556701D01*
X236821Y556868D01*
X236363Y557076D01*
X235738Y557409D01*
Y555743D01*
G01X237196Y558884D02*
X236905Y559176D01*
X236738Y559426D01*
X236655Y559759D01*
X236738Y560051D01*
X236905Y560259D01*
X237155Y560426D01*
X237446Y560468D01*
X237696Y560426D01*
X237946Y560259D01*
X238155Y560009D01*
X238238Y559718D01*
X238155Y559384D01*
X237905Y559093D01*
X237530Y558926D01*
X237113Y558884D01*
X236571Y558968D01*
X236280Y559093D01*
X235988Y559301D01*
X235780Y559593D01*
X235738Y559884D01*
X235821Y560176D01*
X236030Y560384D01*
G01X238238Y562693D02*
X237696Y562776D01*
X237238Y562901D01*
X236821Y563068D01*
X236363Y563276D01*
X235738Y563609D01*
Y561943D01*
G01X242238Y549543D02*
X239738D01*
Y550584D01*
X239863Y550918D01*
X240030Y551126D01*
X240363Y551209D01*
X240696Y551126D01*
X240905Y550876D01*
X241030Y550584D01*
Y549543D01*
G01Y550584D02*
X242238Y551209D01*
G01X241863Y552559D02*
X242071Y552809D01*
X242196Y553101D01*
X242238Y553476D01*
X242155Y553851D01*
X241988Y554143D01*
X241696Y554351D01*
X241363Y554393D01*
X241030Y554309D01*
X240821Y554101D01*
X240655Y553809D01*
X240613Y553518D01*
X240655Y553226D01*
X240821Y552851D01*
X239738Y552976D01*
Y554101D01*
G01X242238Y556493D02*
X241696Y556576D01*
X241238Y556701D01*
X240821Y556868D01*
X240363Y557076D01*
X239738Y557409D01*
Y555743D01*
G01X241196Y558884D02*
X240905Y559176D01*
X240738Y559426D01*
X240655Y559759D01*
X240738Y560051D01*
X240905Y560259D01*
X241155Y560426D01*
X241446Y560468D01*
X241696Y560426D01*
X241946Y560259D01*
X242155Y560009D01*
X242238Y559718D01*
X242155Y559384D01*
X241905Y559093D01*
X241530Y558926D01*
X241113Y558884D01*
X240571Y558968D01*
X240280Y559093D01*
X239988Y559301D01*
X239780Y559593D01*
X239738Y559884D01*
X239821Y560176D01*
X240030Y560384D01*
G01X241863Y561859D02*
X242071Y562109D01*
X242196Y562401D01*
X242238Y562776D01*
X242155Y563151D01*
X241988Y563443D01*
X241696Y563651D01*
X241363Y563693D01*
X241030Y563609D01*
X240821Y563401D01*
X240655Y563109D01*
X240613Y562818D01*
X240655Y562526D01*
X240821Y562151D01*
X239738Y562276D01*
Y563401D01*
G01X247946Y551293D02*
X247821Y551043D01*
X247738Y550751D01*
Y550418D01*
X247863Y550043D01*
X248071Y549751D01*
X248321Y549543D01*
X248738Y549376D01*
X249113Y549334D01*
X249488Y549418D01*
X249738Y549543D01*
X249988Y549793D01*
X250155Y550084D01*
X250238Y550376D01*
Y550668D01*
X250155Y550959D01*
X250030Y551209D01*
X249863Y551418D01*
G01X250238Y553476D02*
X250196Y553768D01*
X250071Y554101D01*
X249863Y554309D01*
X249571Y554393D01*
X249280Y554309D01*
X249030Y554059D01*
X248905Y553684D01*
Y553268D01*
X248821Y553018D01*
X248613Y552809D01*
X248321Y552726D01*
X248030Y552851D01*
X247821Y553143D01*
X247738Y553476D01*
X247821Y553809D01*
X248030Y554101D01*
X248321Y554226D01*
X248613Y554143D01*
X248821Y553934D01*
X248905Y553684D01*
Y553268D01*
X249030Y552893D01*
X249280Y552643D01*
X249571Y552559D01*
X249863Y552643D01*
X250071Y552851D01*
X250196Y553184D01*
X250238Y553476D01*
G01X247738Y556576D02*
X247821Y556243D01*
X248030Y555993D01*
X248280Y555826D01*
X248613Y555701D01*
X248988Y555659D01*
X249363Y555701D01*
X249696Y555826D01*
X249946Y555993D01*
X250155Y556243D01*
X250238Y556576D01*
X250155Y556909D01*
X249946Y557159D01*
X249696Y557326D01*
X249363Y557451D01*
X248988Y557493D01*
X248613Y557451D01*
X248280Y557326D01*
X248030Y557159D01*
X247821Y556909D01*
X247738Y556576D01*
G01X250238Y559676D02*
X250196Y559968D01*
X250071Y560301D01*
X249863Y560509D01*
X249571Y560593D01*
X249280Y560509D01*
X249030Y560259D01*
X248905Y559884D01*
Y559468D01*
X248821Y559218D01*
X248613Y559009D01*
X248321Y558926D01*
X248030Y559051D01*
X247821Y559343D01*
X247738Y559676D01*
X247821Y560009D01*
X248030Y560301D01*
X248321Y560426D01*
X248613Y560343D01*
X248821Y560134D01*
X248905Y559884D01*
Y559468D01*
X249030Y559093D01*
X249280Y558843D01*
X249571Y558759D01*
X249863Y558843D01*
X250071Y559051D01*
X250196Y559384D01*
X250238Y559676D01*
G01X249738Y561859D02*
X250030Y562109D01*
X250196Y562443D01*
X250238Y562818D01*
X250196Y563151D01*
X249988Y563484D01*
X249738Y563693D01*
X249488Y563734D01*
X249196Y563651D01*
X248988Y563359D01*
X248905Y563068D01*
Y562693D01*
G01Y563068D02*
X248780Y563318D01*
X248571Y563526D01*
X248321Y563609D01*
X248071Y563526D01*
X247863Y563318D01*
X247738Y562943D01*
X247780Y562568D01*
X247946Y562193D01*
G01X251615Y568488D02*
X251365Y568613D01*
X251073Y568696D01*
X250740D01*
X250365Y568571D01*
X250073Y568363D01*
X249865Y568113D01*
X249698Y567696D01*
X249656Y567321D01*
X249740Y566946D01*
X249865Y566696D01*
X250115Y566446D01*
X250406Y566279D01*
X250698Y566196D01*
X250990D01*
X251281Y566279D01*
X251531Y566404D01*
X251740Y566571D01*
G01X253798Y566196D02*
Y568696D01*
X253298Y568196D01*
G01Y566196D02*
X254298D01*
G01X255981Y566571D02*
X256231Y566363D01*
X256523Y566238D01*
X256898Y566196D01*
X257273Y566279D01*
X257565Y566446D01*
X257773Y566738D01*
X257815Y567071D01*
X257731Y567404D01*
X257523Y567613D01*
X257231Y567779D01*
X256940Y567821D01*
X256648Y567779D01*
X256273Y567613D01*
X256398Y568696D01*
X257523D01*
G01X259206Y568279D02*
X259456Y568529D01*
X259748Y568654D01*
X260081Y568696D01*
X260498Y568613D01*
X260790Y568404D01*
X260873Y568154D01*
X260831Y567904D01*
X260665Y567696D01*
X259831Y567279D01*
X259456Y566988D01*
X259206Y566571D01*
X259123Y566196D01*
X260873D01*
G01X237517Y585000D02*
Y587500D01*
X238558D01*
X238892Y587375D01*
X239100Y587208D01*
X239183Y586875D01*
X239100Y586542D01*
X238850Y586333D01*
X238558Y586208D01*
X237517D01*
G01X238558D02*
X239183Y585000D01*
G01X241450D02*
Y587500D01*
X240950Y587000D01*
G01Y585000D02*
X241950D01*
G01X243633Y585375D02*
X243883Y585167D01*
X244175Y585042D01*
X244550Y585000D01*
X244925Y585083D01*
X245217Y585250D01*
X245425Y585542D01*
X245467Y585875D01*
X245383Y586208D01*
X245175Y586417D01*
X244883Y586583D01*
X244592Y586625D01*
X244300Y586583D01*
X243925Y586417D01*
X244050Y587500D01*
X245175D01*
G01X246942Y585292D02*
X247233Y585083D01*
X247567Y585000D01*
X247900Y585083D01*
X248192Y585333D01*
X248400Y585708D01*
X248483Y586083D01*
Y586542D01*
X248400Y586917D01*
X248192Y587250D01*
X247942Y587417D01*
X247650Y587500D01*
X247317Y587417D01*
X247067Y587250D01*
X246900Y587000D01*
X246817Y586667D01*
X246900Y586375D01*
X247108Y586083D01*
X247358Y585917D01*
X247650Y585875D01*
X247983Y585958D01*
X248233Y586167D01*
X248483Y586542D01*
G01X237517Y589500D02*
Y592000D01*
X238558D01*
X238892Y591875D01*
X239100Y591708D01*
X239183Y591375D01*
X239100Y591042D01*
X238850Y590833D01*
X238558Y590708D01*
X237517D01*
G01X238558D02*
X239183Y589500D01*
G01X241450D02*
Y592000D01*
X240950Y591500D01*
G01Y589500D02*
X241950D01*
G01X243758Y590542D02*
X244050Y590833D01*
X244300Y591000D01*
X244633Y591083D01*
X244925Y591000D01*
X245133Y590833D01*
X245300Y590583D01*
X245342Y590292D01*
X245300Y590042D01*
X245133Y589792D01*
X244883Y589583D01*
X244592Y589500D01*
X244258Y589583D01*
X243967Y589833D01*
X243800Y590208D01*
X243758Y590625D01*
X243842Y591167D01*
X243967Y591458D01*
X244175Y591750D01*
X244467Y591958D01*
X244758Y592000D01*
X245050Y591917D01*
X245258Y591708D01*
G01X246858Y591583D02*
X247108Y591833D01*
X247400Y591958D01*
X247733Y592000D01*
X248150Y591917D01*
X248442Y591708D01*
X248525Y591458D01*
X248483Y591208D01*
X248317Y591000D01*
X247483Y590583D01*
X247108Y590292D01*
X246858Y589875D01*
X246775Y589500D01*
X248525D01*
G01X238495Y610796D02*
Y613296D01*
X239495D01*
X239828Y613171D01*
X240078Y612879D01*
X240161Y612546D01*
X240078Y612213D01*
X239870Y611963D01*
X239495Y611838D01*
X238495D01*
G01X242678Y612046D02*
X243511D01*
Y611296D01*
X243261Y611046D01*
X242970Y610879D01*
X242553Y610796D01*
X242136Y610879D01*
X241845Y611046D01*
X241595Y611296D01*
X241428Y611588D01*
X241345Y611921D01*
Y612213D01*
X241428Y612463D01*
X241595Y612754D01*
X241845Y613004D01*
X242095Y613171D01*
X242428Y613296D01*
X242720D01*
X243053Y613213D01*
X243303Y613046D01*
G01X245528Y610796D02*
Y613296D01*
X245028Y612796D01*
G01Y610796D02*
X246028D01*
G01X248628D02*
Y613296D01*
X248128Y612796D01*
G01Y610796D02*
X249128D01*
G01X249356Y647023D02*
Y649523D01*
X250356D01*
X250689Y649398D01*
X250939Y649106D01*
X251022Y648773D01*
X250939Y648440D01*
X250731Y648190D01*
X250356Y648065D01*
X249356D01*
G01X252372Y649523D02*
Y647731D01*
X252539Y647356D01*
X252872Y647106D01*
X253289Y647023D01*
X253706Y647106D01*
X254039Y647356D01*
X254206Y647731D01*
Y649523D01*
G01X256889Y647023D02*
Y649523D01*
X255347Y647731D01*
X257431D01*
G01X269200Y642300D02*
Y645300D01*
X266200D01*
G01X252400D02*
X249400D01*
Y642300D01*
G01Y629500D02*
Y626500D01*
X252400D01*
G01X250300Y632000D02*
X247300D01*
G01X235300Y633700D02*
X239300D01*
Y641100D01*
G01X247300D02*
X243300D01*
Y633700D01*
G01X238251Y614937D02*
Y617437D01*
X239251D01*
X239584Y617312D01*
X239834Y617020D01*
X239917Y616687D01*
X239834Y616354D01*
X239626Y616104D01*
X239251Y615979D01*
X238251D01*
G01X242434Y616187D02*
X243267D01*
Y615437D01*
X243017Y615187D01*
X242726Y615020D01*
X242309Y614937D01*
X241892Y615020D01*
X241601Y615187D01*
X241351Y615437D01*
X241184Y615729D01*
X241101Y616062D01*
Y616354D01*
X241184Y616604D01*
X241351Y616895D01*
X241601Y617145D01*
X241851Y617312D01*
X242184Y617437D01*
X242476D01*
X242809Y617354D01*
X243059Y617187D01*
G01X244492Y615979D02*
X244784Y616270D01*
X245034Y616437D01*
X245367Y616520D01*
X245659Y616437D01*
X245867Y616270D01*
X246034Y616020D01*
X246076Y615729D01*
X246034Y615479D01*
X245867Y615229D01*
X245617Y615020D01*
X245326Y614937D01*
X244992Y615020D01*
X244701Y615270D01*
X244534Y615645D01*
X244492Y616062D01*
X244576Y616604D01*
X244701Y616895D01*
X244909Y617187D01*
X245201Y617395D01*
X245492Y617437D01*
X245784Y617354D01*
X245992Y617145D01*
G01X248384Y614937D02*
X248676Y614979D01*
X249009Y615104D01*
X249217Y615312D01*
X249301Y615604D01*
X249217Y615895D01*
X248967Y616145D01*
X248592Y616270D01*
X248176D01*
X247926Y616354D01*
X247717Y616562D01*
X247634Y616854D01*
X247759Y617145D01*
X248051Y617354D01*
X248384Y617437D01*
X248717Y617354D01*
X249009Y617145D01*
X249134Y616854D01*
X249051Y616562D01*
X248842Y616354D01*
X248592Y616270D01*
X248176D01*
X247801Y616145D01*
X247551Y615895D01*
X247467Y615604D01*
X247551Y615312D01*
X247759Y615104D01*
X248092Y614979D01*
X248384Y614937D01*
G01X257888Y660760D02*
Y663260D01*
X258888D01*
X259221Y663135D01*
X259471Y662843D01*
X259554Y662510D01*
X259471Y662177D01*
X259263Y661927D01*
X258888Y661802D01*
X257888D01*
G01X260988Y660760D02*
Y663260D01*
X262029D01*
X262363Y663135D01*
X262571Y662968D01*
X262654Y662635D01*
X262571Y662302D01*
X262321Y662093D01*
X262029Y661968D01*
X260988D01*
G01X262029D02*
X262654Y660760D01*
G01X264129Y662843D02*
X264379Y663093D01*
X264671Y663218D01*
X265004Y663260D01*
X265421Y663177D01*
X265713Y662968D01*
X265796Y662718D01*
X265754Y662468D01*
X265588Y662260D01*
X264754Y661843D01*
X264379Y661552D01*
X264129Y661135D01*
X264046Y660760D01*
X265796D01*
G01X267229Y662843D02*
X267479Y663093D01*
X267771Y663218D01*
X268104Y663260D01*
X268521Y663177D01*
X268813Y662968D01*
X268896Y662718D01*
X268854Y662468D01*
X268688Y662260D01*
X267854Y661843D01*
X267479Y661552D01*
X267229Y661135D01*
X267146Y660760D01*
X268896D01*
G01X258017Y655500D02*
Y658000D01*
X259017D01*
X259350Y657875D01*
X259600Y657583D01*
X259683Y657250D01*
X259600Y656917D01*
X259392Y656667D01*
X259017Y656542D01*
X258017D01*
G01X262867Y657792D02*
X262617Y657917D01*
X262325Y658000D01*
X261992D01*
X261617Y657875D01*
X261325Y657667D01*
X261117Y657417D01*
X260950Y657000D01*
X260908Y656625D01*
X260992Y656250D01*
X261117Y656000D01*
X261367Y655750D01*
X261658Y655583D01*
X261950Y655500D01*
X262242D01*
X262533Y655583D01*
X262783Y655708D01*
X262992Y655875D01*
G01X264967Y655500D02*
X265050Y656042D01*
X265175Y656500D01*
X265342Y656917D01*
X265550Y657375D01*
X265883Y658000D01*
X264217D01*
G01X268650Y655500D02*
Y658000D01*
X267108Y656208D01*
X269192D01*
G01X264258Y700889D02*
X261758D01*
Y701930D01*
X261883Y702264D01*
X262050Y702472D01*
X262383Y702555D01*
X262716Y702472D01*
X262925Y702222D01*
X263050Y701930D01*
Y700889D01*
G01Y701930D02*
X264258Y702555D01*
G01Y704739D02*
X263716Y704822D01*
X263258Y704947D01*
X262841Y705114D01*
X262383Y705322D01*
X261758Y705655D01*
Y703989D01*
G01X263966Y707214D02*
X264175Y707505D01*
X264258Y707839D01*
X264175Y708172D01*
X263925Y708464D01*
X263550Y708672D01*
X263175Y708755D01*
X262716D01*
X262341Y708672D01*
X262008Y708464D01*
X261841Y708214D01*
X261758Y707922D01*
X261841Y707589D01*
X262008Y707339D01*
X262258Y707172D01*
X262591Y707089D01*
X262883Y707172D01*
X263175Y707380D01*
X263341Y707630D01*
X263383Y707922D01*
X263300Y708255D01*
X263091Y708505D01*
X262716Y708755D01*
G01X264258Y711022D02*
X264216Y711314D01*
X264091Y711647D01*
X263883Y711855D01*
X263591Y711939D01*
X263300Y711855D01*
X263050Y711605D01*
X262925Y711230D01*
Y710814D01*
X262841Y710564D01*
X262633Y710355D01*
X262341Y710272D01*
X262050Y710397D01*
X261841Y710689D01*
X261758Y711022D01*
X261841Y711355D01*
X262050Y711647D01*
X262341Y711772D01*
X262633Y711689D01*
X262841Y711480D01*
X262925Y711230D01*
Y710814D01*
X263050Y710439D01*
X263300Y710189D01*
X263591Y710105D01*
X263883Y710189D01*
X264091Y710397D01*
X264216Y710730D01*
X264258Y711022D01*
G01Y714122D02*
X261758D01*
X262258Y713622D01*
G01X264258D02*
Y714622D01*
G01X260258Y700889D02*
X257758D01*
Y701930D01*
X257883Y702264D01*
X258050Y702472D01*
X258383Y702555D01*
X258716Y702472D01*
X258925Y702222D01*
X259050Y701930D01*
Y700889D01*
G01Y701930D02*
X260258Y702555D01*
G01Y704739D02*
X259716Y704822D01*
X259258Y704947D01*
X258841Y705114D01*
X258383Y705322D01*
X257758Y705655D01*
Y703989D01*
G01X259966Y707214D02*
X260175Y707505D01*
X260258Y707839D01*
X260175Y708172D01*
X259925Y708464D01*
X259550Y708672D01*
X259175Y708755D01*
X258716D01*
X258341Y708672D01*
X258008Y708464D01*
X257841Y708214D01*
X257758Y707922D01*
X257841Y707589D01*
X258008Y707339D01*
X258258Y707172D01*
X258591Y707089D01*
X258883Y707172D01*
X259175Y707380D01*
X259341Y707630D01*
X259383Y707922D01*
X259300Y708255D01*
X259091Y708505D01*
X258716Y708755D01*
G01X259883Y710105D02*
X260091Y710355D01*
X260216Y710647D01*
X260258Y711022D01*
X260175Y711397D01*
X260008Y711689D01*
X259716Y711897D01*
X259383Y711939D01*
X259050Y711855D01*
X258841Y711647D01*
X258675Y711355D01*
X258633Y711064D01*
X258675Y710772D01*
X258841Y710397D01*
X257758Y710522D01*
Y711647D01*
G01X258175Y713330D02*
X257925Y713580D01*
X257800Y713872D01*
X257758Y714205D01*
X257841Y714622D01*
X258050Y714914D01*
X258300Y714997D01*
X258550Y714955D01*
X258758Y714789D01*
X259175Y713955D01*
X259466Y713580D01*
X259883Y713330D01*
X260258Y713247D01*
Y714997D01*
G01X256400Y701167D02*
X253900D01*
Y702208D01*
X254025Y702542D01*
X254192Y702750D01*
X254525Y702833D01*
X254858Y702750D01*
X255067Y702500D01*
X255192Y702208D01*
Y701167D01*
G01Y702208D02*
X256400Y702833D01*
G01Y705017D02*
X255858Y705100D01*
X255400Y705225D01*
X254983Y705392D01*
X254525Y705600D01*
X253900Y705933D01*
Y704267D01*
G01X256108Y707492D02*
X256317Y707783D01*
X256400Y708117D01*
X256317Y708450D01*
X256067Y708742D01*
X255692Y708950D01*
X255317Y709033D01*
X254858D01*
X254483Y708950D01*
X254150Y708742D01*
X253983Y708492D01*
X253900Y708200D01*
X253983Y707867D01*
X254150Y707617D01*
X254400Y707450D01*
X254733Y707367D01*
X255025Y707450D01*
X255317Y707658D01*
X255483Y707908D01*
X255525Y708200D01*
X255442Y708533D01*
X255233Y708783D01*
X254858Y709033D01*
G01X255900Y710383D02*
X256192Y710633D01*
X256358Y710967D01*
X256400Y711342D01*
X256358Y711675D01*
X256150Y712008D01*
X255900Y712217D01*
X255650Y712258D01*
X255358Y712175D01*
X255150Y711883D01*
X255067Y711592D01*
Y711217D01*
G01Y711592D02*
X254942Y711842D01*
X254733Y712050D01*
X254483Y712133D01*
X254233Y712050D01*
X254025Y711842D01*
X253900Y711467D01*
X253942Y711092D01*
X254108Y710717D01*
G01X256400Y714317D02*
X255858Y714400D01*
X255400Y714525D01*
X254983Y714692D01*
X254525Y714900D01*
X253900Y715233D01*
Y713567D01*
G01X252258Y700889D02*
X249758D01*
Y701930D01*
X249883Y702264D01*
X250050Y702472D01*
X250383Y702555D01*
X250716Y702472D01*
X250925Y702222D01*
X251050Y701930D01*
Y700889D01*
G01Y701930D02*
X252258Y702555D01*
G01Y704739D02*
X251716Y704822D01*
X251258Y704947D01*
X250841Y705114D01*
X250383Y705322D01*
X249758Y705655D01*
Y703989D01*
G01X251966Y707214D02*
X252175Y707505D01*
X252258Y707839D01*
X252175Y708172D01*
X251925Y708464D01*
X251550Y708672D01*
X251175Y708755D01*
X250716D01*
X250341Y708672D01*
X250008Y708464D01*
X249841Y708214D01*
X249758Y707922D01*
X249841Y707589D01*
X250008Y707339D01*
X250258Y707172D01*
X250591Y707089D01*
X250883Y707172D01*
X251175Y707380D01*
X251341Y707630D01*
X251383Y707922D01*
X251300Y708255D01*
X251091Y708505D01*
X250716Y708755D01*
G01X251758Y710105D02*
X252050Y710355D01*
X252216Y710689D01*
X252258Y711064D01*
X252216Y711397D01*
X252008Y711730D01*
X251758Y711939D01*
X251508Y711980D01*
X251216Y711897D01*
X251008Y711605D01*
X250925Y711314D01*
Y710939D01*
G01Y711314D02*
X250800Y711564D01*
X250591Y711772D01*
X250341Y711855D01*
X250091Y711772D01*
X249883Y711564D01*
X249758Y711189D01*
X249800Y710814D01*
X249966Y710439D01*
G01X251883Y713205D02*
X252091Y713455D01*
X252216Y713747D01*
X252258Y714122D01*
X252175Y714497D01*
X252008Y714789D01*
X251716Y714997D01*
X251383Y715039D01*
X251050Y714955D01*
X250841Y714747D01*
X250675Y714455D01*
X250633Y714164D01*
X250675Y713872D01*
X250841Y713497D01*
X249758Y713622D01*
Y714747D01*
G01X268258Y700889D02*
X265758D01*
Y701930D01*
X265883Y702264D01*
X266050Y702472D01*
X266383Y702555D01*
X266716Y702472D01*
X266925Y702222D01*
X267050Y701930D01*
Y700889D01*
G01Y701930D02*
X268258Y702555D01*
G01Y704739D02*
X267716Y704822D01*
X267258Y704947D01*
X266841Y705114D01*
X266383Y705322D01*
X265758Y705655D01*
Y703989D01*
G01X267966Y707214D02*
X268175Y707505D01*
X268258Y707839D01*
X268175Y708172D01*
X267925Y708464D01*
X267550Y708672D01*
X267175Y708755D01*
X266716D01*
X266341Y708672D01*
X266008Y708464D01*
X265841Y708214D01*
X265758Y707922D01*
X265841Y707589D01*
X266008Y707339D01*
X266258Y707172D01*
X266591Y707089D01*
X266883Y707172D01*
X267175Y707380D01*
X267341Y707630D01*
X267383Y707922D01*
X267300Y708255D01*
X267091Y708505D01*
X266716Y708755D01*
G01X266175Y710230D02*
X265925Y710480D01*
X265800Y710772D01*
X265758Y711105D01*
X265841Y711522D01*
X266050Y711814D01*
X266300Y711897D01*
X266550Y711855D01*
X266758Y711689D01*
X267175Y710855D01*
X267466Y710480D01*
X267883Y710230D01*
X268258Y710147D01*
Y711897D01*
G01Y714122D02*
X268216Y714414D01*
X268091Y714747D01*
X267883Y714955D01*
X267591Y715039D01*
X267300Y714955D01*
X267050Y714705D01*
X266925Y714330D01*
Y713914D01*
X266841Y713664D01*
X266633Y713455D01*
X266341Y713372D01*
X266050Y713497D01*
X265841Y713789D01*
X265758Y714122D01*
X265841Y714455D01*
X266050Y714747D01*
X266341Y714872D01*
X266633Y714789D01*
X266841Y714580D01*
X266925Y714330D01*
Y713914D01*
X267050Y713539D01*
X267300Y713289D01*
X267591Y713205D01*
X267883Y713289D01*
X268091Y713497D01*
X268216Y713830D01*
X268258Y714122D01*
G01X244054Y701091D02*
X241554D01*
Y702132D01*
X241679Y702466D01*
X241846Y702674D01*
X242179Y702757D01*
X242512Y702674D01*
X242721Y702424D01*
X242846Y702132D01*
Y701091D01*
G01Y702132D02*
X244054Y702757D01*
G01X243679Y704107D02*
X243887Y704357D01*
X244012Y704649D01*
X244054Y705024D01*
X243971Y705399D01*
X243804Y705691D01*
X243512Y705899D01*
X243179Y705941D01*
X242846Y705857D01*
X242637Y705649D01*
X242471Y705357D01*
X242429Y705066D01*
X242471Y704774D01*
X242637Y704399D01*
X241554Y704524D01*
Y705649D01*
G01X244054Y708124D02*
X241554D01*
X242054Y707624D01*
G01X244054D02*
Y708624D01*
G01Y711141D02*
X243512Y711224D01*
X243054Y711349D01*
X242637Y711516D01*
X242179Y711724D01*
X241554Y712057D01*
Y710391D01*
G01X248054Y701091D02*
X245554D01*
Y702132D01*
X245679Y702466D01*
X245846Y702674D01*
X246179Y702757D01*
X246512Y702674D01*
X246721Y702424D01*
X246846Y702132D01*
Y701091D01*
G01Y702132D02*
X248054Y702757D01*
G01X247679Y704107D02*
X247887Y704357D01*
X248012Y704649D01*
X248054Y705024D01*
X247971Y705399D01*
X247804Y705691D01*
X247512Y705899D01*
X247179Y705941D01*
X246846Y705857D01*
X246637Y705649D01*
X246471Y705357D01*
X246429Y705066D01*
X246471Y704774D01*
X246637Y704399D01*
X245554Y704524D01*
Y705649D01*
G01X248054Y708124D02*
X245554D01*
X246054Y707624D01*
G01X248054D02*
Y708624D01*
G01X247012Y710432D02*
X246721Y710724D01*
X246554Y710974D01*
X246471Y711307D01*
X246554Y711599D01*
X246721Y711807D01*
X246971Y711974D01*
X247262Y712016D01*
X247512Y711974D01*
X247762Y711807D01*
X247971Y711557D01*
X248054Y711266D01*
X247971Y710932D01*
X247721Y710641D01*
X247346Y710474D01*
X246929Y710432D01*
X246387Y710516D01*
X246096Y710641D01*
X245804Y710849D01*
X245596Y711141D01*
X245554Y711432D01*
X245637Y711724D01*
X245846Y711932D01*
G01X266108Y778767D02*
X265983Y778517D01*
X265900Y778225D01*
Y777892D01*
X266025Y777517D01*
X266233Y777225D01*
X266483Y777017D01*
X266900Y776850D01*
X267275Y776808D01*
X267650Y776892D01*
X267900Y777017D01*
X268150Y777267D01*
X268317Y777558D01*
X268400Y777850D01*
Y778142D01*
X268317Y778433D01*
X268192Y778683D01*
X268025Y778892D01*
G01X267900Y780033D02*
X268192Y780283D01*
X268358Y780617D01*
X268400Y780992D01*
X268358Y781325D01*
X268150Y781658D01*
X267900Y781867D01*
X267650Y781908D01*
X267358Y781825D01*
X267150Y781533D01*
X267067Y781242D01*
Y780867D01*
G01Y781242D02*
X266942Y781492D01*
X266733Y781700D01*
X266483Y781783D01*
X266233Y781700D01*
X266025Y781492D01*
X265900Y781117D01*
X265942Y780742D01*
X266108Y780367D01*
G01X268400Y783967D02*
X267858Y784050D01*
X267400Y784175D01*
X266983Y784342D01*
X266525Y784550D01*
X265900Y784883D01*
Y783217D01*
G01Y787150D02*
X265983Y786817D01*
X266192Y786567D01*
X266442Y786400D01*
X266775Y786275D01*
X267150Y786233D01*
X267525Y786275D01*
X267858Y786400D01*
X268108Y786567D01*
X268317Y786817D01*
X268400Y787150D01*
X268317Y787483D01*
X268108Y787733D01*
X267858Y787900D01*
X267525Y788025D01*
X267150Y788067D01*
X266775Y788025D01*
X266442Y787900D01*
X266192Y787733D01*
X265983Y787483D01*
X265900Y787150D01*
G01X253908Y842867D02*
X253783Y842617D01*
X253700Y842325D01*
Y841992D01*
X253825Y841617D01*
X254033Y841325D01*
X254283Y841117D01*
X254700Y840950D01*
X255075Y840908D01*
X255450Y840992D01*
X255700Y841117D01*
X255950Y841367D01*
X256117Y841658D01*
X256200Y841950D01*
Y842242D01*
X256117Y842533D01*
X255992Y842783D01*
X255825Y842992D01*
G01X255700Y844133D02*
X255992Y844383D01*
X256158Y844717D01*
X256200Y845092D01*
X256158Y845425D01*
X255950Y845758D01*
X255700Y845967D01*
X255450Y846008D01*
X255158Y845925D01*
X254950Y845633D01*
X254867Y845342D01*
Y844967D01*
G01Y845342D02*
X254742Y845592D01*
X254533Y845800D01*
X254283Y845883D01*
X254033Y845800D01*
X253825Y845592D01*
X253700Y845217D01*
X253742Y844842D01*
X253908Y844467D01*
G01X255825Y847233D02*
X256033Y847483D01*
X256158Y847775D01*
X256200Y848150D01*
X256117Y848525D01*
X255950Y848817D01*
X255658Y849025D01*
X255325Y849067D01*
X254992Y848983D01*
X254783Y848775D01*
X254617Y848483D01*
X254575Y848192D01*
X254617Y847900D01*
X254783Y847525D01*
X253700Y847650D01*
Y848775D01*
G01X256200Y851250D02*
X256158Y851542D01*
X256033Y851875D01*
X255825Y852083D01*
X255533Y852167D01*
X255242Y852083D01*
X254992Y851833D01*
X254867Y851458D01*
Y851042D01*
X254783Y850792D01*
X254575Y850583D01*
X254283Y850500D01*
X253992Y850625D01*
X253783Y850917D01*
X253700Y851250D01*
X253783Y851583D01*
X253992Y851875D01*
X254283Y852000D01*
X254575Y851917D01*
X254783Y851708D01*
X254867Y851458D01*
Y851042D01*
X254992Y850667D01*
X255242Y850417D01*
X255533Y850333D01*
X255825Y850417D01*
X256033Y850625D01*
X256158Y850958D01*
X256200Y851250D01*
G01X248108Y842867D02*
X247983Y842617D01*
X247900Y842325D01*
Y841992D01*
X248025Y841617D01*
X248233Y841325D01*
X248483Y841117D01*
X248900Y840950D01*
X249275Y840908D01*
X249650Y840992D01*
X249900Y841117D01*
X250150Y841367D01*
X250317Y841658D01*
X250400Y841950D01*
Y842242D01*
X250317Y842533D01*
X250192Y842783D01*
X250025Y842992D01*
G01X249900Y844133D02*
X250192Y844383D01*
X250358Y844717D01*
X250400Y845092D01*
X250358Y845425D01*
X250150Y845758D01*
X249900Y845967D01*
X249650Y846008D01*
X249358Y845925D01*
X249150Y845633D01*
X249067Y845342D01*
Y844967D01*
G01Y845342D02*
X248942Y845592D01*
X248733Y845800D01*
X248483Y845883D01*
X248233Y845800D01*
X248025Y845592D01*
X247900Y845217D01*
X247942Y844842D01*
X248108Y844467D01*
G01X250025Y847233D02*
X250233Y847483D01*
X250358Y847775D01*
X250400Y848150D01*
X250317Y848525D01*
X250150Y848817D01*
X249858Y849025D01*
X249525Y849067D01*
X249192Y848983D01*
X248983Y848775D01*
X248817Y848483D01*
X248775Y848192D01*
X248817Y847900D01*
X248983Y847525D01*
X247900Y847650D01*
Y848775D01*
G01X250400Y851167D02*
X249858Y851250D01*
X249400Y851375D01*
X248983Y851542D01*
X248525Y851750D01*
X247900Y852083D01*
Y850417D01*
G01X261108Y842967D02*
X260983Y842717D01*
X260900Y842425D01*
Y842092D01*
X261025Y841717D01*
X261233Y841425D01*
X261483Y841217D01*
X261900Y841050D01*
X262275Y841008D01*
X262650Y841092D01*
X262900Y841217D01*
X263150Y841467D01*
X263317Y841758D01*
X263400Y842050D01*
Y842342D01*
X263317Y842633D01*
X263192Y842883D01*
X263025Y843092D01*
G01X262900Y844233D02*
X263192Y844483D01*
X263358Y844817D01*
X263400Y845192D01*
X263358Y845525D01*
X263150Y845858D01*
X262900Y846067D01*
X262650Y846108D01*
X262358Y846025D01*
X262150Y845733D01*
X262067Y845442D01*
Y845067D01*
G01Y845442D02*
X261942Y845692D01*
X261733Y845900D01*
X261483Y845983D01*
X261233Y845900D01*
X261025Y845692D01*
X260900Y845317D01*
X260942Y844942D01*
X261108Y844567D01*
G01X263025Y847333D02*
X263233Y847583D01*
X263358Y847875D01*
X263400Y848250D01*
X263317Y848625D01*
X263150Y848917D01*
X262858Y849125D01*
X262525Y849167D01*
X262192Y849083D01*
X261983Y848875D01*
X261817Y848583D01*
X261775Y848292D01*
X261817Y848000D01*
X261983Y847625D01*
X260900Y847750D01*
Y848875D01*
G01X263025Y850433D02*
X263233Y850683D01*
X263358Y850975D01*
X263400Y851350D01*
X263317Y851725D01*
X263150Y852017D01*
X262858Y852225D01*
X262525Y852267D01*
X262192Y852183D01*
X261983Y851975D01*
X261817Y851683D01*
X261775Y851392D01*
X261817Y851100D01*
X261983Y850725D01*
X260900Y850850D01*
Y851975D01*
G01X295517Y124500D02*
Y127000D01*
X296517D01*
X296850Y126875D01*
X297100Y126583D01*
X297183Y126250D01*
X297100Y125917D01*
X296892Y125667D01*
X296517Y125542D01*
X295517D01*
G01X298617Y124500D02*
Y127000D01*
X299658D01*
X299992Y126875D01*
X300200Y126708D01*
X300283Y126375D01*
X300200Y126042D01*
X299950Y125833D01*
X299658Y125708D01*
X298617D01*
G01X299658D02*
X300283Y124500D01*
G01X301758Y126583D02*
X302008Y126833D01*
X302300Y126958D01*
X302633Y127000D01*
X303050Y126917D01*
X303342Y126708D01*
X303425Y126458D01*
X303383Y126208D01*
X303217Y126000D01*
X302383Y125583D01*
X302008Y125292D01*
X301758Y124875D01*
X301675Y124500D01*
X303425D01*
G01X305567D02*
X305650Y125042D01*
X305775Y125500D01*
X305942Y125917D01*
X306150Y126375D01*
X306483Y127000D01*
X304817D01*
G01X275200Y124000D02*
Y128000D01*
X267800D01*
G01X296100Y129817D02*
X293600D01*
Y130817D01*
X293725Y131150D01*
X294017Y131400D01*
X294350Y131483D01*
X294683Y131400D01*
X294933Y131192D01*
X295058Y130817D01*
Y129817D01*
G01X296100Y132917D02*
X293600D01*
Y133958D01*
X293725Y134292D01*
X293892Y134500D01*
X294225Y134583D01*
X294558Y134500D01*
X294767Y134250D01*
X294892Y133958D01*
Y132917D01*
G01Y133958D02*
X296100Y134583D01*
G01Y136850D02*
X293600D01*
X294100Y136350D01*
G01X296100D02*
Y137350D01*
G01Y139950D02*
X296058Y140242D01*
X295933Y140575D01*
X295725Y140783D01*
X295433Y140867D01*
X295142Y140783D01*
X294892Y140533D01*
X294767Y140158D01*
Y139742D01*
X294683Y139492D01*
X294475Y139283D01*
X294183Y139200D01*
X293892Y139325D01*
X293683Y139617D01*
X293600Y139950D01*
X293683Y140283D01*
X293892Y140575D01*
X294183Y140700D01*
X294475Y140617D01*
X294683Y140408D01*
X294767Y140158D01*
Y139742D01*
X294892Y139367D01*
X295142Y139117D01*
X295433Y139033D01*
X295725Y139117D01*
X295933Y139325D01*
X296058Y139658D01*
X296100Y139950D01*
G01X279500Y131800D02*
X283500D01*
Y139200D01*
G01X275800Y128000D02*
Y124000D01*
X283200D01*
G01X289100Y129717D02*
X286600D01*
Y130717D01*
X286725Y131050D01*
X287017Y131300D01*
X287350Y131383D01*
X287683Y131300D01*
X287933Y131092D01*
X288058Y130717D01*
Y129717D01*
G01X289100Y132817D02*
X286600D01*
Y133858D01*
X286725Y134192D01*
X286892Y134400D01*
X287225Y134483D01*
X287558Y134400D01*
X287767Y134150D01*
X287892Y133858D01*
Y132817D01*
G01Y133858D02*
X289100Y134483D01*
G01X287017Y135958D02*
X286767Y136208D01*
X286642Y136500D01*
X286600Y136833D01*
X286683Y137250D01*
X286892Y137542D01*
X287142Y137625D01*
X287392Y137583D01*
X287600Y137417D01*
X288017Y136583D01*
X288308Y136208D01*
X288725Y135958D01*
X289100Y135875D01*
Y137625D01*
G01Y140350D02*
X286600D01*
X288392Y138808D01*
Y140892D01*
G01X279500Y139200D02*
X275500D01*
Y131800D01*
G01X272343Y150031D02*
X274343D01*
G01X272343Y159874D02*
X275343D01*
G01X273350Y161000D02*
Y166000D01*
X268350D01*
G01X309700Y152500D02*
X274300D01*
Y180500D01*
X309700D01*
Y152500D01*
G01X292557Y147350D02*
Y149850D01*
X293557D01*
X293890Y149725D01*
X294140Y149433D01*
X294223Y149100D01*
X294140Y148767D01*
X293932Y148517D01*
X293557Y148392D01*
X292557D01*
G01X295657Y147350D02*
Y149850D01*
X296698D01*
X297032Y149725D01*
X297240Y149558D01*
X297323Y149225D01*
X297240Y148892D01*
X296990Y148683D01*
X296698Y148558D01*
X295657D01*
G01X296698D02*
X297323Y147350D01*
G01X298673Y147850D02*
X298923Y147558D01*
X299257Y147392D01*
X299632Y147350D01*
X299965Y147392D01*
X300298Y147600D01*
X300507Y147850D01*
X300548Y148100D01*
X300465Y148392D01*
X300173Y148600D01*
X299882Y148683D01*
X299507D01*
G01X299882D02*
X300132Y148808D01*
X300340Y149017D01*
X300423Y149267D01*
X300340Y149517D01*
X300132Y149725D01*
X299757Y149850D01*
X299382Y149808D01*
X299007Y149642D01*
G01X301898Y148392D02*
X302190Y148683D01*
X302440Y148850D01*
X302773Y148933D01*
X303065Y148850D01*
X303273Y148683D01*
X303440Y148433D01*
X303482Y148142D01*
X303440Y147892D01*
X303273Y147642D01*
X303023Y147433D01*
X302732Y147350D01*
X302398Y147433D01*
X302107Y147683D01*
X301940Y148058D01*
X301898Y148475D01*
X301982Y149017D01*
X302107Y149308D01*
X302315Y149600D01*
X302607Y149808D01*
X302898Y149850D01*
X303190Y149767D01*
X303398Y149558D01*
G01X283340Y151350D02*
Y147350D01*
X290740D01*
G01X285017Y143500D02*
Y146000D01*
X286017D01*
X286350Y145875D01*
X286600Y145583D01*
X286683Y145250D01*
X286600Y144917D01*
X286392Y144667D01*
X286017Y144542D01*
X285017D01*
G01X288117Y143500D02*
Y146000D01*
X289158D01*
X289492Y145875D01*
X289700Y145708D01*
X289783Y145375D01*
X289700Y145042D01*
X289450Y144833D01*
X289158Y144708D01*
X288117D01*
G01X289158D02*
X289783Y143500D01*
G01X291258Y145583D02*
X291508Y145833D01*
X291800Y145958D01*
X292133Y146000D01*
X292550Y145917D01*
X292842Y145708D01*
X292925Y145458D01*
X292883Y145208D01*
X292717Y145000D01*
X291883Y144583D01*
X291508Y144292D01*
X291258Y143875D01*
X291175Y143500D01*
X292925D01*
G01X294233Y143875D02*
X294483Y143667D01*
X294775Y143542D01*
X295150Y143500D01*
X295525Y143583D01*
X295817Y143750D01*
X296025Y144042D01*
X296067Y144375D01*
X295983Y144708D01*
X295775Y144917D01*
X295483Y145083D01*
X295192Y145125D01*
X294900Y145083D01*
X294525Y144917D01*
X294650Y146000D01*
X295775D01*
G01X275800Y147500D02*
Y143500D01*
X283200D01*
G01X276067Y182500D02*
Y185000D01*
X277067D01*
X277400Y184875D01*
X277650Y184583D01*
X277733Y184250D01*
X277650Y183917D01*
X277442Y183667D01*
X277067Y183542D01*
X276067D01*
G01X279167Y185000D02*
Y182500D01*
X280833D01*
G01X282183Y183000D02*
X282433Y182708D01*
X282767Y182542D01*
X283142Y182500D01*
X283475Y182542D01*
X283808Y182750D01*
X284017Y183000D01*
X284058Y183250D01*
X283975Y183542D01*
X283683Y183750D01*
X283392Y183833D01*
X283017D01*
G01X283392D02*
X283642Y183958D01*
X283850Y184167D01*
X283933Y184417D01*
X283850Y184667D01*
X283642Y184875D01*
X283267Y185000D01*
X282892Y184958D01*
X282517Y184792D01*
G01X275472Y200803D02*
X272972D01*
Y201844D01*
X273097Y202178D01*
X273264Y202386D01*
X273597Y202469D01*
X273930Y202386D01*
X274139Y202136D01*
X274264Y201844D01*
Y200803D01*
G01Y201844D02*
X275472Y202469D01*
G01X275180Y204028D02*
X275389Y204319D01*
X275472Y204653D01*
X275389Y204986D01*
X275139Y205278D01*
X274764Y205486D01*
X274389Y205569D01*
X273930D01*
X273555Y205486D01*
X273222Y205278D01*
X273055Y205028D01*
X272972Y204736D01*
X273055Y204403D01*
X273222Y204153D01*
X273472Y203986D01*
X273805Y203903D01*
X274097Y203986D01*
X274389Y204194D01*
X274555Y204444D01*
X274597Y204736D01*
X274514Y205069D01*
X274305Y205319D01*
X273930Y205569D01*
G01X274430Y207044D02*
X274139Y207336D01*
X273972Y207586D01*
X273889Y207919D01*
X273972Y208211D01*
X274139Y208419D01*
X274389Y208586D01*
X274680Y208628D01*
X274930Y208586D01*
X275180Y208419D01*
X275389Y208169D01*
X275472Y207878D01*
X275389Y207544D01*
X275139Y207253D01*
X274764Y207086D01*
X274347Y207044D01*
X273805Y207128D01*
X273514Y207253D01*
X273222Y207461D01*
X273014Y207753D01*
X272972Y208044D01*
X273055Y208336D01*
X273264Y208544D01*
G01X272972Y210936D02*
X273055Y210603D01*
X273264Y210353D01*
X273514Y210186D01*
X273847Y210061D01*
X274222Y210019D01*
X274597Y210061D01*
X274930Y210186D01*
X275180Y210353D01*
X275389Y210603D01*
X275472Y210936D01*
X275389Y211269D01*
X275180Y211519D01*
X274930Y211686D01*
X274597Y211811D01*
X274222Y211853D01*
X273847Y211811D01*
X273514Y211686D01*
X273264Y211519D01*
X273055Y211269D01*
X272972Y210936D01*
G01X279100Y203100D02*
X283100D01*
Y210500D01*
G01X295217Y195967D02*
X295425Y195717D01*
X295675Y195550D01*
X295967Y195467D01*
X296300Y195550D01*
X296550Y195717D01*
X296800Y195967D01*
X296883Y196300D01*
Y197967D01*
G01X298317Y195467D02*
Y197967D01*
X299317D01*
X299650Y197842D01*
X299900Y197550D01*
X299983Y197217D01*
X299900Y196884D01*
X299692Y196634D01*
X299317Y196509D01*
X298317D01*
G01X302250Y195467D02*
Y197967D01*
X301750Y197467D01*
G01Y195467D02*
X302750D01*
G01X304433Y195967D02*
X304683Y195675D01*
X305017Y195509D01*
X305392Y195467D01*
X305725Y195509D01*
X306058Y195717D01*
X306267Y195967D01*
X306308Y196217D01*
X306225Y196509D01*
X305933Y196717D01*
X305642Y196800D01*
X305267D01*
G01X305642D02*
X305892Y196925D01*
X306100Y197134D01*
X306183Y197384D01*
X306100Y197634D01*
X305892Y197842D01*
X305517Y197967D01*
X305142Y197925D01*
X304767Y197759D01*
G01X287200Y201300D02*
X317800D01*
Y213100D01*
X287200D01*
Y201300D01*
G01X293150Y230800D02*
X293817Y230383D01*
X294567Y230133D01*
X295233D01*
X295900Y230383D01*
X296400Y230800D01*
X296650Y231383D01*
X296483Y231966D01*
X296067Y232466D01*
X295317Y232800D01*
X294317Y232966D01*
X293733Y233300D01*
X293483Y233883D01*
X293650Y234466D01*
X294067Y234883D01*
X294650Y235133D01*
X295233D01*
X295817Y234966D01*
X296317Y234550D01*
G01X302167Y230133D02*
X298833D01*
Y235133D01*
X302167D01*
G01X300833Y232716D02*
X298833D01*
G01X307933Y234716D02*
X307433Y234966D01*
X306850Y235133D01*
X306183D01*
X305433Y234883D01*
X304850Y234466D01*
X304433Y233966D01*
X304100Y233133D01*
X304017Y232383D01*
X304183Y231633D01*
X304433Y231133D01*
X304933Y230633D01*
X305517Y230300D01*
X306100Y230133D01*
X306683D01*
X307267Y230300D01*
X307767Y230550D01*
X308183Y230883D01*
G01X309867Y235133D02*
Y231550D01*
X310200Y230800D01*
X310867Y230300D01*
X311700Y230133D01*
X312533Y230300D01*
X313200Y230800D01*
X313533Y231550D01*
Y235133D01*
G01X315633Y230133D02*
Y235133D01*
X317717D01*
X318383Y234883D01*
X318800Y234550D01*
X318967Y233883D01*
X318800Y233216D01*
X318300Y232800D01*
X317717Y232550D01*
X315633D01*
G01X317717D02*
X318967Y230133D01*
G01X324567D02*
X321233D01*
Y235133D01*
X324567D01*
G01X323233Y232716D02*
X321233D01*
G01X332517Y230133D02*
Y235133D01*
X335683D01*
G01X334517Y232716D02*
X332517D01*
G01X338033Y235133D02*
Y230133D01*
X341367D01*
G01X343217D02*
X345300Y235133D01*
X347383Y230133D01*
G01X346633Y231883D02*
X343967D01*
G01X349150Y230800D02*
X349817Y230383D01*
X350567Y230133D01*
X351233D01*
X351900Y230383D01*
X352400Y230800D01*
X352650Y231383D01*
X352483Y231966D01*
X352067Y232466D01*
X351317Y232800D01*
X350317Y232966D01*
X349733Y233300D01*
X349483Y233883D01*
X349650Y234466D01*
X350067Y234883D01*
X350650Y235133D01*
X351233D01*
X351817Y234966D01*
X352317Y234550D01*
G01X354750Y230133D02*
Y235133D01*
G01X358250D02*
Y230133D01*
G01Y232633D02*
X354750D01*
G01X293217Y216000D02*
X293425Y215750D01*
X293675Y215583D01*
X293967Y215500D01*
X294300Y215583D01*
X294550Y215750D01*
X294800Y216000D01*
X294883Y216333D01*
Y218000D01*
G01X296317Y215500D02*
Y218000D01*
X297317D01*
X297650Y217875D01*
X297900Y217583D01*
X297983Y217250D01*
X297900Y216917D01*
X297692Y216667D01*
X297317Y216542D01*
X296317D01*
G01X300250Y215500D02*
Y218000D01*
X299750Y217500D01*
G01Y215500D02*
X300750D01*
G01X302433Y216000D02*
X302683Y215708D01*
X303017Y215542D01*
X303392Y215500D01*
X303725Y215542D01*
X304058Y215750D01*
X304267Y216000D01*
X304308Y216250D01*
X304225Y216542D01*
X303933Y216750D01*
X303642Y216833D01*
X303267D01*
G01X303642D02*
X303892Y216958D01*
X304100Y217167D01*
X304183Y217417D01*
X304100Y217667D01*
X303892Y217875D01*
X303517Y218000D01*
X303142Y217958D01*
X302767Y217792D01*
G01X289234Y239011D02*
X351434D01*
Y289411D01*
X289234D01*
Y239011D01*
G01X284781Y268580D02*
X280181Y263980D01*
X284831Y259330D01*
G01X273761Y264280D02*
X275731Y266250D01*
G01Y262310D02*
X273761Y264280D01*
G01X275731Y276980D02*
Y251580D01*
G01X279766Y302317D02*
X277266D01*
Y303358D01*
X277391Y303692D01*
X277558Y303900D01*
X277891Y303983D01*
X278224Y303900D01*
X278433Y303650D01*
X278558Y303358D01*
Y302317D01*
G01Y303358D02*
X279766Y303983D01*
G01X277683Y305458D02*
X277433Y305708D01*
X277308Y306000D01*
X277266Y306333D01*
X277349Y306750D01*
X277558Y307042D01*
X277808Y307125D01*
X278058Y307083D01*
X278266Y306917D01*
X278683Y306083D01*
X278974Y305708D01*
X279391Y305458D01*
X279766Y305375D01*
Y307125D01*
G01X278724Y308558D02*
X278433Y308850D01*
X278266Y309100D01*
X278183Y309433D01*
X278266Y309725D01*
X278433Y309933D01*
X278683Y310100D01*
X278974Y310142D01*
X279224Y310100D01*
X279474Y309933D01*
X279683Y309683D01*
X279766Y309392D01*
X279683Y309058D01*
X279433Y308767D01*
X279058Y308600D01*
X278641Y308558D01*
X278099Y308642D01*
X277808Y308767D01*
X277516Y308975D01*
X277308Y309267D01*
X277266Y309558D01*
X277349Y309850D01*
X277558Y310058D01*
G01X278724Y311658D02*
X278433Y311950D01*
X278266Y312200D01*
X278183Y312533D01*
X278266Y312825D01*
X278433Y313033D01*
X278683Y313200D01*
X278974Y313242D01*
X279224Y313200D01*
X279474Y313033D01*
X279683Y312783D01*
X279766Y312492D01*
X279683Y312158D01*
X279433Y311867D01*
X279058Y311700D01*
X278641Y311658D01*
X278099Y311742D01*
X277808Y311867D01*
X277516Y312075D01*
X277308Y312367D01*
X277266Y312658D01*
X277349Y312950D01*
X277558Y313158D01*
G01X274900Y298700D02*
X270900D01*
Y291300D01*
G01X298564Y290697D02*
X296064D01*
Y291738D01*
X296189Y292072D01*
X296356Y292280D01*
X296689Y292363D01*
X297022Y292280D01*
X297231Y292030D01*
X297356Y291738D01*
Y290697D01*
G01Y291738D02*
X298564Y292363D01*
G01Y294547D02*
X298022Y294630D01*
X297564Y294755D01*
X297147Y294922D01*
X296689Y295130D01*
X296064Y295463D01*
Y293797D01*
G01X298564Y298230D02*
X296064D01*
X297856Y296688D01*
Y298772D01*
G01X296064Y300830D02*
X296147Y300497D01*
X296356Y300247D01*
X296606Y300080D01*
X296939Y299955D01*
X297314Y299913D01*
X297689Y299955D01*
X298022Y300080D01*
X298272Y300247D01*
X298481Y300497D01*
X298564Y300830D01*
X298481Y301163D01*
X298272Y301413D01*
X298022Y301580D01*
X297689Y301705D01*
X297314Y301747D01*
X296939Y301705D01*
X296606Y301580D01*
X296356Y301413D01*
X296147Y301163D01*
X296064Y300830D01*
G01X269866Y302417D02*
X267366D01*
Y303458D01*
X267491Y303792D01*
X267658Y304000D01*
X267991Y304083D01*
X268324Y304000D01*
X268533Y303750D01*
X268658Y303458D01*
Y302417D01*
G01Y303458D02*
X269866Y304083D01*
G01X269574Y305642D02*
X269783Y305933D01*
X269866Y306267D01*
X269783Y306600D01*
X269533Y306892D01*
X269158Y307100D01*
X268783Y307183D01*
X268324D01*
X267949Y307100D01*
X267616Y306892D01*
X267449Y306642D01*
X267366Y306350D01*
X267449Y306017D01*
X267616Y305767D01*
X267866Y305600D01*
X268199Y305517D01*
X268491Y305600D01*
X268783Y305808D01*
X268949Y306058D01*
X268991Y306350D01*
X268908Y306683D01*
X268699Y306933D01*
X268324Y307183D01*
G01X268824Y308658D02*
X268533Y308950D01*
X268366Y309200D01*
X268283Y309533D01*
X268366Y309825D01*
X268533Y310033D01*
X268783Y310200D01*
X269074Y310242D01*
X269324Y310200D01*
X269574Y310033D01*
X269783Y309783D01*
X269866Y309492D01*
X269783Y309158D01*
X269533Y308867D01*
X269158Y308700D01*
X268741Y308658D01*
X268199Y308742D01*
X267908Y308867D01*
X267616Y309075D01*
X267408Y309367D01*
X267366Y309658D01*
X267449Y309950D01*
X267658Y310158D01*
G01X269366Y311633D02*
X269658Y311883D01*
X269824Y312217D01*
X269866Y312592D01*
X269824Y312925D01*
X269616Y313258D01*
X269366Y313467D01*
X269116Y313508D01*
X268824Y313425D01*
X268616Y313133D01*
X268533Y312842D01*
Y312467D01*
G01Y312842D02*
X268408Y313092D01*
X268199Y313300D01*
X267949Y313383D01*
X267699Y313300D01*
X267491Y313092D01*
X267366Y312717D01*
X267408Y312342D01*
X267574Y311967D01*
G01X298417Y304276D02*
Y306776D01*
X299458D01*
X299792Y306651D01*
X300000Y306484D01*
X300083Y306151D01*
X300000Y305818D01*
X299750Y305609D01*
X299458Y305484D01*
X298417D01*
G01X299458D02*
X300083Y304276D01*
G01X301642Y304568D02*
X301933Y304359D01*
X302267Y304276D01*
X302600Y304359D01*
X302892Y304609D01*
X303100Y304984D01*
X303183Y305359D01*
Y305818D01*
X303100Y306193D01*
X302892Y306526D01*
X302642Y306693D01*
X302350Y306776D01*
X302017Y306693D01*
X301767Y306526D01*
X301600Y306276D01*
X301517Y305943D01*
X301600Y305651D01*
X301808Y305359D01*
X302058Y305193D01*
X302350Y305151D01*
X302683Y305234D01*
X302933Y305443D01*
X303183Y305818D01*
G01X304658Y305318D02*
X304950Y305609D01*
X305200Y305776D01*
X305533Y305859D01*
X305825Y305776D01*
X306033Y305609D01*
X306200Y305359D01*
X306242Y305068D01*
X306200Y304818D01*
X306033Y304568D01*
X305783Y304359D01*
X305492Y304276D01*
X305158Y304359D01*
X304867Y304609D01*
X304700Y304984D01*
X304658Y305401D01*
X304742Y305943D01*
X304867Y306234D01*
X305075Y306526D01*
X305367Y306734D01*
X305658Y306776D01*
X305950Y306693D01*
X306158Y306484D01*
G01X307758Y306359D02*
X308008Y306609D01*
X308300Y306734D01*
X308633Y306776D01*
X309050Y306693D01*
X309342Y306484D01*
X309425Y306234D01*
X309383Y305984D01*
X309217Y305776D01*
X308383Y305359D01*
X308008Y305068D01*
X307758Y304651D01*
X307675Y304276D01*
X309425D01*
G01X271874Y304067D02*
X271749Y303817D01*
X271666Y303525D01*
Y303192D01*
X271791Y302817D01*
X271999Y302525D01*
X272249Y302317D01*
X272666Y302150D01*
X273041Y302108D01*
X273416Y302192D01*
X273666Y302317D01*
X273916Y302567D01*
X274083Y302858D01*
X274166Y303150D01*
Y303442D01*
X274083Y303733D01*
X273958Y303983D01*
X273791Y304192D01*
G01X274166Y306250D02*
X271666D01*
X272166Y305750D01*
G01X274166D02*
Y306750D01*
G01Y309350D02*
X274124Y309642D01*
X273999Y309975D01*
X273791Y310183D01*
X273499Y310267D01*
X273208Y310183D01*
X272958Y309933D01*
X272833Y309558D01*
Y309142D01*
X272749Y308892D01*
X272541Y308683D01*
X272249Y308600D01*
X271958Y308725D01*
X271749Y309017D01*
X271666Y309350D01*
X271749Y309683D01*
X271958Y309975D01*
X272249Y310100D01*
X272541Y310017D01*
X272749Y309808D01*
X272833Y309558D01*
Y309142D01*
X272958Y308767D01*
X273208Y308517D01*
X273499Y308433D01*
X273791Y308517D01*
X273999Y308725D01*
X274124Y309058D01*
X274166Y309350D01*
G01X273124Y311658D02*
X272833Y311950D01*
X272666Y312200D01*
X272583Y312533D01*
X272666Y312825D01*
X272833Y313033D01*
X273083Y313200D01*
X273374Y313242D01*
X273624Y313200D01*
X273874Y313033D01*
X274083Y312783D01*
X274166Y312492D01*
X274083Y312158D01*
X273833Y311867D01*
X273458Y311700D01*
X273041Y311658D01*
X272499Y311742D01*
X272208Y311867D01*
X271916Y312075D01*
X271708Y312367D01*
X271666Y312658D01*
X271749Y312950D01*
X271958Y313158D01*
G01X299334Y313517D02*
X296834D01*
Y314558D01*
X296959Y314892D01*
X297126Y315100D01*
X297459Y315183D01*
X297792Y315100D01*
X298001Y314850D01*
X298126Y314558D01*
Y313517D01*
G01Y314558D02*
X299334Y315183D01*
G01Y317950D02*
X296834D01*
X298626Y316408D01*
Y318492D01*
G01X299334Y320550D02*
X299292Y320842D01*
X299167Y321175D01*
X298959Y321383D01*
X298667Y321467D01*
X298376Y321383D01*
X298126Y321133D01*
X298001Y320758D01*
Y320342D01*
X297917Y320092D01*
X297709Y319883D01*
X297417Y319800D01*
X297126Y319925D01*
X296917Y320217D01*
X296834Y320550D01*
X296917Y320883D01*
X297126Y321175D01*
X297417Y321300D01*
X297709Y321217D01*
X297917Y321008D01*
X298001Y320758D01*
Y320342D01*
X298126Y319967D01*
X298376Y319717D01*
X298667Y319633D01*
X298959Y319717D01*
X299167Y319925D01*
X299292Y320258D01*
X299334Y320550D01*
G01X298959Y322733D02*
X299167Y322983D01*
X299292Y323275D01*
X299334Y323650D01*
X299251Y324025D01*
X299084Y324317D01*
X298792Y324525D01*
X298459Y324567D01*
X298126Y324483D01*
X297917Y324275D01*
X297751Y323983D01*
X297709Y323692D01*
X297751Y323400D01*
X297917Y323025D01*
X296834Y323150D01*
Y324275D01*
G01X301639Y338101D02*
X297639D01*
Y330701D01*
G01X276983Y325166D02*
Y323374D01*
X277150Y322999D01*
X277483Y322749D01*
X277900Y322666D01*
X278317Y322749D01*
X278650Y322999D01*
X278817Y323374D01*
Y325166D01*
G01X281500Y322666D02*
Y325166D01*
X279958Y323374D01*
X282042D01*
G01X284100Y322666D02*
Y325166D01*
X283600Y324666D01*
G01Y322666D02*
X284600D01*
G01X277629Y346940D02*
Y327740D01*
X288829D01*
Y346940D01*
X277629D01*
Y346540D01*
G01X278017Y363400D02*
Y365900D01*
X279058D01*
X279392Y365775D01*
X279600Y365608D01*
X279683Y365275D01*
X279600Y364942D01*
X279350Y364733D01*
X279058Y364608D01*
X278017D01*
G01X279058D02*
X279683Y363400D01*
G01X282450D02*
Y365900D01*
X280908Y364108D01*
X282992D01*
G01X284967Y363400D02*
X285050Y363942D01*
X285175Y364400D01*
X285342Y364817D01*
X285550Y365275D01*
X285883Y365900D01*
X284217D01*
G01X287442Y363692D02*
X287733Y363483D01*
X288067Y363400D01*
X288400Y363483D01*
X288692Y363733D01*
X288900Y364108D01*
X288983Y364483D01*
Y364942D01*
X288900Y365317D01*
X288692Y365650D01*
X288442Y365817D01*
X288150Y365900D01*
X287817Y365817D01*
X287567Y365650D01*
X287400Y365400D01*
X287317Y365067D01*
X287400Y364775D01*
X287608Y364483D01*
X287858Y364317D01*
X288150Y364275D01*
X288483Y364358D01*
X288733Y364567D01*
X288983Y364942D01*
G01X269229Y348140D02*
X295229D01*
G01D02*
Y361140D01*
G01D02*
X269229D01*
G01D02*
Y348140D01*
G01X301838Y369640D02*
X302046Y369973D01*
X302171Y370348D01*
Y370682D01*
X302046Y371015D01*
X301838Y371265D01*
X301546Y371390D01*
X301254Y371307D01*
X301004Y371098D01*
X300838Y370723D01*
X300754Y370223D01*
X300588Y369932D01*
X300296Y369807D01*
X300004Y369890D01*
X299796Y370098D01*
X299671Y370390D01*
Y370682D01*
X299754Y370973D01*
X299963Y371223D01*
G01X302171Y372782D02*
X299671D01*
Y373823D01*
X299796Y374157D01*
X299963Y374365D01*
X300296Y374448D01*
X300629Y374365D01*
X300838Y374115D01*
X300963Y373823D01*
Y372782D01*
G01Y373823D02*
X302171Y374448D01*
G01Y376632D02*
X301629Y376715D01*
X301171Y376840D01*
X300754Y377007D01*
X300296Y377215D01*
X299671Y377548D01*
Y375882D01*
G01Y379815D02*
X299754Y379482D01*
X299963Y379232D01*
X300213Y379065D01*
X300546Y378940D01*
X300921Y378898D01*
X301296Y378940D01*
X301629Y379065D01*
X301879Y379232D01*
X302088Y379482D01*
X302171Y379815D01*
X302088Y380148D01*
X301879Y380398D01*
X301629Y380565D01*
X301296Y380690D01*
X300921Y380732D01*
X300546Y380690D01*
X300213Y380565D01*
X299963Y380398D01*
X299754Y380148D01*
X299671Y379815D01*
G01X302171Y382832D02*
X301629Y382915D01*
X301171Y383040D01*
X300754Y383207D01*
X300296Y383415D01*
X299671Y383748D01*
Y382082D01*
G01X299929Y353040D02*
X303929D01*
Y360440D01*
G01X295679Y372882D02*
X295554Y372632D01*
X295471Y372340D01*
Y372007D01*
X295596Y371632D01*
X295804Y371340D01*
X296054Y371132D01*
X296471Y370965D01*
X296846Y370923D01*
X297221Y371007D01*
X297471Y371132D01*
X297721Y371382D01*
X297888Y371673D01*
X297971Y371965D01*
Y372257D01*
X297888Y372548D01*
X297763Y372798D01*
X297596Y373007D01*
G01X295888Y374273D02*
X295638Y374523D01*
X295513Y374815D01*
X295471Y375148D01*
X295554Y375565D01*
X295763Y375857D01*
X296013Y375940D01*
X296263Y375898D01*
X296471Y375732D01*
X296888Y374898D01*
X297179Y374523D01*
X297596Y374273D01*
X297971Y374190D01*
Y375940D01*
G01X296929Y377373D02*
X296638Y377665D01*
X296471Y377915D01*
X296388Y378248D01*
X296471Y378540D01*
X296638Y378748D01*
X296888Y378915D01*
X297179Y378957D01*
X297429Y378915D01*
X297679Y378748D01*
X297888Y378498D01*
X297971Y378207D01*
X297888Y377873D01*
X297638Y377582D01*
X297263Y377415D01*
X296846Y377373D01*
X296304Y377457D01*
X296013Y377582D01*
X295721Y377790D01*
X295513Y378082D01*
X295471Y378373D01*
X295554Y378665D01*
X295763Y378873D01*
G01X297471Y380348D02*
X297763Y380598D01*
X297929Y380932D01*
X297971Y381307D01*
X297929Y381640D01*
X297721Y381973D01*
X297471Y382182D01*
X297221Y382223D01*
X296929Y382140D01*
X296721Y381848D01*
X296638Y381557D01*
Y381182D01*
G01Y381557D02*
X296513Y381807D01*
X296304Y382015D01*
X296054Y382098D01*
X295804Y382015D01*
X295596Y381807D01*
X295471Y381432D01*
X295513Y381057D01*
X295679Y380682D01*
G01X285229Y346840D02*
X283429Y344740D01*
X281229Y346840D01*
G01X271700Y424217D02*
X269200D01*
Y425258D01*
X269325Y425592D01*
X269492Y425800D01*
X269825Y425883D01*
X270158Y425800D01*
X270367Y425550D01*
X270492Y425258D01*
Y424217D01*
G01Y425258D02*
X271700Y425883D01*
G01X271200Y427233D02*
X271492Y427483D01*
X271658Y427817D01*
X271700Y428192D01*
X271658Y428525D01*
X271450Y428858D01*
X271200Y429067D01*
X270950Y429108D01*
X270658Y429025D01*
X270450Y428733D01*
X270367Y428442D01*
Y428067D01*
G01Y428442D02*
X270242Y428692D01*
X270033Y428900D01*
X269783Y428983D01*
X269533Y428900D01*
X269325Y428692D01*
X269200Y428317D01*
X269242Y427942D01*
X269408Y427567D01*
G01X271700Y431250D02*
X269200D01*
X269700Y430750D01*
G01X271700D02*
Y431750D01*
G01X269617Y433558D02*
X269367Y433808D01*
X269242Y434100D01*
X269200Y434433D01*
X269283Y434850D01*
X269492Y435142D01*
X269742Y435225D01*
X269992Y435183D01*
X270200Y435017D01*
X270617Y434183D01*
X270908Y433808D01*
X271325Y433558D01*
X271700Y433475D01*
Y435225D01*
G01X274800Y469600D02*
Y483000D01*
G01X288244Y462450D02*
Y460658D01*
X288411Y460283D01*
X288744Y460033D01*
X289161Y459950D01*
X289578Y460033D01*
X289911Y460283D01*
X290078Y460658D01*
Y462450D01*
G01X291344Y460325D02*
X291594Y460117D01*
X291886Y459992D01*
X292261Y459950D01*
X292636Y460033D01*
X292928Y460200D01*
X293136Y460492D01*
X293178Y460825D01*
X293094Y461158D01*
X292886Y461367D01*
X292594Y461533D01*
X292303Y461575D01*
X292011Y461533D01*
X291636Y461367D01*
X291761Y462450D01*
X292886D01*
G01X294444Y460450D02*
X294694Y460158D01*
X295028Y459992D01*
X295403Y459950D01*
X295736Y459992D01*
X296069Y460200D01*
X296278Y460450D01*
X296319Y460700D01*
X296236Y460992D01*
X295944Y461200D01*
X295653Y461283D01*
X295278D01*
G01X295653D02*
X295903Y461408D01*
X296111Y461617D01*
X296194Y461867D01*
X296111Y462117D01*
X295903Y462325D01*
X295528Y462450D01*
X295153Y462408D01*
X294778Y462242D01*
G01X287562Y477800D02*
X300962D01*
G01X287562Y467800D02*
Y477800D01*
G01X300962Y467800D02*
X287562D01*
G01X279409Y462867D02*
X276909D01*
Y463908D01*
X277034Y464242D01*
X277201Y464450D01*
X277534Y464533D01*
X277867Y464450D01*
X278076Y464200D01*
X278201Y463908D01*
Y462867D01*
G01Y463908D02*
X279409Y464533D01*
G01X277326Y466008D02*
X277076Y466258D01*
X276951Y466550D01*
X276909Y466883D01*
X276992Y467300D01*
X277201Y467592D01*
X277451Y467675D01*
X277701Y467633D01*
X277909Y467467D01*
X278326Y466633D01*
X278617Y466258D01*
X279034Y466008D01*
X279409Y465925D01*
Y467675D01*
G01X277326Y469108D02*
X277076Y469358D01*
X276951Y469650D01*
X276909Y469983D01*
X276992Y470400D01*
X277201Y470692D01*
X277451Y470775D01*
X277701Y470733D01*
X277909Y470567D01*
X278326Y469733D01*
X278617Y469358D01*
X279034Y469108D01*
X279409Y469025D01*
Y470775D01*
G01X276100Y472600D02*
X280100D01*
Y480000D01*
G01X274800Y465300D02*
Y469300D01*
X267400D01*
G01X273717Y446300D02*
Y448800D01*
X274758D01*
X275092Y448675D01*
X275300Y448508D01*
X275383Y448175D01*
X275300Y447842D01*
X275050Y447633D01*
X274758Y447508D01*
X273717D01*
G01X274758D02*
X275383Y446300D01*
G01X278150D02*
Y448800D01*
X276608Y447008D01*
X278692D01*
G01X279833Y446800D02*
X280083Y446508D01*
X280417Y446342D01*
X280792Y446300D01*
X281125Y446342D01*
X281458Y446550D01*
X281667Y446800D01*
X281708Y447050D01*
X281625Y447342D01*
X281333Y447550D01*
X281042Y447633D01*
X280667D01*
G01X281042D02*
X281292Y447758D01*
X281500Y447967D01*
X281583Y448217D01*
X281500Y448467D01*
X281292Y448675D01*
X280917Y448800D01*
X280542Y448758D01*
X280167Y448592D01*
G01X283850Y446300D02*
X284142Y446342D01*
X284475Y446467D01*
X284683Y446675D01*
X284767Y446967D01*
X284683Y447258D01*
X284433Y447508D01*
X284058Y447633D01*
X283642D01*
X283392Y447717D01*
X283183Y447925D01*
X283100Y448217D01*
X283225Y448508D01*
X283517Y448717D01*
X283850Y448800D01*
X284183Y448717D01*
X284475Y448508D01*
X284600Y448217D01*
X284517Y447925D01*
X284308Y447717D01*
X284058Y447633D01*
X283642D01*
X283267Y447508D01*
X283017Y447258D01*
X282933Y446967D01*
X283017Y446675D01*
X283225Y446467D01*
X283558Y446342D01*
X283850Y446300D01*
G01X284000Y455617D02*
X281500D01*
Y456658D01*
X281625Y456992D01*
X281792Y457200D01*
X282125Y457283D01*
X282458Y457200D01*
X282667Y456950D01*
X282792Y456658D01*
Y455617D01*
G01Y456658D02*
X284000Y457283D01*
G01X283625Y458633D02*
X283833Y458883D01*
X283958Y459175D01*
X284000Y459550D01*
X283917Y459925D01*
X283750Y460217D01*
X283458Y460425D01*
X283125Y460467D01*
X282792Y460383D01*
X282583Y460175D01*
X282417Y459883D01*
X282375Y459592D01*
X282417Y459300D01*
X282583Y458925D01*
X281500Y459050D01*
Y460175D01*
G01X282958Y461858D02*
X282667Y462150D01*
X282500Y462400D01*
X282417Y462733D01*
X282500Y463025D01*
X282667Y463233D01*
X282917Y463400D01*
X283208Y463442D01*
X283458Y463400D01*
X283708Y463233D01*
X283917Y462983D01*
X284000Y462692D01*
X283917Y462358D01*
X283667Y462067D01*
X283292Y461900D01*
X282875Y461858D01*
X282333Y461942D01*
X282042Y462067D01*
X281750Y462275D01*
X281542Y462567D01*
X281500Y462858D01*
X281583Y463150D01*
X281792Y463358D01*
G01X284000Y465667D02*
X283458Y465750D01*
X283000Y465875D01*
X282583Y466042D01*
X282125Y466250D01*
X281500Y466583D01*
Y464917D01*
G01X282200Y469100D02*
X286200D01*
Y476500D01*
G01X290567Y455892D02*
X290317Y456017D01*
X290025Y456100D01*
X289692D01*
X289317Y455975D01*
X289025Y455767D01*
X288817Y455517D01*
X288650Y455100D01*
X288608Y454725D01*
X288692Y454350D01*
X288817Y454100D01*
X289067Y453850D01*
X289358Y453683D01*
X289650Y453600D01*
X289942D01*
X290233Y453683D01*
X290483Y453808D01*
X290692Y453975D01*
G01X291958Y455683D02*
X292208Y455933D01*
X292500Y456058D01*
X292833Y456100D01*
X293250Y456017D01*
X293542Y455808D01*
X293625Y455558D01*
X293583Y455308D01*
X293417Y455100D01*
X292583Y454683D01*
X292208Y454392D01*
X291958Y453975D01*
X291875Y453600D01*
X293625D01*
G01X295850D02*
X296142Y453642D01*
X296475Y453767D01*
X296683Y453975D01*
X296767Y454267D01*
X296683Y454558D01*
X296433Y454808D01*
X296058Y454933D01*
X295642D01*
X295392Y455017D01*
X295183Y455225D01*
X295100Y455517D01*
X295225Y455808D01*
X295517Y456017D01*
X295850Y456100D01*
X296183Y456017D01*
X296475Y455808D01*
X296600Y455517D01*
X296517Y455225D01*
X296308Y455017D01*
X296058Y454933D01*
X295642D01*
X295267Y454808D01*
X295017Y454558D01*
X294933Y454267D01*
X295017Y453975D01*
X295225Y453767D01*
X295558Y453642D01*
X295850Y453600D01*
G01X298158Y455683D02*
X298408Y455933D01*
X298700Y456058D01*
X299033Y456100D01*
X299450Y456017D01*
X299742Y455808D01*
X299825Y455558D01*
X299783Y455308D01*
X299617Y455100D01*
X298783Y454683D01*
X298408Y454392D01*
X298158Y453975D01*
X298075Y453600D01*
X299825D01*
G01X288562Y480200D02*
Y493600D01*
G01X298562Y480200D02*
X288562D01*
G01X298562Y493600D02*
Y480200D01*
G01X288562Y493600D02*
X298562D01*
G01X274800Y483800D02*
Y487800D01*
X267400D01*
G01X280500Y489800D02*
X284500D01*
Y497200D01*
G01X290432Y508354D02*
Y506562D01*
X290599Y506187D01*
X290932Y505937D01*
X291349Y505854D01*
X291766Y505937D01*
X292099Y506187D01*
X292266Y506562D01*
Y508354D01*
G01X294949Y505854D02*
Y508354D01*
X293407Y506562D01*
X295491D01*
G01X296632Y506229D02*
X296882Y506021D01*
X297174Y505896D01*
X297549Y505854D01*
X297924Y505937D01*
X298216Y506104D01*
X298424Y506396D01*
X298466Y506729D01*
X298382Y507062D01*
X298174Y507271D01*
X297882Y507437D01*
X297591Y507479D01*
X297299Y507437D01*
X296924Y507271D01*
X297049Y508354D01*
X298174D01*
G01X279400Y493100D02*
Y504500D01*
G01Y505300D02*
Y516700D01*
G01X270435Y521705D02*
Y519913D01*
X270602Y519538D01*
X270935Y519288D01*
X271352Y519205D01*
X271769Y519288D01*
X272102Y519538D01*
X272269Y519913D01*
Y521705D01*
G01X274952Y519205D02*
Y521705D01*
X273410Y519913D01*
X275494D01*
G01X276844Y519497D02*
X277135Y519288D01*
X277469Y519205D01*
X277802Y519288D01*
X278094Y519538D01*
X278302Y519913D01*
X278385Y520288D01*
Y520747D01*
X278302Y521122D01*
X278094Y521455D01*
X277844Y521622D01*
X277552Y521705D01*
X277219Y521622D01*
X276969Y521455D01*
X276802Y521205D01*
X276719Y520872D01*
X276802Y520580D01*
X277010Y520288D01*
X277260Y520122D01*
X277552Y520080D01*
X277885Y520163D01*
X278135Y520372D01*
X278385Y520747D01*
G01X292288Y580165D02*
Y576165D01*
X299688D01*
G01X279088Y574865D02*
Y594065D01*
X267888D01*
Y574865D01*
X279088D01*
Y575265D01*
G01X271488Y574965D02*
X273288Y577065D01*
X275488Y574965D01*
G01X268223Y604561D02*
Y607061D01*
X269223D01*
X269556Y606936D01*
X269806Y606644D01*
X269889Y606311D01*
X269806Y605978D01*
X269598Y605728D01*
X269223Y605603D01*
X268223D01*
G01X273073Y606853D02*
X272823Y606978D01*
X272531Y607061D01*
X272198D01*
X271823Y606936D01*
X271531Y606728D01*
X271323Y606478D01*
X271156Y606061D01*
X271114Y605686D01*
X271198Y605311D01*
X271323Y605061D01*
X271573Y604811D01*
X271864Y604644D01*
X272156Y604561D01*
X272448D01*
X272739Y604644D01*
X272989Y604769D01*
X273198Y604936D01*
G01X275173Y604561D02*
X275256Y605103D01*
X275381Y605561D01*
X275548Y605978D01*
X275756Y606436D01*
X276089Y607061D01*
X274423D01*
G01X278356D02*
X278023Y606978D01*
X277773Y606769D01*
X277606Y606519D01*
X277481Y606186D01*
X277439Y605811D01*
X277481Y605436D01*
X277606Y605103D01*
X277773Y604853D01*
X278023Y604644D01*
X278356Y604561D01*
X278689Y604644D01*
X278939Y604853D01*
X279106Y605103D01*
X279231Y605436D01*
X279273Y605811D01*
X279231Y606186D01*
X279106Y606519D01*
X278939Y606769D01*
X278689Y606978D01*
X278356Y607061D01*
G01X268223Y608561D02*
Y611061D01*
X269223D01*
X269556Y610936D01*
X269806Y610644D01*
X269889Y610311D01*
X269806Y609978D01*
X269598Y609728D01*
X269223Y609603D01*
X268223D01*
G01X273073Y610853D02*
X272823Y610978D01*
X272531Y611061D01*
X272198D01*
X271823Y610936D01*
X271531Y610728D01*
X271323Y610478D01*
X271156Y610061D01*
X271114Y609686D01*
X271198Y609311D01*
X271323Y609061D01*
X271573Y608811D01*
X271864Y608644D01*
X272156Y608561D01*
X272448D01*
X272739Y608644D01*
X272989Y608769D01*
X273198Y608936D01*
G01X275173Y608561D02*
X275256Y609103D01*
X275381Y609561D01*
X275548Y609978D01*
X275756Y610436D01*
X276089Y611061D01*
X274423D01*
G01X277439Y608936D02*
X277689Y608728D01*
X277981Y608603D01*
X278356Y608561D01*
X278731Y608644D01*
X279023Y608811D01*
X279231Y609103D01*
X279273Y609436D01*
X279189Y609769D01*
X278981Y609978D01*
X278689Y610144D01*
X278398Y610186D01*
X278106Y610144D01*
X277731Y609978D01*
X277856Y611061D01*
X278981D01*
G01X268323Y612761D02*
Y615261D01*
X269323D01*
X269656Y615136D01*
X269906Y614844D01*
X269989Y614511D01*
X269906Y614178D01*
X269698Y613928D01*
X269323Y613803D01*
X268323D01*
G01X273173Y615053D02*
X272923Y615178D01*
X272631Y615261D01*
X272298D01*
X271923Y615136D01*
X271631Y614928D01*
X271423Y614678D01*
X271256Y614261D01*
X271214Y613886D01*
X271298Y613511D01*
X271423Y613261D01*
X271673Y613011D01*
X271964Y612844D01*
X272256Y612761D01*
X272548D01*
X272839Y612844D01*
X273089Y612969D01*
X273298Y613136D01*
G01X275356Y612761D02*
Y615261D01*
X274856Y614761D01*
G01Y612761D02*
X275856D01*
G01X277748Y613053D02*
X278039Y612844D01*
X278373Y612761D01*
X278706Y612844D01*
X278998Y613094D01*
X279206Y613469D01*
X279289Y613844D01*
Y614303D01*
X279206Y614678D01*
X278998Y615011D01*
X278748Y615178D01*
X278456Y615261D01*
X278123Y615178D01*
X277873Y615011D01*
X277706Y614761D01*
X277623Y614428D01*
X277706Y614136D01*
X277914Y613844D01*
X278164Y613678D01*
X278456Y613636D01*
X278789Y613719D01*
X279039Y613928D01*
X279289Y614303D01*
G01X292288Y585165D02*
Y581165D01*
X299688D01*
G01X292288Y590665D02*
Y586665D01*
X299688D01*
G01X270229Y600866D02*
Y599074D01*
X270396Y598699D01*
X270729Y598449D01*
X271146Y598366D01*
X271563Y598449D01*
X271896Y598699D01*
X272063Y599074D01*
Y600866D01*
G01X274246Y598366D02*
Y600866D01*
X273746Y600366D01*
G01Y598366D02*
X274746D01*
G01X276554Y599408D02*
X276846Y599699D01*
X277096Y599866D01*
X277429Y599949D01*
X277721Y599866D01*
X277929Y599699D01*
X278096Y599449D01*
X278138Y599158D01*
X278096Y598908D01*
X277929Y598658D01*
X277679Y598449D01*
X277388Y598366D01*
X277054Y598449D01*
X276763Y598699D01*
X276596Y599074D01*
X276554Y599491D01*
X276638Y600033D01*
X276763Y600324D01*
X276971Y600616D01*
X277263Y600824D01*
X277554Y600866D01*
X277846Y600783D01*
X278054Y600574D01*
G01X270300Y639800D02*
X268300D01*
G01X284000Y615517D02*
X281500D01*
Y616517D01*
X281625Y616850D01*
X281917Y617100D01*
X282250Y617183D01*
X282583Y617100D01*
X282833Y616892D01*
X282958Y616517D01*
Y615517D01*
G01X281708Y620367D02*
X281583Y620117D01*
X281500Y619825D01*
Y619492D01*
X281625Y619117D01*
X281833Y618825D01*
X282083Y618617D01*
X282500Y618450D01*
X282875Y618408D01*
X283250Y618492D01*
X283500Y618617D01*
X283750Y618867D01*
X283917Y619158D01*
X284000Y619450D01*
Y619742D01*
X283917Y620033D01*
X283792Y620283D01*
X283625Y620492D01*
G01X283708Y621842D02*
X283917Y622133D01*
X284000Y622467D01*
X283917Y622800D01*
X283667Y623092D01*
X283292Y623300D01*
X282917Y623383D01*
X282458D01*
X282083Y623300D01*
X281750Y623092D01*
X281583Y622842D01*
X281500Y622550D01*
X281583Y622217D01*
X281750Y621967D01*
X282000Y621800D01*
X282333Y621717D01*
X282625Y621800D01*
X282917Y622008D01*
X283083Y622258D01*
X283125Y622550D01*
X283042Y622883D01*
X282833Y623133D01*
X282458Y623383D01*
G01X283625Y624733D02*
X283833Y624983D01*
X283958Y625275D01*
X284000Y625650D01*
X283917Y626025D01*
X283750Y626317D01*
X283458Y626525D01*
X283125Y626567D01*
X282792Y626483D01*
X282583Y626275D01*
X282417Y625983D01*
X282375Y625692D01*
X282417Y625400D01*
X282583Y625025D01*
X281500Y625150D01*
Y626275D01*
G01X296194Y628847D02*
Y631347D01*
X297194D01*
X297527Y631222D01*
X297777Y630930D01*
X297860Y630597D01*
X297777Y630264D01*
X297569Y630014D01*
X297194Y629889D01*
X296194D01*
G01X299294Y628847D02*
Y631347D01*
X300335D01*
X300669Y631222D01*
X300877Y631055D01*
X300960Y630722D01*
X300877Y630389D01*
X300627Y630180D01*
X300335Y630055D01*
X299294D01*
G01X300335D02*
X300960Y628847D01*
G01X302435Y630930D02*
X302685Y631180D01*
X302977Y631305D01*
X303310Y631347D01*
X303727Y631264D01*
X304019Y631055D01*
X304102Y630805D01*
X304060Y630555D01*
X303894Y630347D01*
X303060Y629930D01*
X302685Y629639D01*
X302435Y629222D01*
X302352Y628847D01*
X304102D01*
G01X305410Y629347D02*
X305660Y629055D01*
X305994Y628889D01*
X306369Y628847D01*
X306702Y628889D01*
X307035Y629097D01*
X307244Y629347D01*
X307285Y629597D01*
X307202Y629889D01*
X306910Y630097D01*
X306619Y630180D01*
X306244D01*
G01X306619D02*
X306869Y630305D01*
X307077Y630514D01*
X307160Y630764D01*
X307077Y631014D01*
X306869Y631222D01*
X306494Y631347D01*
X306119Y631305D01*
X305744Y631139D01*
G01X290765Y638018D02*
Y640518D01*
X291765D01*
X292098Y640393D01*
X292348Y640101D01*
X292431Y639768D01*
X292348Y639435D01*
X292140Y639185D01*
X291765Y639060D01*
X290765D01*
G01X293865Y638018D02*
Y640518D01*
X294906D01*
X295240Y640393D01*
X295448Y640226D01*
X295531Y639893D01*
X295448Y639560D01*
X295198Y639351D01*
X294906Y639226D01*
X293865D01*
G01X294906D02*
X295531Y638018D01*
G01X298298D02*
Y640518D01*
X296756Y638726D01*
X298840D01*
G01X299981Y638518D02*
X300231Y638226D01*
X300565Y638060D01*
X300940Y638018D01*
X301273Y638060D01*
X301606Y638268D01*
X301815Y638518D01*
X301856Y638768D01*
X301773Y639060D01*
X301481Y639268D01*
X301190Y639351D01*
X300815D01*
G01X301190D02*
X301440Y639476D01*
X301648Y639685D01*
X301731Y639935D01*
X301648Y640185D01*
X301440Y640393D01*
X301065Y640518D01*
X300690Y640476D01*
X300315Y640310D01*
G01X280000Y636900D02*
Y640900D01*
X272600D01*
G01X287500Y641900D02*
Y645900D01*
X280100D01*
G01X290765Y634018D02*
Y636518D01*
X291765D01*
X292098Y636393D01*
X292348Y636101D01*
X292431Y635768D01*
X292348Y635435D01*
X292140Y635185D01*
X291765Y635060D01*
X290765D01*
G01X295615Y636310D02*
X295365Y636435D01*
X295073Y636518D01*
X294740D01*
X294365Y636393D01*
X294073Y636185D01*
X293865Y635935D01*
X293698Y635518D01*
X293656Y635143D01*
X293740Y634768D01*
X293865Y634518D01*
X294115Y634268D01*
X294406Y634101D01*
X294698Y634018D01*
X294990D01*
X295281Y634101D01*
X295531Y634226D01*
X295740Y634393D01*
G01X297715Y634018D02*
X297798Y634560D01*
X297923Y635018D01*
X298090Y635435D01*
X298298Y635893D01*
X298631Y636518D01*
X296965D01*
G01X300106Y635060D02*
X300398Y635351D01*
X300648Y635518D01*
X300981Y635601D01*
X301273Y635518D01*
X301481Y635351D01*
X301648Y635101D01*
X301690Y634810D01*
X301648Y634560D01*
X301481Y634310D01*
X301231Y634101D01*
X300940Y634018D01*
X300606Y634101D01*
X300315Y634351D01*
X300148Y634726D01*
X300106Y635143D01*
X300190Y635685D01*
X300315Y635976D01*
X300523Y636268D01*
X300815Y636476D01*
X301106Y636518D01*
X301398Y636435D01*
X301606Y636226D01*
G01X277356Y655452D02*
X274856D01*
Y656452D01*
X274981Y656785D01*
X275273Y657035D01*
X275606Y657118D01*
X275939Y657035D01*
X276189Y656827D01*
X276314Y656452D01*
Y655452D01*
G01X275064Y660302D02*
X274939Y660052D01*
X274856Y659760D01*
Y659427D01*
X274981Y659052D01*
X275189Y658760D01*
X275439Y658552D01*
X275856Y658385D01*
X276231Y658343D01*
X276606Y658427D01*
X276856Y658552D01*
X277106Y658802D01*
X277273Y659093D01*
X277356Y659385D01*
Y659677D01*
X277273Y659968D01*
X277148Y660218D01*
X276981Y660427D01*
G01X275273Y661693D02*
X275023Y661943D01*
X274898Y662235D01*
X274856Y662568D01*
X274939Y662985D01*
X275148Y663277D01*
X275398Y663360D01*
X275648Y663318D01*
X275856Y663152D01*
X276273Y662318D01*
X276564Y661943D01*
X276981Y661693D01*
X277356Y661610D01*
Y663360D01*
G01X274856Y665585D02*
X274939Y665252D01*
X275148Y665002D01*
X275398Y664835D01*
X275731Y664710D01*
X276106Y664668D01*
X276481Y664710D01*
X276814Y664835D01*
X277064Y665002D01*
X277273Y665252D01*
X277356Y665585D01*
X277273Y665918D01*
X277064Y666168D01*
X276814Y666335D01*
X276481Y666460D01*
X276106Y666502D01*
X275731Y666460D01*
X275398Y666335D01*
X275148Y666168D01*
X274939Y665918D01*
X274856Y665585D01*
G01X282017Y650000D02*
Y652500D01*
X283017D01*
X283350Y652375D01*
X283600Y652083D01*
X283683Y651750D01*
X283600Y651417D01*
X283392Y651167D01*
X283017Y651042D01*
X282017D01*
G01X285117Y650000D02*
Y652500D01*
X286158D01*
X286492Y652375D01*
X286700Y652208D01*
X286783Y651875D01*
X286700Y651542D01*
X286450Y651333D01*
X286158Y651208D01*
X285117D01*
G01X286158D02*
X286783Y650000D01*
G01X289050D02*
Y652500D01*
X288550Y652000D01*
G01Y650000D02*
X289550D01*
G01X292067D02*
X292150Y650542D01*
X292275Y651000D01*
X292442Y651417D01*
X292650Y651875D01*
X292983Y652500D01*
X291317D01*
G01X289009Y689823D02*
X288884Y689573D01*
X288801Y689281D01*
Y688948D01*
X288926Y688573D01*
X289134Y688281D01*
X289384Y688073D01*
X289801Y687906D01*
X290176Y687864D01*
X290551Y687948D01*
X290801Y688073D01*
X291051Y688323D01*
X291218Y688614D01*
X291301Y688906D01*
Y689198D01*
X291218Y689489D01*
X291093Y689739D01*
X290926Y689948D01*
G01X291301Y692506D02*
X288801D01*
X290593Y690964D01*
Y693048D01*
G01X291301Y695106D02*
X288801D01*
X289301Y694606D01*
G01X291301D02*
Y695606D01*
G01X288801Y698206D02*
X288884Y697873D01*
X289093Y697623D01*
X289343Y697456D01*
X289676Y697331D01*
X290051Y697289D01*
X290426Y697331D01*
X290759Y697456D01*
X291009Y697623D01*
X291218Y697873D01*
X291301Y698206D01*
X291218Y698539D01*
X291009Y698789D01*
X290759Y698956D01*
X290426Y699081D01*
X290051Y699123D01*
X289676Y699081D01*
X289343Y698956D01*
X289093Y698789D01*
X288884Y698539D01*
X288801Y698206D01*
G01X291301Y701806D02*
X288801D01*
X290593Y700264D01*
Y702348D01*
G01X280258Y700889D02*
X277758D01*
Y701930D01*
X277883Y702264D01*
X278050Y702472D01*
X278383Y702555D01*
X278716Y702472D01*
X278925Y702222D01*
X279050Y701930D01*
Y700889D01*
G01Y701930D02*
X280258Y702555D01*
G01Y704739D02*
X279716Y704822D01*
X279258Y704947D01*
X278841Y705114D01*
X278383Y705322D01*
X277758Y705655D01*
Y703989D01*
G01X279966Y707214D02*
X280175Y707505D01*
X280258Y707839D01*
X280175Y708172D01*
X279925Y708464D01*
X279550Y708672D01*
X279175Y708755D01*
X278716D01*
X278341Y708672D01*
X278008Y708464D01*
X277841Y708214D01*
X277758Y707922D01*
X277841Y707589D01*
X278008Y707339D01*
X278258Y707172D01*
X278591Y707089D01*
X278883Y707172D01*
X279175Y707380D01*
X279341Y707630D01*
X279383Y707922D01*
X279300Y708255D01*
X279091Y708505D01*
X278716Y708755D01*
G01X280258Y710939D02*
X279716Y711022D01*
X279258Y711147D01*
X278841Y711314D01*
X278383Y711522D01*
X277758Y711855D01*
Y710189D01*
G01X279758Y713205D02*
X280050Y713455D01*
X280216Y713789D01*
X280258Y714164D01*
X280216Y714497D01*
X280008Y714830D01*
X279758Y715039D01*
X279508Y715080D01*
X279216Y714997D01*
X279008Y714705D01*
X278925Y714414D01*
Y714039D01*
G01Y714414D02*
X278800Y714664D01*
X278591Y714872D01*
X278341Y714955D01*
X278091Y714872D01*
X277883Y714664D01*
X277758Y714289D01*
X277800Y713914D01*
X277966Y713539D01*
G01X276258Y700889D02*
X273758D01*
Y701930D01*
X273883Y702264D01*
X274050Y702472D01*
X274383Y702555D01*
X274716Y702472D01*
X274925Y702222D01*
X275050Y701930D01*
Y700889D01*
G01Y701930D02*
X276258Y702555D01*
G01Y704739D02*
X275716Y704822D01*
X275258Y704947D01*
X274841Y705114D01*
X274383Y705322D01*
X273758Y705655D01*
Y703989D01*
G01X275966Y707214D02*
X276175Y707505D01*
X276258Y707839D01*
X276175Y708172D01*
X275925Y708464D01*
X275550Y708672D01*
X275175Y708755D01*
X274716D01*
X274341Y708672D01*
X274008Y708464D01*
X273841Y708214D01*
X273758Y707922D01*
X273841Y707589D01*
X274008Y707339D01*
X274258Y707172D01*
X274591Y707089D01*
X274883Y707172D01*
X275175Y707380D01*
X275341Y707630D01*
X275383Y707922D01*
X275300Y708255D01*
X275091Y708505D01*
X274716Y708755D01*
G01X275883Y710105D02*
X276091Y710355D01*
X276216Y710647D01*
X276258Y711022D01*
X276175Y711397D01*
X276008Y711689D01*
X275716Y711897D01*
X275383Y711939D01*
X275050Y711855D01*
X274841Y711647D01*
X274675Y711355D01*
X274633Y711064D01*
X274675Y710772D01*
X274841Y710397D01*
X273758Y710522D01*
Y711647D01*
G01X276258Y714122D02*
X276216Y714414D01*
X276091Y714747D01*
X275883Y714955D01*
X275591Y715039D01*
X275300Y714955D01*
X275050Y714705D01*
X274925Y714330D01*
Y713914D01*
X274841Y713664D01*
X274633Y713455D01*
X274341Y713372D01*
X274050Y713497D01*
X273841Y713789D01*
X273758Y714122D01*
X273841Y714455D01*
X274050Y714747D01*
X274341Y714872D01*
X274633Y714789D01*
X274841Y714580D01*
X274925Y714330D01*
Y713914D01*
X275050Y713539D01*
X275300Y713289D01*
X275591Y713205D01*
X275883Y713289D01*
X276091Y713497D01*
X276216Y713830D01*
X276258Y714122D01*
G01X272258Y700889D02*
X269758D01*
Y701930D01*
X269883Y702264D01*
X270050Y702472D01*
X270383Y702555D01*
X270716Y702472D01*
X270925Y702222D01*
X271050Y701930D01*
Y700889D01*
G01Y701930D02*
X272258Y702555D01*
G01Y704739D02*
X271716Y704822D01*
X271258Y704947D01*
X270841Y705114D01*
X270383Y705322D01*
X269758Y705655D01*
Y703989D01*
G01X271966Y707214D02*
X272175Y707505D01*
X272258Y707839D01*
X272175Y708172D01*
X271925Y708464D01*
X271550Y708672D01*
X271175Y708755D01*
X270716D01*
X270341Y708672D01*
X270008Y708464D01*
X269841Y708214D01*
X269758Y707922D01*
X269841Y707589D01*
X270008Y707339D01*
X270258Y707172D01*
X270591Y707089D01*
X270883Y707172D01*
X271175Y707380D01*
X271341Y707630D01*
X271383Y707922D01*
X271300Y708255D01*
X271091Y708505D01*
X270716Y708755D01*
G01X272258Y711522D02*
X269758D01*
X271550Y709980D01*
Y712064D01*
G01X271758Y713205D02*
X272050Y713455D01*
X272216Y713789D01*
X272258Y714164D01*
X272216Y714497D01*
X272008Y714830D01*
X271758Y715039D01*
X271508Y715080D01*
X271216Y714997D01*
X271008Y714705D01*
X270925Y714414D01*
Y714039D01*
G01Y714414D02*
X270800Y714664D01*
X270591Y714872D01*
X270341Y714955D01*
X270091Y714872D01*
X269883Y714664D01*
X269758Y714289D01*
X269800Y713914D01*
X269966Y713539D01*
G01X283876Y700919D02*
X281376D01*
Y701960D01*
X281501Y702294D01*
X281668Y702502D01*
X282001Y702585D01*
X282334Y702502D01*
X282543Y702252D01*
X282668Y701960D01*
Y700919D01*
G01Y701960D02*
X283876Y702585D01*
G01X283584Y704144D02*
X283793Y704435D01*
X283876Y704769D01*
X283793Y705102D01*
X283543Y705394D01*
X283168Y705602D01*
X282793Y705685D01*
X282334D01*
X281959Y705602D01*
X281626Y705394D01*
X281459Y705144D01*
X281376Y704852D01*
X281459Y704519D01*
X281626Y704269D01*
X281876Y704102D01*
X282209Y704019D01*
X282501Y704102D01*
X282793Y704310D01*
X282959Y704560D01*
X283001Y704852D01*
X282918Y705185D01*
X282709Y705435D01*
X282334Y705685D01*
G01X281376Y707952D02*
X281459Y707619D01*
X281668Y707369D01*
X281918Y707202D01*
X282251Y707077D01*
X282626Y707035D01*
X283001Y707077D01*
X283334Y707202D01*
X283584Y707369D01*
X283793Y707619D01*
X283876Y707952D01*
X283793Y708285D01*
X283584Y708535D01*
X283334Y708702D01*
X283001Y708827D01*
X282626Y708869D01*
X282251Y708827D01*
X281918Y708702D01*
X281668Y708535D01*
X281459Y708285D01*
X281376Y707952D01*
G01X283376Y710135D02*
X283668Y710385D01*
X283834Y710719D01*
X283876Y711094D01*
X283834Y711427D01*
X283626Y711760D01*
X283376Y711969D01*
X283126Y712010D01*
X282834Y711927D01*
X282626Y711635D01*
X282543Y711344D01*
Y710969D01*
G01Y711344D02*
X282418Y711594D01*
X282209Y711802D01*
X281959Y711885D01*
X281709Y711802D01*
X281501Y711594D01*
X281376Y711219D01*
X281418Y710844D01*
X281584Y710469D01*
G01X283876Y714652D02*
X281376D01*
X283168Y713110D01*
Y715194D01*
G01X267572Y740688D02*
X269364D01*
X269739Y740855D01*
X269989Y741188D01*
X270072Y741605D01*
X269989Y742022D01*
X269739Y742355D01*
X269364Y742522D01*
X267572D01*
G01X270072Y744705D02*
X267572D01*
X268072Y744205D01*
G01X270072D02*
Y745205D01*
G01X269780Y747097D02*
X269989Y747388D01*
X270072Y747722D01*
X269989Y748055D01*
X269739Y748347D01*
X269364Y748555D01*
X268989Y748638D01*
X268530D01*
X268155Y748555D01*
X267822Y748347D01*
X267655Y748097D01*
X267572Y747805D01*
X267655Y747472D01*
X267822Y747222D01*
X268072Y747055D01*
X268405Y746972D01*
X268697Y747055D01*
X268989Y747263D01*
X269155Y747513D01*
X269197Y747805D01*
X269114Y748138D01*
X268905Y748388D01*
X268530Y748638D01*
G01X270072Y750905D02*
X270030Y751197D01*
X269905Y751530D01*
X269697Y751738D01*
X269405Y751822D01*
X269114Y751738D01*
X268864Y751488D01*
X268739Y751113D01*
Y750697D01*
X268655Y750447D01*
X268447Y750238D01*
X268155Y750155D01*
X267864Y750280D01*
X267655Y750572D01*
X267572Y750905D01*
X267655Y751238D01*
X267864Y751530D01*
X268155Y751655D01*
X268447Y751572D01*
X268655Y751363D01*
X268739Y751113D01*
Y750697D01*
X268864Y750322D01*
X269114Y750072D01*
X269405Y749988D01*
X269697Y750072D01*
X269905Y750280D01*
X270030Y750613D01*
X270072Y750905D01*
G01X306406Y739398D02*
X275706D01*
G01Y753398D02*
Y739398D01*
G01X276806Y746398D02*
X275706Y747498D01*
G01X276806Y746398D02*
X275706Y745298D01*
G01X296406Y725098D02*
X292406D01*
Y717698D01*
G01Y725098D02*
X288406D01*
Y717698D01*
G01Y725098D02*
X284406D01*
Y717698D01*
G01Y725098D02*
X280406D01*
Y717698D01*
G01X300406Y725098D02*
X296406D01*
Y717698D01*
G01X272406D02*
X276406D01*
Y725098D01*
G01Y717698D02*
X280406D01*
Y725098D01*
G01X275706Y753398D02*
X306406D01*
G01X284500Y774300D02*
X288500D01*
Y781700D01*
G01X292348Y775743D02*
X289848D01*
Y776784D01*
X289973Y777118D01*
X290140Y777326D01*
X290473Y777409D01*
X290806Y777326D01*
X291015Y777076D01*
X291140Y776784D01*
Y775743D01*
G01Y776784D02*
X292348Y777409D01*
G01Y779593D02*
X291806Y779676D01*
X291348Y779801D01*
X290931Y779968D01*
X290473Y780176D01*
X289848Y780509D01*
Y778843D01*
G01X292056Y782068D02*
X292265Y782359D01*
X292348Y782693D01*
X292265Y783026D01*
X292015Y783318D01*
X291640Y783526D01*
X291265Y783609D01*
X290806D01*
X290431Y783526D01*
X290098Y783318D01*
X289931Y783068D01*
X289848Y782776D01*
X289931Y782443D01*
X290098Y782193D01*
X290348Y782026D01*
X290681Y781943D01*
X290973Y782026D01*
X291265Y782234D01*
X291431Y782484D01*
X291473Y782776D01*
X291390Y783109D01*
X291181Y783359D01*
X290806Y783609D01*
G01X291306Y785084D02*
X291015Y785376D01*
X290848Y785626D01*
X290765Y785959D01*
X290848Y786251D01*
X291015Y786459D01*
X291265Y786626D01*
X291556Y786668D01*
X291806Y786626D01*
X292056Y786459D01*
X292265Y786209D01*
X292348Y785918D01*
X292265Y785584D01*
X292015Y785293D01*
X291640Y785126D01*
X291223Y785084D01*
X290681Y785168D01*
X290390Y785293D01*
X290098Y785501D01*
X289890Y785793D01*
X289848Y786084D01*
X289931Y786376D01*
X290140Y786584D01*
G01X292348Y788976D02*
X289848D01*
X290348Y788476D01*
G01X292348D02*
Y789476D01*
G01X289000Y766700D02*
X293000D01*
Y774100D01*
G01X296427Y775693D02*
X293927D01*
Y776734D01*
X294052Y777068D01*
X294219Y777276D01*
X294552Y777359D01*
X294885Y777276D01*
X295094Y777026D01*
X295219Y776734D01*
Y775693D01*
G01Y776734D02*
X296427Y777359D01*
G01Y779543D02*
X295885Y779626D01*
X295427Y779751D01*
X295010Y779918D01*
X294552Y780126D01*
X293927Y780459D01*
Y778793D01*
G01X296135Y782018D02*
X296344Y782309D01*
X296427Y782643D01*
X296344Y782976D01*
X296094Y783268D01*
X295719Y783476D01*
X295344Y783559D01*
X294885D01*
X294510Y783476D01*
X294177Y783268D01*
X294010Y783018D01*
X293927Y782726D01*
X294010Y782393D01*
X294177Y782143D01*
X294427Y781976D01*
X294760Y781893D01*
X295052Y781976D01*
X295344Y782184D01*
X295510Y782434D01*
X295552Y782726D01*
X295469Y783059D01*
X295260Y783309D01*
X294885Y783559D01*
G01X296427Y786326D02*
X293927D01*
X295719Y784784D01*
Y786868D01*
G01X296052Y788009D02*
X296260Y788259D01*
X296385Y788551D01*
X296427Y788926D01*
X296344Y789301D01*
X296177Y789593D01*
X295885Y789801D01*
X295552Y789843D01*
X295219Y789759D01*
X295010Y789551D01*
X294844Y789259D01*
X294802Y788968D01*
X294844Y788676D01*
X295010Y788301D01*
X293927Y788426D01*
Y789551D01*
G01X293079Y766650D02*
X297079D01*
Y774050D01*
G01X300527Y775693D02*
X298027D01*
Y776734D01*
X298152Y777068D01*
X298319Y777276D01*
X298652Y777359D01*
X298985Y777276D01*
X299194Y777026D01*
X299319Y776734D01*
Y775693D01*
G01Y776734D02*
X300527Y777359D01*
G01Y779543D02*
X299985Y779626D01*
X299527Y779751D01*
X299110Y779918D01*
X298652Y780126D01*
X298027Y780459D01*
Y778793D01*
G01X300235Y782018D02*
X300444Y782309D01*
X300527Y782643D01*
X300444Y782976D01*
X300194Y783268D01*
X299819Y783476D01*
X299444Y783559D01*
X298985D01*
X298610Y783476D01*
X298277Y783268D01*
X298110Y783018D01*
X298027Y782726D01*
X298110Y782393D01*
X298277Y782143D01*
X298527Y781976D01*
X298860Y781893D01*
X299152Y781976D01*
X299444Y782184D01*
X299610Y782434D01*
X299652Y782726D01*
X299569Y783059D01*
X299360Y783309D01*
X298985Y783559D01*
G01X300027Y784909D02*
X300319Y785159D01*
X300485Y785493D01*
X300527Y785868D01*
X300485Y786201D01*
X300277Y786534D01*
X300027Y786743D01*
X299777Y786784D01*
X299485Y786701D01*
X299277Y786409D01*
X299194Y786118D01*
Y785743D01*
G01Y786118D02*
X299069Y786368D01*
X298860Y786576D01*
X298610Y786659D01*
X298360Y786576D01*
X298152Y786368D01*
X298027Y785993D01*
X298069Y785618D01*
X298235Y785243D01*
G01X300527Y788926D02*
X298027D01*
X298527Y788426D01*
G01X300527D02*
Y789426D01*
G01X297148Y766905D02*
X301148D01*
Y774305D01*
G01X279058Y776689D02*
X276558D01*
Y777730D01*
X276683Y778064D01*
X276850Y778272D01*
X277183Y778355D01*
X277516Y778272D01*
X277725Y778022D01*
X277850Y777730D01*
Y776689D01*
G01Y777730D02*
X279058Y778355D01*
G01Y780539D02*
X278516Y780622D01*
X278058Y780747D01*
X277641Y780914D01*
X277183Y781122D01*
X276558Y781455D01*
Y779789D01*
G01X278766Y783014D02*
X278975Y783305D01*
X279058Y783639D01*
X278975Y783972D01*
X278725Y784264D01*
X278350Y784472D01*
X277975Y784555D01*
X277516D01*
X277141Y784472D01*
X276808Y784264D01*
X276641Y784014D01*
X276558Y783722D01*
X276641Y783389D01*
X276808Y783139D01*
X277058Y782972D01*
X277391Y782889D01*
X277683Y782972D01*
X277975Y783180D01*
X278141Y783430D01*
X278183Y783722D01*
X278100Y784055D01*
X277891Y784305D01*
X277516Y784555D01*
G01X279058Y786822D02*
X276558D01*
X277058Y786322D01*
G01X279058D02*
Y787322D01*
G01X278558Y789005D02*
X278850Y789255D01*
X279016Y789589D01*
X279058Y789964D01*
X279016Y790297D01*
X278808Y790630D01*
X278558Y790839D01*
X278308Y790880D01*
X278016Y790797D01*
X277808Y790505D01*
X277725Y790214D01*
Y789839D01*
G01Y790214D02*
X277600Y790464D01*
X277391Y790672D01*
X277141Y790755D01*
X276891Y790672D01*
X276683Y790464D01*
X276558Y790089D01*
X276600Y789714D01*
X276766Y789339D01*
G01X280406Y774098D02*
X276406D01*
Y766698D01*
G01X275058Y776689D02*
X272558D01*
Y777730D01*
X272683Y778064D01*
X272850Y778272D01*
X273183Y778355D01*
X273516Y778272D01*
X273725Y778022D01*
X273850Y777730D01*
Y776689D01*
G01Y777730D02*
X275058Y778355D01*
G01Y780539D02*
X274516Y780622D01*
X274058Y780747D01*
X273641Y780914D01*
X273183Y781122D01*
X272558Y781455D01*
Y779789D01*
G01X274766Y783014D02*
X274975Y783305D01*
X275058Y783639D01*
X274975Y783972D01*
X274725Y784264D01*
X274350Y784472D01*
X273975Y784555D01*
X273516D01*
X273141Y784472D01*
X272808Y784264D01*
X272641Y784014D01*
X272558Y783722D01*
X272641Y783389D01*
X272808Y783139D01*
X273058Y782972D01*
X273391Y782889D01*
X273683Y782972D01*
X273975Y783180D01*
X274141Y783430D01*
X274183Y783722D01*
X274100Y784055D01*
X273891Y784305D01*
X273516Y784555D01*
G01X275058Y786822D02*
X272558D01*
X273058Y786322D01*
G01X275058D02*
Y787322D01*
G01X272975Y789130D02*
X272725Y789380D01*
X272600Y789672D01*
X272558Y790005D01*
X272641Y790422D01*
X272850Y790714D01*
X273100Y790797D01*
X273350Y790755D01*
X273558Y790589D01*
X273975Y789755D01*
X274266Y789380D01*
X274683Y789130D01*
X275058Y789047D01*
Y790797D01*
G01X276406Y774098D02*
X272406D01*
Y766698D01*
G01X283100Y776917D02*
X280600D01*
Y777958D01*
X280725Y778292D01*
X280892Y778500D01*
X281225Y778583D01*
X281558Y778500D01*
X281767Y778250D01*
X281892Y777958D01*
Y776917D01*
G01Y777958D02*
X283100Y778583D01*
G01Y781350D02*
X280600D01*
X282392Y779808D01*
Y781892D01*
G01X282725Y783033D02*
X282933Y783283D01*
X283058Y783575D01*
X283100Y783950D01*
X283017Y784325D01*
X282850Y784617D01*
X282558Y784825D01*
X282225Y784867D01*
X281892Y784783D01*
X281683Y784575D01*
X281517Y784283D01*
X281475Y783992D01*
X281517Y783700D01*
X281683Y783325D01*
X280600Y783450D01*
Y784575D01*
G01X282600Y786133D02*
X282892Y786383D01*
X283058Y786717D01*
X283100Y787092D01*
X283058Y787425D01*
X282850Y787758D01*
X282600Y787967D01*
X282350Y788008D01*
X282058Y787925D01*
X281850Y787633D01*
X281767Y787342D01*
Y786967D01*
G01Y787342D02*
X281642Y787592D01*
X281433Y787800D01*
X281183Y787883D01*
X280933Y787800D01*
X280725Y787592D01*
X280600Y787217D01*
X280642Y786842D01*
X280808Y786467D01*
G01X284478Y774131D02*
X280478D01*
Y766731D01*
G01X287912Y783018D02*
X285412D01*
Y784059D01*
X285537Y784393D01*
X285704Y784601D01*
X286037Y784684D01*
X286370Y784601D01*
X286579Y784351D01*
X286704Y784059D01*
Y783018D01*
G01Y784059D02*
X287912Y784684D01*
G01X287620Y786243D02*
X287829Y786534D01*
X287912Y786868D01*
X287829Y787201D01*
X287579Y787493D01*
X287204Y787701D01*
X286829Y787784D01*
X286370D01*
X285995Y787701D01*
X285662Y787493D01*
X285495Y787243D01*
X285412Y786951D01*
X285495Y786618D01*
X285662Y786368D01*
X285912Y786201D01*
X286245Y786118D01*
X286537Y786201D01*
X286829Y786409D01*
X286995Y786659D01*
X287037Y786951D01*
X286954Y787284D01*
X286745Y787534D01*
X286370Y787784D01*
G01X285412Y790051D02*
X285495Y789718D01*
X285704Y789468D01*
X285954Y789301D01*
X286287Y789176D01*
X286662Y789134D01*
X287037Y789176D01*
X287370Y789301D01*
X287620Y789468D01*
X287829Y789718D01*
X287912Y790051D01*
X287829Y790384D01*
X287620Y790634D01*
X287370Y790801D01*
X287037Y790926D01*
X286662Y790968D01*
X286287Y790926D01*
X285954Y790801D01*
X285704Y790634D01*
X285495Y790384D01*
X285412Y790051D01*
G01X287912Y793651D02*
X285412D01*
X287204Y792109D01*
Y794193D01*
G01X285412Y796251D02*
X285495Y795918D01*
X285704Y795668D01*
X285954Y795501D01*
X286287Y795376D01*
X286662Y795334D01*
X287037Y795376D01*
X287370Y795501D01*
X287620Y795668D01*
X287829Y795918D01*
X287912Y796251D01*
X287829Y796584D01*
X287620Y796834D01*
X287370Y797001D01*
X287037Y797126D01*
X286662Y797168D01*
X286287Y797126D01*
X285954Y797001D01*
X285704Y796834D01*
X285495Y796584D01*
X285412Y796251D01*
G01X284500Y766800D02*
X288500D01*
Y774200D01*
G01X301984Y799175D02*
X299484D01*
Y800216D01*
X299609Y800550D01*
X299776Y800758D01*
X300109Y800841D01*
X300442Y800758D01*
X300651Y800508D01*
X300776Y800216D01*
Y799175D01*
G01Y800216D02*
X301984Y800841D01*
G01Y803025D02*
X301442Y803108D01*
X300984Y803233D01*
X300567Y803400D01*
X300109Y803608D01*
X299484Y803941D01*
Y802275D01*
G01X301692Y805500D02*
X301901Y805791D01*
X301984Y806125D01*
X301901Y806458D01*
X301651Y806750D01*
X301276Y806958D01*
X300901Y807041D01*
X300442D01*
X300067Y806958D01*
X299734Y806750D01*
X299567Y806500D01*
X299484Y806208D01*
X299567Y805875D01*
X299734Y805625D01*
X299984Y805458D01*
X300317Y805375D01*
X300609Y805458D01*
X300901Y805666D01*
X301067Y805916D01*
X301109Y806208D01*
X301026Y806541D01*
X300817Y806791D01*
X300442Y807041D01*
G01X301984Y809225D02*
X301442Y809308D01*
X300984Y809433D01*
X300567Y809600D01*
X300109Y809808D01*
X299484Y810141D01*
Y808475D01*
G01X301984Y812408D02*
X301942Y812700D01*
X301817Y813033D01*
X301609Y813241D01*
X301317Y813325D01*
X301026Y813241D01*
X300776Y812991D01*
X300651Y812616D01*
Y812200D01*
X300567Y811950D01*
X300359Y811741D01*
X300067Y811658D01*
X299776Y811783D01*
X299567Y812075D01*
X299484Y812408D01*
X299567Y812741D01*
X299776Y813033D01*
X300067Y813158D01*
X300359Y813075D01*
X300567Y812866D01*
X300651Y812616D01*
Y812200D01*
X300776Y811825D01*
X301026Y811575D01*
X301317Y811491D01*
X301609Y811575D01*
X301817Y811783D01*
X301942Y812116D01*
X301984Y812408D01*
G01X288217Y800314D02*
X285717D01*
Y801355D01*
X285842Y801689D01*
X286009Y801897D01*
X286342Y801980D01*
X286675Y801897D01*
X286884Y801647D01*
X287009Y801355D01*
Y800314D01*
G01Y801355D02*
X288217Y801980D01*
G01Y804164D02*
X287675Y804247D01*
X287217Y804372D01*
X286800Y804539D01*
X286342Y804747D01*
X285717Y805080D01*
Y803414D01*
G01X287925Y806639D02*
X288134Y806930D01*
X288217Y807264D01*
X288134Y807597D01*
X287884Y807889D01*
X287509Y808097D01*
X287134Y808180D01*
X286675D01*
X286300Y808097D01*
X285967Y807889D01*
X285800Y807639D01*
X285717Y807347D01*
X285800Y807014D01*
X285967Y806764D01*
X286217Y806597D01*
X286550Y806514D01*
X286842Y806597D01*
X287134Y806805D01*
X287300Y807055D01*
X287342Y807347D01*
X287259Y807680D01*
X287050Y807930D01*
X286675Y808180D01*
G01X288217Y810364D02*
X287675Y810447D01*
X287217Y810572D01*
X286800Y810739D01*
X286342Y810947D01*
X285717Y811280D01*
Y809614D01*
G01X287175Y812755D02*
X286884Y813047D01*
X286717Y813297D01*
X286634Y813630D01*
X286717Y813922D01*
X286884Y814130D01*
X287134Y814297D01*
X287425Y814339D01*
X287675Y814297D01*
X287925Y814130D01*
X288134Y813880D01*
X288217Y813589D01*
X288134Y813255D01*
X287884Y812964D01*
X287509Y812797D01*
X287092Y812755D01*
X286550Y812839D01*
X286259Y812964D01*
X285967Y813172D01*
X285759Y813464D01*
X285717Y813755D01*
X285800Y814047D01*
X286009Y814255D01*
G01X267008Y843167D02*
X266883Y842917D01*
X266800Y842625D01*
Y842292D01*
X266925Y841917D01*
X267133Y841625D01*
X267383Y841417D01*
X267800Y841250D01*
X268175Y841208D01*
X268550Y841292D01*
X268800Y841417D01*
X269050Y841667D01*
X269217Y841958D01*
X269300Y842250D01*
Y842542D01*
X269217Y842833D01*
X269092Y843083D01*
X268925Y843292D01*
G01X268800Y844433D02*
X269092Y844683D01*
X269258Y845017D01*
X269300Y845392D01*
X269258Y845725D01*
X269050Y846058D01*
X268800Y846267D01*
X268550Y846308D01*
X268258Y846225D01*
X268050Y845933D01*
X267967Y845642D01*
Y845267D01*
G01Y845642D02*
X267842Y845892D01*
X267633Y846100D01*
X267383Y846183D01*
X267133Y846100D01*
X266925Y845892D01*
X266800Y845517D01*
X266842Y845142D01*
X267008Y844767D01*
G01X268925Y847533D02*
X269133Y847783D01*
X269258Y848075D01*
X269300Y848450D01*
X269217Y848825D01*
X269050Y849117D01*
X268758Y849325D01*
X268425Y849367D01*
X268092Y849283D01*
X267883Y849075D01*
X267717Y848783D01*
X267675Y848492D01*
X267717Y848200D01*
X267883Y847825D01*
X266800Y847950D01*
Y849075D01*
G01X268258Y850758D02*
X267967Y851050D01*
X267800Y851300D01*
X267717Y851633D01*
X267800Y851925D01*
X267967Y852133D01*
X268217Y852300D01*
X268508Y852342D01*
X268758Y852300D01*
X269008Y852133D01*
X269217Y851883D01*
X269300Y851592D01*
X269217Y851258D01*
X268967Y850967D01*
X268592Y850800D01*
X268175Y850758D01*
X267633Y850842D01*
X267342Y850967D01*
X267050Y851175D01*
X266842Y851467D01*
X266800Y851758D01*
X266883Y852050D01*
X267092Y852258D01*
G01X279208Y842767D02*
X279083Y842517D01*
X279000Y842225D01*
Y841892D01*
X279125Y841517D01*
X279333Y841225D01*
X279583Y841017D01*
X280000Y840850D01*
X280375Y840808D01*
X280750Y840892D01*
X281000Y841017D01*
X281250Y841267D01*
X281417Y841558D01*
X281500Y841850D01*
Y842142D01*
X281417Y842433D01*
X281292Y842683D01*
X281125Y842892D01*
G01X281000Y844033D02*
X281292Y844283D01*
X281458Y844617D01*
X281500Y844992D01*
X281458Y845325D01*
X281250Y845658D01*
X281000Y845867D01*
X280750Y845908D01*
X280458Y845825D01*
X280250Y845533D01*
X280167Y845242D01*
Y844867D01*
G01Y845242D02*
X280042Y845492D01*
X279833Y845700D01*
X279583Y845783D01*
X279333Y845700D01*
X279125Y845492D01*
X279000Y845117D01*
X279042Y844742D01*
X279208Y844367D01*
G01X281125Y847133D02*
X281333Y847383D01*
X281458Y847675D01*
X281500Y848050D01*
X281417Y848425D01*
X281250Y848717D01*
X280958Y848925D01*
X280625Y848967D01*
X280292Y848883D01*
X280083Y848675D01*
X279917Y848383D01*
X279875Y848092D01*
X279917Y847800D01*
X280083Y847425D01*
X279000Y847550D01*
Y848675D01*
G01X281500Y851650D02*
X279000D01*
X280792Y850108D01*
Y852192D01*
G01X273408Y842767D02*
X273283Y842517D01*
X273200Y842225D01*
Y841892D01*
X273325Y841517D01*
X273533Y841225D01*
X273783Y841017D01*
X274200Y840850D01*
X274575Y840808D01*
X274950Y840892D01*
X275200Y841017D01*
X275450Y841267D01*
X275617Y841558D01*
X275700Y841850D01*
Y842142D01*
X275617Y842433D01*
X275492Y842683D01*
X275325Y842892D01*
G01X275200Y844033D02*
X275492Y844283D01*
X275658Y844617D01*
X275700Y844992D01*
X275658Y845325D01*
X275450Y845658D01*
X275200Y845867D01*
X274950Y845908D01*
X274658Y845825D01*
X274450Y845533D01*
X274367Y845242D01*
Y844867D01*
G01Y845242D02*
X274242Y845492D01*
X274033Y845700D01*
X273783Y845783D01*
X273533Y845700D01*
X273325Y845492D01*
X273200Y845117D01*
X273242Y844742D01*
X273408Y844367D01*
G01X275325Y847133D02*
X275533Y847383D01*
X275658Y847675D01*
X275700Y848050D01*
X275617Y848425D01*
X275450Y848717D01*
X275158Y848925D01*
X274825Y848967D01*
X274492Y848883D01*
X274283Y848675D01*
X274117Y848383D01*
X274075Y848092D01*
X274117Y847800D01*
X274283Y847425D01*
X273200Y847550D01*
Y848675D01*
G01X275200Y850233D02*
X275492Y850483D01*
X275658Y850817D01*
X275700Y851192D01*
X275658Y851525D01*
X275450Y851858D01*
X275200Y852067D01*
X274950Y852108D01*
X274658Y852025D01*
X274450Y851733D01*
X274367Y851442D01*
Y851067D01*
G01Y851442D02*
X274242Y851692D01*
X274033Y851900D01*
X273783Y851983D01*
X273533Y851900D01*
X273325Y851692D01*
X273200Y851317D01*
X273242Y850942D01*
X273408Y850567D01*
G01X293528Y856526D02*
X294361D01*
Y855776D01*
X294111Y855526D01*
X293820Y855359D01*
X293403Y855276D01*
X292986Y855359D01*
X292695Y855526D01*
X292445Y855776D01*
X292278Y856068D01*
X292195Y856401D01*
Y856693D01*
X292278Y856943D01*
X292445Y857234D01*
X292695Y857484D01*
X292945Y857651D01*
X293278Y857776D01*
X293570D01*
X293903Y857693D01*
X294153Y857526D01*
G01X295586Y855276D02*
Y857776D01*
X297170D01*
G01X296586Y856568D02*
X295586D01*
G01X299478Y855276D02*
X299770Y855318D01*
X300103Y855443D01*
X300311Y855651D01*
X300395Y855943D01*
X300311Y856234D01*
X300061Y856484D01*
X299686Y856609D01*
X299270D01*
X299020Y856693D01*
X298811Y856901D01*
X298728Y857193D01*
X298853Y857484D01*
X299145Y857693D01*
X299478Y857776D01*
X299811Y857693D01*
X300103Y857484D01*
X300228Y857193D01*
X300145Y856901D01*
X299936Y856693D01*
X299686Y856609D01*
X299270D01*
X298895Y856484D01*
X298645Y856234D01*
X298561Y855943D01*
X298645Y855651D01*
X298853Y855443D01*
X299186Y855318D01*
X299478Y855276D01*
G01X312017Y113500D02*
Y116000D01*
X313017D01*
X313350Y115875D01*
X313600Y115583D01*
X313683Y115250D01*
X313600Y114917D01*
X313392Y114667D01*
X313017Y114542D01*
X312017D01*
G01X314908Y113500D02*
X315950Y116000D01*
X316992Y113500D01*
G01X316617Y114375D02*
X315283D01*
G01X318133Y113500D02*
Y116000D01*
X318967D01*
X319300Y115875D01*
X319550Y115708D01*
X319758Y115458D01*
X319925Y115167D01*
X319967Y114750D01*
X319925Y114333D01*
X319758Y114042D01*
X319550Y113792D01*
X319300Y113625D01*
X318967Y113500D01*
X318133D01*
G01X321358Y115583D02*
X321608Y115833D01*
X321900Y115958D01*
X322233Y116000D01*
X322650Y115917D01*
X322942Y115708D01*
X323025Y115458D01*
X322983Y115208D01*
X322817Y115000D01*
X321983Y114583D01*
X321608Y114292D01*
X321358Y113875D01*
X321275Y113500D01*
X323025D01*
G01X313549Y152413D02*
Y154913D01*
X314549D01*
X314882Y154788D01*
X315132Y154496D01*
X315215Y154163D01*
X315132Y153830D01*
X314924Y153580D01*
X314549Y153455D01*
X313549D01*
G01X317482Y154913D02*
Y152413D01*
G01X316524Y154913D02*
X318440D01*
G01X321499Y154705D02*
X321249Y154830D01*
X320957Y154913D01*
X320624D01*
X320249Y154788D01*
X319957Y154580D01*
X319749Y154330D01*
X319582Y153913D01*
X319540Y153538D01*
X319624Y153163D01*
X319749Y152913D01*
X319999Y152663D01*
X320290Y152496D01*
X320582Y152413D01*
X320874D01*
X321165Y152496D01*
X321415Y152621D01*
X321624Y152788D01*
G01X322765Y152913D02*
X323015Y152621D01*
X323349Y152455D01*
X323724Y152413D01*
X324057Y152455D01*
X324390Y152663D01*
X324599Y152913D01*
X324640Y153163D01*
X324557Y153455D01*
X324265Y153663D01*
X323974Y153746D01*
X323599D01*
G01X323974D02*
X324224Y153871D01*
X324432Y154080D01*
X324515Y154330D01*
X324432Y154580D01*
X324224Y154788D01*
X323849Y154913D01*
X323474Y154871D01*
X323099Y154705D01*
G01X326782Y152413D02*
X327074Y152455D01*
X327407Y152580D01*
X327615Y152788D01*
X327699Y153080D01*
X327615Y153371D01*
X327365Y153621D01*
X326990Y153746D01*
X326574D01*
X326324Y153830D01*
X326115Y154038D01*
X326032Y154330D01*
X326157Y154621D01*
X326449Y154830D01*
X326782Y154913D01*
X327115Y154830D01*
X327407Y154621D01*
X327532Y154330D01*
X327449Y154038D01*
X327240Y153830D01*
X326990Y153746D01*
X326574D01*
X326199Y153621D01*
X325949Y153371D01*
X325865Y153080D01*
X325949Y152788D01*
X326157Y152580D01*
X326490Y152455D01*
X326782Y152413D01*
G01X311500Y169500D02*
Y158300D01*
G01D02*
X329500D01*
G01D02*
Y169500D01*
G01X311500Y185500D02*
Y196700D01*
G01D02*
X329500D01*
G01D02*
Y185500D01*
G01X351500Y213100D02*
X320900D01*
Y201300D01*
X351500D01*
Y213100D01*
G01X327017Y215800D02*
X327225Y215550D01*
X327475Y215383D01*
X327767Y215300D01*
X328100Y215383D01*
X328350Y215550D01*
X328600Y215800D01*
X328683Y216133D01*
Y217800D01*
G01X330117Y215300D02*
Y217800D01*
X331117D01*
X331450Y217675D01*
X331700Y217383D01*
X331783Y217050D01*
X331700Y216717D01*
X331492Y216467D01*
X331117Y216342D01*
X330117D01*
G01X334050Y215300D02*
Y217800D01*
X333550Y217300D01*
G01Y215300D02*
X334550D01*
G01X307050Y215500D02*
Y218000D01*
X306550Y217500D01*
G01Y215500D02*
X307550D01*
G01X309608Y216333D02*
X310692D01*
G01X312458Y217583D02*
X312708Y217833D01*
X313000Y217958D01*
X313333Y218000D01*
X313750Y217917D01*
X314042Y217708D01*
X314125Y217458D01*
X314083Y217208D01*
X313917Y217000D01*
X313083Y216583D01*
X312708Y216292D01*
X312458Y215875D01*
X312375Y215500D01*
X314125D01*
G01X305800Y219500D02*
X315800D01*
Y214000D01*
X305300D01*
Y219500D01*
X305800D01*
G01X340600Y220000D02*
Y224000D01*
X333200D01*
G01X308417Y225800D02*
Y228300D01*
X309458D01*
X309792Y228175D01*
X310000Y228008D01*
X310083Y227675D01*
X310000Y227342D01*
X309750Y227133D01*
X309458Y227008D01*
X308417D01*
G01X309458D02*
X310083Y225800D01*
G01X311642Y226092D02*
X311933Y225883D01*
X312267Y225800D01*
X312600Y225883D01*
X312892Y226133D01*
X313100Y226508D01*
X313183Y226883D01*
Y227342D01*
X313100Y227717D01*
X312892Y228050D01*
X312642Y228217D01*
X312350Y228300D01*
X312017Y228217D01*
X311767Y228050D01*
X311600Y227800D01*
X311517Y227467D01*
X311600Y227175D01*
X311808Y226883D01*
X312058Y226717D01*
X312350Y226675D01*
X312683Y226758D01*
X312933Y226967D01*
X313183Y227342D01*
G01X314658Y226842D02*
X314950Y227133D01*
X315200Y227300D01*
X315533Y227383D01*
X315825Y227300D01*
X316033Y227133D01*
X316200Y226883D01*
X316242Y226592D01*
X316200Y226342D01*
X316033Y226092D01*
X315783Y225883D01*
X315492Y225800D01*
X315158Y225883D01*
X314867Y226133D01*
X314700Y226508D01*
X314658Y226925D01*
X314742Y227467D01*
X314867Y227758D01*
X315075Y228050D01*
X315367Y228258D01*
X315658Y228300D01*
X315950Y228217D01*
X316158Y228008D01*
G01X318550Y225800D02*
Y228300D01*
X318050Y227800D01*
G01Y225800D02*
X319050D01*
G01X316700Y219900D02*
Y223900D01*
X309300D01*
G01X301634Y251511D02*
Y276911D01*
G01X342334Y251511D02*
X301634D01*
G01X313734Y300697D02*
X311234D01*
Y301738D01*
X311359Y302072D01*
X311526Y302280D01*
X311859Y302363D01*
X312192Y302280D01*
X312401Y302030D01*
X312526Y301738D01*
Y300697D01*
G01Y301738D02*
X313734Y302363D01*
G01Y304547D02*
X313192Y304630D01*
X312734Y304755D01*
X312317Y304922D01*
X311859Y305130D01*
X311234Y305463D01*
Y303797D01*
G01X313234Y306813D02*
X313526Y307063D01*
X313692Y307397D01*
X313734Y307772D01*
X313692Y308105D01*
X313484Y308438D01*
X313234Y308647D01*
X312984Y308688D01*
X312692Y308605D01*
X312484Y308313D01*
X312401Y308022D01*
Y307647D01*
G01Y308022D02*
X312276Y308272D01*
X312067Y308480D01*
X311817Y308563D01*
X311567Y308480D01*
X311359Y308272D01*
X311234Y307897D01*
X311276Y307522D01*
X311442Y307147D01*
G01X311651Y310038D02*
X311401Y310288D01*
X311276Y310580D01*
X311234Y310913D01*
X311317Y311330D01*
X311526Y311622D01*
X311776Y311705D01*
X312026Y311663D01*
X312234Y311497D01*
X312651Y310663D01*
X312942Y310288D01*
X313359Y310038D01*
X313734Y309955D01*
Y311705D01*
G01X318646Y298975D02*
X314646D01*
Y291575D01*
G01X304700Y299962D02*
X300700D01*
Y292562D01*
G01X307082Y295550D02*
Y291550D01*
X314482D01*
G01X317813Y301127D02*
X315313D01*
Y302168D01*
X315438Y302502D01*
X315605Y302710D01*
X315938Y302793D01*
X316271Y302710D01*
X316480Y302460D01*
X316605Y302168D01*
Y301127D01*
G01Y302168D02*
X317813Y302793D01*
G01X317521Y304352D02*
X317730Y304643D01*
X317813Y304977D01*
X317730Y305310D01*
X317480Y305602D01*
X317105Y305810D01*
X316730Y305893D01*
X316271D01*
X315896Y305810D01*
X315563Y305602D01*
X315396Y305352D01*
X315313Y305060D01*
X315396Y304727D01*
X315563Y304477D01*
X315813Y304310D01*
X316146Y304227D01*
X316438Y304310D01*
X316730Y304518D01*
X316896Y304768D01*
X316938Y305060D01*
X316855Y305393D01*
X316646Y305643D01*
X316271Y305893D01*
G01X316771Y307368D02*
X316480Y307660D01*
X316313Y307910D01*
X316230Y308243D01*
X316313Y308535D01*
X316480Y308743D01*
X316730Y308910D01*
X317021Y308952D01*
X317271Y308910D01*
X317521Y308743D01*
X317730Y308493D01*
X317813Y308202D01*
X317730Y307868D01*
X317480Y307577D01*
X317105Y307410D01*
X316688Y307368D01*
X316146Y307452D01*
X315855Y307577D01*
X315563Y307785D01*
X315355Y308077D01*
X315313Y308368D01*
X315396Y308660D01*
X315605Y308868D01*
G01X317813Y311260D02*
X317771Y311552D01*
X317646Y311885D01*
X317438Y312093D01*
X317146Y312177D01*
X316855Y312093D01*
X316605Y311843D01*
X316480Y311468D01*
Y311052D01*
X316396Y310802D01*
X316188Y310593D01*
X315896Y310510D01*
X315605Y310635D01*
X315396Y310927D01*
X315313Y311260D01*
X315396Y311593D01*
X315605Y311885D01*
X315896Y312010D01*
X316188Y311927D01*
X316396Y311718D01*
X316480Y311468D01*
Y311052D01*
X316605Y310677D01*
X316855Y310427D01*
X317146Y310343D01*
X317438Y310427D01*
X317646Y310635D01*
X317771Y310968D01*
X317813Y311260D01*
G01X322662Y298990D02*
X318662D01*
Y291590D01*
G01X330467Y303492D02*
X330217Y303617D01*
X329925Y303700D01*
X329592D01*
X329217Y303575D01*
X328925Y303367D01*
X328717Y303117D01*
X328550Y302700D01*
X328508Y302325D01*
X328592Y301950D01*
X328717Y301700D01*
X328967Y301450D01*
X329258Y301283D01*
X329550Y301200D01*
X329842D01*
X330133Y301283D01*
X330383Y301408D01*
X330592Y301575D01*
G01X331858Y303283D02*
X332108Y303533D01*
X332400Y303658D01*
X332733Y303700D01*
X333150Y303617D01*
X333442Y303408D01*
X333525Y303158D01*
X333483Y302908D01*
X333317Y302700D01*
X332483Y302283D01*
X332108Y301992D01*
X331858Y301575D01*
X331775Y301200D01*
X333525D01*
G01X335667D02*
X335750Y301742D01*
X335875Y302200D01*
X336042Y302617D01*
X336250Y303075D01*
X336583Y303700D01*
X334917D01*
G01X339350Y301200D02*
Y303700D01*
X337808Y301908D01*
X339892D01*
G01X323037Y307529D02*
X322787Y307654D01*
X322495Y307737D01*
X322162D01*
X321787Y307612D01*
X321495Y307404D01*
X321287Y307154D01*
X321120Y306737D01*
X321078Y306362D01*
X321162Y305987D01*
X321287Y305737D01*
X321537Y305487D01*
X321828Y305320D01*
X322120Y305237D01*
X322412D01*
X322703Y305320D01*
X322953Y305445D01*
X323162Y305612D01*
G01X324428Y307320D02*
X324678Y307570D01*
X324970Y307695D01*
X325303Y307737D01*
X325720Y307654D01*
X326012Y307445D01*
X326095Y307195D01*
X326053Y306945D01*
X325887Y306737D01*
X325053Y306320D01*
X324678Y306029D01*
X324428Y305612D01*
X324345Y305237D01*
X326095D01*
G01X328320D02*
X328612Y305279D01*
X328945Y305404D01*
X329153Y305612D01*
X329237Y305904D01*
X329153Y306195D01*
X328903Y306445D01*
X328528Y306570D01*
X328112D01*
X327862Y306654D01*
X327653Y306862D01*
X327570Y307154D01*
X327695Y307445D01*
X327987Y307654D01*
X328320Y307737D01*
X328653Y307654D01*
X328945Y307445D01*
X329070Y307154D01*
X328987Y306862D01*
X328778Y306654D01*
X328528Y306570D01*
X328112D01*
X327737Y306445D01*
X327487Y306195D01*
X327403Y305904D01*
X327487Y305612D01*
X327695Y305404D01*
X328028Y305279D01*
X328320Y305237D01*
G01X330503Y305737D02*
X330753Y305445D01*
X331087Y305279D01*
X331462Y305237D01*
X331795Y305279D01*
X332128Y305487D01*
X332337Y305737D01*
X332378Y305987D01*
X332295Y306279D01*
X332003Y306487D01*
X331712Y306570D01*
X331337D01*
G01X331712D02*
X331962Y306695D01*
X332170Y306904D01*
X332253Y307154D01*
X332170Y307404D01*
X331962Y307612D01*
X331587Y307737D01*
X331212Y307695D01*
X330837Y307529D01*
G01X301634Y276911D02*
X342334D01*
G01X332141Y331880D02*
X349341D01*
Y321980D01*
X332141D01*
Y331880D01*
G01X301375Y318500D02*
X301708Y318292D01*
X302083Y318167D01*
X302417D01*
X302750Y318292D01*
X303000Y318500D01*
X303125Y318792D01*
X303042Y319084D01*
X302833Y319334D01*
X302458Y319500D01*
X301958Y319584D01*
X301667Y319750D01*
X301542Y320042D01*
X301625Y320334D01*
X301833Y320542D01*
X302125Y320667D01*
X302417D01*
X302708Y320584D01*
X302958Y320375D01*
G01X306267Y320459D02*
X306017Y320584D01*
X305725Y320667D01*
X305392D01*
X305017Y320542D01*
X304725Y320334D01*
X304517Y320084D01*
X304350Y319667D01*
X304308Y319292D01*
X304392Y318917D01*
X304517Y318667D01*
X304767Y318417D01*
X305058Y318250D01*
X305350Y318167D01*
X305642D01*
X305933Y318250D01*
X306183Y318375D01*
X306392Y318542D01*
G01X308450Y318167D02*
Y320667D01*
X307950Y320167D01*
G01Y318167D02*
X308950D01*
G01X310633Y318667D02*
X310883Y318375D01*
X311217Y318209D01*
X311592Y318167D01*
X311925Y318209D01*
X312258Y318417D01*
X312467Y318667D01*
X312508Y318917D01*
X312425Y319209D01*
X312133Y319417D01*
X311842Y319500D01*
X311467D01*
G01X311842D02*
X312092Y319625D01*
X312300Y319834D01*
X312383Y320084D01*
X312300Y320334D01*
X312092Y320542D01*
X311717Y320667D01*
X311342Y320625D01*
X310967Y320459D01*
G01X314650Y318167D02*
Y320667D01*
X314150Y320167D01*
G01Y318167D02*
X315150D01*
G01X317750Y320667D02*
X317417Y320584D01*
X317167Y320375D01*
X317000Y320125D01*
X316875Y319792D01*
X316833Y319417D01*
X316875Y319042D01*
X317000Y318709D01*
X317167Y318459D01*
X317417Y318250D01*
X317750Y318167D01*
X318083Y318250D01*
X318333Y318459D01*
X318500Y318709D01*
X318625Y319042D01*
X318667Y319417D01*
X318625Y319792D01*
X318500Y320125D01*
X318333Y320375D01*
X318083Y320584D01*
X317750Y320667D01*
G01X326374Y340413D02*
X326707Y340205D01*
X327082Y340080D01*
X327416D01*
X327749Y340205D01*
X327999Y340413D01*
X328124Y340705D01*
X328041Y340997D01*
X327832Y341247D01*
X327457Y341413D01*
X326957Y341497D01*
X326666Y341663D01*
X326541Y341955D01*
X326624Y342247D01*
X326832Y342455D01*
X327124Y342580D01*
X327416D01*
X327707Y342497D01*
X327957Y342288D01*
G01X329516Y340080D02*
Y342580D01*
X330557D01*
X330891Y342455D01*
X331099Y342288D01*
X331182Y341955D01*
X331099Y341622D01*
X330849Y341413D01*
X330557Y341288D01*
X329516D01*
G01X330557D02*
X331182Y340080D01*
G01X332741Y340372D02*
X333032Y340163D01*
X333366Y340080D01*
X333699Y340163D01*
X333991Y340413D01*
X334199Y340788D01*
X334282Y341163D01*
Y341622D01*
X334199Y341997D01*
X333991Y342330D01*
X333741Y342497D01*
X333449Y342580D01*
X333116Y342497D01*
X332866Y342330D01*
X332699Y342080D01*
X332616Y341747D01*
X332699Y341455D01*
X332907Y341163D01*
X333157Y340997D01*
X333449Y340955D01*
X333782Y341038D01*
X334032Y341247D01*
X334282Y341622D01*
G01X337049Y340080D02*
Y342580D01*
X335507Y340788D01*
X337591D01*
G01X338941Y340372D02*
X339232Y340163D01*
X339566Y340080D01*
X339899Y340163D01*
X340191Y340413D01*
X340399Y340788D01*
X340482Y341163D01*
Y341622D01*
X340399Y341997D01*
X340191Y342330D01*
X339941Y342497D01*
X339649Y342580D01*
X339316Y342497D01*
X339066Y342330D01*
X338899Y342080D01*
X338816Y341747D01*
X338899Y341455D01*
X339107Y341163D01*
X339357Y340997D01*
X339649Y340955D01*
X339982Y341038D01*
X340232Y341247D01*
X340482Y341622D01*
G01X340300Y333500D02*
Y337500D01*
X332900D01*
G01X331100Y320900D02*
Y316900D01*
X338500D01*
G01X300917Y343666D02*
Y346166D01*
X301958D01*
X302292Y346041D01*
X302500Y345874D01*
X302583Y345541D01*
X302500Y345208D01*
X302250Y344999D01*
X301958Y344874D01*
X300917D01*
G01X301958D02*
X302583Y343666D01*
G01X305350D02*
Y346166D01*
X303808Y344374D01*
X305892D01*
G01X307867Y343666D02*
X307950Y344208D01*
X308075Y344666D01*
X308242Y345083D01*
X308450Y345541D01*
X308783Y346166D01*
X307117D01*
G01X310967Y343666D02*
X311050Y344208D01*
X311175Y344666D01*
X311342Y345083D01*
X311550Y345541D01*
X311883Y346166D01*
X310217D01*
G01X306300Y330600D02*
X310300D01*
Y338000D01*
G01X320834Y334517D02*
X318334D01*
Y335558D01*
X318459Y335892D01*
X318626Y336100D01*
X318959Y336183D01*
X319292Y336100D01*
X319501Y335850D01*
X319626Y335558D01*
Y334517D01*
G01Y335558D02*
X320834Y336183D01*
G01Y338950D02*
X318334D01*
X320126Y337408D01*
Y339492D01*
G01X320834Y341550D02*
X320792Y341842D01*
X320667Y342175D01*
X320459Y342383D01*
X320167Y342467D01*
X319876Y342383D01*
X319626Y342133D01*
X319501Y341758D01*
Y341342D01*
X319417Y341092D01*
X319209Y340883D01*
X318917Y340800D01*
X318626Y340925D01*
X318417Y341217D01*
X318334Y341550D01*
X318417Y341883D01*
X318626Y342175D01*
X318917Y342300D01*
X319209Y342217D01*
X319417Y342008D01*
X319501Y341758D01*
Y341342D01*
X319626Y340967D01*
X319876Y340717D01*
X320167Y340633D01*
X320459Y340717D01*
X320667Y340925D01*
X320792Y341258D01*
X320834Y341550D01*
G01Y345150D02*
X318334D01*
X320126Y343608D01*
Y345692D01*
G01X317300Y342700D02*
X313300D01*
Y335300D01*
G01X324501Y319875D02*
X324709Y320208D01*
X324834Y320583D01*
Y320917D01*
X324709Y321250D01*
X324501Y321500D01*
X324209Y321625D01*
X323917Y321542D01*
X323667Y321333D01*
X323501Y320958D01*
X323417Y320458D01*
X323251Y320167D01*
X322959Y320042D01*
X322667Y320125D01*
X322459Y320333D01*
X322334Y320625D01*
Y320917D01*
X322417Y321208D01*
X322626Y321458D01*
G01X322542Y324767D02*
X322417Y324517D01*
X322334Y324225D01*
Y323892D01*
X322459Y323517D01*
X322667Y323225D01*
X322917Y323017D01*
X323334Y322850D01*
X323709Y322808D01*
X324084Y322892D01*
X324334Y323017D01*
X324584Y323267D01*
X324751Y323558D01*
X324834Y323850D01*
Y324142D01*
X324751Y324433D01*
X324626Y324683D01*
X324459Y324892D01*
G01X324834Y326950D02*
X322334D01*
X322834Y326450D01*
G01X324834D02*
Y327450D01*
G01X324334Y329133D02*
X324626Y329383D01*
X324792Y329717D01*
X324834Y330092D01*
X324792Y330425D01*
X324584Y330758D01*
X324334Y330967D01*
X324084Y331008D01*
X323792Y330925D01*
X323584Y330633D01*
X323501Y330342D01*
Y329967D01*
G01Y330342D02*
X323376Y330592D01*
X323167Y330800D01*
X322917Y330883D01*
X322667Y330800D01*
X322459Y330592D01*
X322334Y330217D01*
X322376Y329842D01*
X322542Y329467D01*
G01X322334Y333150D02*
X322417Y332817D01*
X322626Y332567D01*
X322876Y332400D01*
X323209Y332275D01*
X323584Y332233D01*
X323959Y332275D01*
X324292Y332400D01*
X324542Y332567D01*
X324751Y332817D01*
X324834Y333150D01*
X324751Y333483D01*
X324542Y333733D01*
X324292Y333900D01*
X323959Y334025D01*
X323584Y334067D01*
X323209Y334025D01*
X322876Y333900D01*
X322626Y333733D01*
X322417Y333483D01*
X322334Y333150D01*
G01X324334Y335333D02*
X324626Y335583D01*
X324792Y335917D01*
X324834Y336292D01*
X324792Y336625D01*
X324584Y336958D01*
X324334Y337167D01*
X324084Y337208D01*
X323792Y337125D01*
X323584Y336833D01*
X323501Y336542D01*
Y336167D01*
G01Y336542D02*
X323376Y336792D01*
X323167Y337000D01*
X322917Y337083D01*
X322667Y337000D01*
X322459Y336792D01*
X322334Y336417D01*
X322376Y336042D01*
X322542Y335667D01*
G01X318250Y475070D02*
X411500D01*
Y375340D01*
X315430D01*
Y475070D01*
X318250D01*
G01X301817Y348100D02*
Y350600D01*
X302858D01*
X303192Y350475D01*
X303400Y350308D01*
X303483Y349975D01*
X303400Y349642D01*
X303150Y349433D01*
X302858Y349308D01*
X301817D01*
G01X302858D02*
X303483Y348100D01*
G01X306250D02*
Y350600D01*
X304708Y348808D01*
X306792D01*
G01X308850Y348100D02*
X309142Y348142D01*
X309475Y348267D01*
X309683Y348475D01*
X309767Y348767D01*
X309683Y349058D01*
X309433Y349308D01*
X309058Y349433D01*
X308642D01*
X308392Y349517D01*
X308183Y349725D01*
X308100Y350017D01*
X308225Y350308D01*
X308517Y350517D01*
X308850Y350600D01*
X309183Y350517D01*
X309475Y350308D01*
X309600Y350017D01*
X309517Y349725D01*
X309308Y349517D01*
X309058Y349433D01*
X308642D01*
X308267Y349308D01*
X308017Y349058D01*
X307933Y348767D01*
X308017Y348475D01*
X308225Y348267D01*
X308558Y348142D01*
X308850Y348100D01*
G01X311950D02*
Y350600D01*
X311450Y350100D01*
G01Y348100D02*
X312450D01*
G01X325381Y397627D02*
X325256Y397377D01*
X325173Y397085D01*
Y396752D01*
X325298Y396377D01*
X325506Y396085D01*
X325756Y395877D01*
X326173Y395710D01*
X326548Y395668D01*
X326923Y395752D01*
X327173Y395877D01*
X327423Y396127D01*
X327590Y396418D01*
X327673Y396710D01*
Y397002D01*
X327590Y397293D01*
X327465Y397543D01*
X327298Y397752D01*
G01X325590Y399018D02*
X325340Y399268D01*
X325215Y399560D01*
X325173Y399893D01*
X325256Y400310D01*
X325465Y400602D01*
X325715Y400685D01*
X325965Y400643D01*
X326173Y400477D01*
X326590Y399643D01*
X326881Y399268D01*
X327298Y399018D01*
X327673Y398935D01*
Y400685D01*
G01X327173Y401993D02*
X327465Y402243D01*
X327631Y402577D01*
X327673Y402952D01*
X327631Y403285D01*
X327423Y403618D01*
X327173Y403827D01*
X326923Y403868D01*
X326631Y403785D01*
X326423Y403493D01*
X326340Y403202D01*
Y402827D01*
G01Y403202D02*
X326215Y403452D01*
X326006Y403660D01*
X325756Y403743D01*
X325506Y403660D01*
X325298Y403452D01*
X325173Y403077D01*
X325215Y402702D01*
X325381Y402327D01*
G01X327673Y406510D02*
X325173D01*
X326965Y404968D01*
Y407052D01*
G01X325381Y411627D02*
X325256Y411377D01*
X325173Y411085D01*
Y410752D01*
X325298Y410377D01*
X325506Y410085D01*
X325756Y409877D01*
X326173Y409710D01*
X326548Y409668D01*
X326923Y409752D01*
X327173Y409877D01*
X327423Y410127D01*
X327590Y410418D01*
X327673Y410710D01*
Y411002D01*
X327590Y411293D01*
X327465Y411543D01*
X327298Y411752D01*
G01X325590Y413018D02*
X325340Y413268D01*
X325215Y413560D01*
X325173Y413893D01*
X325256Y414310D01*
X325465Y414602D01*
X325715Y414685D01*
X325965Y414643D01*
X326173Y414477D01*
X326590Y413643D01*
X326881Y413268D01*
X327298Y413018D01*
X327673Y412935D01*
Y414685D01*
G01X327173Y415993D02*
X327465Y416243D01*
X327631Y416577D01*
X327673Y416952D01*
X327631Y417285D01*
X327423Y417618D01*
X327173Y417827D01*
X326923Y417868D01*
X326631Y417785D01*
X326423Y417493D01*
X326340Y417202D01*
Y416827D01*
G01Y417202D02*
X326215Y417452D01*
X326006Y417660D01*
X325756Y417743D01*
X325506Y417660D01*
X325298Y417452D01*
X325173Y417077D01*
X325215Y416702D01*
X325381Y416327D01*
G01X327298Y419093D02*
X327506Y419343D01*
X327631Y419635D01*
X327673Y420010D01*
X327590Y420385D01*
X327423Y420677D01*
X327131Y420885D01*
X326798Y420927D01*
X326465Y420843D01*
X326256Y420635D01*
X326090Y420343D01*
X326048Y420052D01*
X326090Y419760D01*
X326256Y419385D01*
X325173Y419510D01*
Y420635D01*
G01X333582Y408741D02*
X336082D01*
G01X333582Y407783D02*
Y409699D01*
G01X336082Y411008D02*
X333582D01*
Y412008D01*
X333707Y412341D01*
X333999Y412591D01*
X334332Y412674D01*
X334665Y412591D01*
X334915Y412383D01*
X335040Y412008D01*
Y411008D01*
G01X336082Y414941D02*
X333582D01*
X334082Y414441D01*
G01X336082D02*
Y415441D01*
G01X335707Y417124D02*
X335915Y417374D01*
X336040Y417666D01*
X336082Y418041D01*
X335999Y418416D01*
X335832Y418708D01*
X335540Y418916D01*
X335207Y418958D01*
X334874Y418874D01*
X334665Y418666D01*
X334499Y418374D01*
X334457Y418083D01*
X334499Y417791D01*
X334665Y417416D01*
X333582Y417541D01*
Y418666D01*
G01X336082Y421058D02*
X335540Y421141D01*
X335082Y421266D01*
X334665Y421433D01*
X334207Y421641D01*
X333582Y421974D01*
Y420308D01*
G01X329557Y404260D02*
Y406760D01*
X330598D01*
X330932Y406635D01*
X331140Y406468D01*
X331223Y406135D01*
X331140Y405802D01*
X330890Y405593D01*
X330598Y405468D01*
X329557D01*
G01X330598D02*
X331223Y404260D01*
G01X332573Y404760D02*
X332823Y404468D01*
X333157Y404302D01*
X333532Y404260D01*
X333865Y404302D01*
X334198Y404510D01*
X334407Y404760D01*
X334448Y405010D01*
X334365Y405302D01*
X334073Y405510D01*
X333782Y405593D01*
X333407D01*
G01X333782D02*
X334032Y405718D01*
X334240Y405927D01*
X334323Y406177D01*
X334240Y406427D01*
X334032Y406635D01*
X333657Y406760D01*
X333282Y406718D01*
X332907Y406552D01*
G01X336590Y404260D02*
X336882Y404302D01*
X337215Y404427D01*
X337423Y404635D01*
X337507Y404927D01*
X337423Y405218D01*
X337173Y405468D01*
X336798Y405593D01*
X336382D01*
X336132Y405677D01*
X335923Y405885D01*
X335840Y406177D01*
X335965Y406468D01*
X336257Y406677D01*
X336590Y406760D01*
X336923Y406677D01*
X337215Y406468D01*
X337340Y406177D01*
X337257Y405885D01*
X337048Y405677D01*
X336798Y405593D01*
X336382D01*
X336007Y405468D01*
X335757Y405218D01*
X335673Y404927D01*
X335757Y404635D01*
X335965Y404427D01*
X336298Y404302D01*
X336590Y404260D01*
G01X338898Y405302D02*
X339190Y405593D01*
X339440Y405760D01*
X339773Y405843D01*
X340065Y405760D01*
X340273Y405593D01*
X340440Y405343D01*
X340482Y405052D01*
X340440Y404802D01*
X340273Y404552D01*
X340023Y404343D01*
X339732Y404260D01*
X339398Y404343D01*
X339107Y404593D01*
X338940Y404968D01*
X338898Y405385D01*
X338982Y405927D01*
X339107Y406218D01*
X339315Y406510D01*
X339607Y406718D01*
X339898Y406760D01*
X340190Y406677D01*
X340398Y406468D01*
G01X329557Y400160D02*
Y402660D01*
X330598D01*
X330932Y402535D01*
X331140Y402368D01*
X331223Y402035D01*
X331140Y401702D01*
X330890Y401493D01*
X330598Y401368D01*
X329557D01*
G01X330598D02*
X331223Y400160D01*
G01X332573Y400660D02*
X332823Y400368D01*
X333157Y400202D01*
X333532Y400160D01*
X333865Y400202D01*
X334198Y400410D01*
X334407Y400660D01*
X334448Y400910D01*
X334365Y401202D01*
X334073Y401410D01*
X333782Y401493D01*
X333407D01*
G01X333782D02*
X334032Y401618D01*
X334240Y401827D01*
X334323Y402077D01*
X334240Y402327D01*
X334032Y402535D01*
X333657Y402660D01*
X333282Y402618D01*
X332907Y402452D01*
G01X336590Y400160D02*
X336882Y400202D01*
X337215Y400327D01*
X337423Y400535D01*
X337507Y400827D01*
X337423Y401118D01*
X337173Y401368D01*
X336798Y401493D01*
X336382D01*
X336132Y401577D01*
X335923Y401785D01*
X335840Y402077D01*
X335965Y402368D01*
X336257Y402577D01*
X336590Y402660D01*
X336923Y402577D01*
X337215Y402368D01*
X337340Y402077D01*
X337257Y401785D01*
X337048Y401577D01*
X336798Y401493D01*
X336382D01*
X336007Y401368D01*
X335757Y401118D01*
X335673Y400827D01*
X335757Y400535D01*
X335965Y400327D01*
X336298Y400202D01*
X336590Y400160D01*
G01X338773Y400535D02*
X339023Y400327D01*
X339315Y400202D01*
X339690Y400160D01*
X340065Y400243D01*
X340357Y400410D01*
X340565Y400702D01*
X340607Y401035D01*
X340523Y401368D01*
X340315Y401577D01*
X340023Y401743D01*
X339732Y401785D01*
X339440Y401743D01*
X339065Y401577D01*
X339190Y402660D01*
X340315D01*
G01X331048Y387127D02*
X330923Y386877D01*
X330840Y386585D01*
Y386252D01*
X330965Y385877D01*
X331173Y385585D01*
X331423Y385377D01*
X331840Y385210D01*
X332215Y385168D01*
X332590Y385252D01*
X332840Y385377D01*
X333090Y385627D01*
X333257Y385918D01*
X333340Y386210D01*
Y386502D01*
X333257Y386793D01*
X333132Y387043D01*
X332965Y387252D01*
G01X332298Y388518D02*
X332007Y388810D01*
X331840Y389060D01*
X331757Y389393D01*
X331840Y389685D01*
X332007Y389893D01*
X332257Y390060D01*
X332548Y390102D01*
X332798Y390060D01*
X333048Y389893D01*
X333257Y389643D01*
X333340Y389352D01*
X333257Y389018D01*
X333007Y388727D01*
X332632Y388560D01*
X332215Y388518D01*
X331673Y388602D01*
X331382Y388727D01*
X331090Y388935D01*
X330882Y389227D01*
X330840Y389518D01*
X330923Y389810D01*
X331132Y390018D01*
G01X331257Y391618D02*
X331007Y391868D01*
X330882Y392160D01*
X330840Y392493D01*
X330923Y392910D01*
X331132Y393202D01*
X331382Y393285D01*
X331632Y393243D01*
X331840Y393077D01*
X332257Y392243D01*
X332548Y391868D01*
X332965Y391618D01*
X333340Y391535D01*
Y393285D01*
G01X332840Y394593D02*
X333132Y394843D01*
X333298Y395177D01*
X333340Y395552D01*
X333298Y395885D01*
X333090Y396218D01*
X332840Y396427D01*
X332590Y396468D01*
X332298Y396385D01*
X332090Y396093D01*
X332007Y395802D01*
Y395427D01*
G01Y395802D02*
X331882Y396052D01*
X331673Y396260D01*
X331423Y396343D01*
X331173Y396260D01*
X330965Y396052D01*
X330840Y395677D01*
X330882Y395302D01*
X331048Y394927D01*
G01X321015Y438332D02*
Y440832D01*
X322056D01*
X322390Y440707D01*
X322598Y440540D01*
X322681Y440207D01*
X322598Y439874D01*
X322348Y439665D01*
X322056Y439540D01*
X321015D01*
G01X322056D02*
X322681Y438332D01*
G01X324031Y438832D02*
X324281Y438540D01*
X324615Y438374D01*
X324990Y438332D01*
X325323Y438374D01*
X325656Y438582D01*
X325865Y438832D01*
X325906Y439082D01*
X325823Y439374D01*
X325531Y439582D01*
X325240Y439665D01*
X324865D01*
G01X325240D02*
X325490Y439790D01*
X325698Y439999D01*
X325781Y440249D01*
X325698Y440499D01*
X325490Y440707D01*
X325115Y440832D01*
X324740Y440790D01*
X324365Y440624D01*
G01X327340Y438624D02*
X327631Y438415D01*
X327965Y438332D01*
X328298Y438415D01*
X328590Y438665D01*
X328798Y439040D01*
X328881Y439415D01*
Y439874D01*
X328798Y440249D01*
X328590Y440582D01*
X328340Y440749D01*
X328048Y440832D01*
X327715Y440749D01*
X327465Y440582D01*
X327298Y440332D01*
X327215Y439999D01*
X327298Y439707D01*
X327506Y439415D01*
X327756Y439249D01*
X328048Y439207D01*
X328381Y439290D01*
X328631Y439499D01*
X328881Y439874D01*
G01X331065Y438332D02*
X331148Y438874D01*
X331273Y439332D01*
X331440Y439749D01*
X331648Y440207D01*
X331981Y440832D01*
X330315D01*
G01X321079Y434134D02*
Y436634D01*
X322120D01*
X322454Y436509D01*
X322662Y436342D01*
X322745Y436009D01*
X322662Y435676D01*
X322412Y435467D01*
X322120Y435342D01*
X321079D01*
G01X322120D02*
X322745Y434134D01*
G01X324095Y434634D02*
X324345Y434342D01*
X324679Y434176D01*
X325054Y434134D01*
X325387Y434176D01*
X325720Y434384D01*
X325929Y434634D01*
X325970Y434884D01*
X325887Y435176D01*
X325595Y435384D01*
X325304Y435467D01*
X324929D01*
G01X325304D02*
X325554Y435592D01*
X325762Y435801D01*
X325845Y436051D01*
X325762Y436301D01*
X325554Y436509D01*
X325179Y436634D01*
X324804Y436592D01*
X324429Y436426D01*
G01X327404Y434426D02*
X327695Y434217D01*
X328029Y434134D01*
X328362Y434217D01*
X328654Y434467D01*
X328862Y434842D01*
X328945Y435217D01*
Y435676D01*
X328862Y436051D01*
X328654Y436384D01*
X328404Y436551D01*
X328112Y436634D01*
X327779Y436551D01*
X327529Y436384D01*
X327362Y436134D01*
X327279Y435801D01*
X327362Y435509D01*
X327570Y435217D01*
X327820Y435051D01*
X328112Y435009D01*
X328445Y435092D01*
X328695Y435301D01*
X328945Y435676D01*
G01X331212Y434134D02*
X331504Y434176D01*
X331837Y434301D01*
X332045Y434509D01*
X332129Y434801D01*
X332045Y435092D01*
X331795Y435342D01*
X331420Y435467D01*
X331004D01*
X330754Y435551D01*
X330545Y435759D01*
X330462Y436051D01*
X330587Y436342D01*
X330879Y436551D01*
X331212Y436634D01*
X331545Y436551D01*
X331837Y436342D01*
X331962Y436051D01*
X331879Y435759D01*
X331670Y435551D01*
X331420Y435467D01*
X331004D01*
X330629Y435342D01*
X330379Y435092D01*
X330295Y434801D01*
X330379Y434509D01*
X330587Y434301D01*
X330920Y434176D01*
X331212Y434134D01*
G01X328623Y459720D02*
Y467720D01*
X330957D01*
X331890Y467320D01*
X332590Y466787D01*
X333173Y465987D01*
X333640Y465053D01*
X333757Y463720D01*
X333640Y462387D01*
X333173Y461453D01*
X332590Y460653D01*
X331890Y460120D01*
X330957Y459720D01*
X328623D01*
G01X300962Y477800D02*
Y467800D01*
G01X327617Y451900D02*
Y454400D01*
X328658D01*
X328992Y454275D01*
X329200Y454108D01*
X329283Y453775D01*
X329200Y453442D01*
X328950Y453233D01*
X328658Y453108D01*
X327617D01*
G01X328658D02*
X329283Y451900D01*
G01X330633Y452400D02*
X330883Y452108D01*
X331217Y451942D01*
X331592Y451900D01*
X331925Y451942D01*
X332258Y452150D01*
X332467Y452400D01*
X332508Y452650D01*
X332425Y452942D01*
X332133Y453150D01*
X331842Y453233D01*
X331467D01*
G01X331842D02*
X332092Y453358D01*
X332300Y453567D01*
X332383Y453817D01*
X332300Y454067D01*
X332092Y454275D01*
X331717Y454400D01*
X331342Y454358D01*
X330967Y454192D01*
G01X333942Y452192D02*
X334233Y451983D01*
X334567Y451900D01*
X334900Y451983D01*
X335192Y452233D01*
X335400Y452608D01*
X335483Y452983D01*
Y453442D01*
X335400Y453817D01*
X335192Y454150D01*
X334942Y454317D01*
X334650Y454400D01*
X334317Y454317D01*
X334067Y454150D01*
X333900Y453900D01*
X333817Y453567D01*
X333900Y453275D01*
X334108Y452983D01*
X334358Y452817D01*
X334650Y452775D01*
X334983Y452858D01*
X335233Y453067D01*
X335483Y453442D01*
G01X337042Y452192D02*
X337333Y451983D01*
X337667Y451900D01*
X338000Y451983D01*
X338292Y452233D01*
X338500Y452608D01*
X338583Y452983D01*
Y453442D01*
X338500Y453817D01*
X338292Y454150D01*
X338042Y454317D01*
X337750Y454400D01*
X337417Y454317D01*
X337167Y454150D01*
X337000Y453900D01*
X336917Y453567D01*
X337000Y453275D01*
X337208Y452983D01*
X337458Y452817D01*
X337750Y452775D01*
X338083Y452858D01*
X338333Y453067D01*
X338583Y453442D01*
G01X322507Y449752D02*
X322257Y449877D01*
X321965Y449960D01*
X321632D01*
X321257Y449835D01*
X320965Y449627D01*
X320757Y449377D01*
X320590Y448960D01*
X320548Y448585D01*
X320632Y448210D01*
X320757Y447960D01*
X321007Y447710D01*
X321298Y447543D01*
X321590Y447460D01*
X321882D01*
X322173Y447543D01*
X322423Y447668D01*
X322632Y447835D01*
G01X323898Y449543D02*
X324148Y449793D01*
X324440Y449918D01*
X324773Y449960D01*
X325190Y449877D01*
X325482Y449668D01*
X325565Y449418D01*
X325523Y449168D01*
X325357Y448960D01*
X324523Y448543D01*
X324148Y448252D01*
X323898Y447835D01*
X323815Y447460D01*
X325565D01*
G01X326873Y447960D02*
X327123Y447668D01*
X327457Y447502D01*
X327832Y447460D01*
X328165Y447502D01*
X328498Y447710D01*
X328707Y447960D01*
X328748Y448210D01*
X328665Y448502D01*
X328373Y448710D01*
X328082Y448793D01*
X327707D01*
G01X328082D02*
X328332Y448918D01*
X328540Y449127D01*
X328623Y449377D01*
X328540Y449627D01*
X328332Y449835D01*
X327957Y449960D01*
X327582Y449918D01*
X327207Y449752D01*
G01X329973Y447960D02*
X330223Y447668D01*
X330557Y447502D01*
X330932Y447460D01*
X331265Y447502D01*
X331598Y447710D01*
X331807Y447960D01*
X331848Y448210D01*
X331765Y448502D01*
X331473Y448710D01*
X331182Y448793D01*
X330807D01*
G01X331182D02*
X331432Y448918D01*
X331640Y449127D01*
X331723Y449377D01*
X331640Y449627D01*
X331432Y449835D01*
X331057Y449960D01*
X330682Y449918D01*
X330307Y449752D01*
G01X304833Y482498D02*
X306625D01*
X307000Y482665D01*
X307250Y482998D01*
X307333Y483415D01*
X307250Y483832D01*
X307000Y484165D01*
X306625Y484332D01*
X304833D01*
G01X306958Y485598D02*
X307166Y485848D01*
X307291Y486140D01*
X307333Y486515D01*
X307250Y486890D01*
X307083Y487182D01*
X306791Y487390D01*
X306458Y487432D01*
X306125Y487348D01*
X305916Y487140D01*
X305750Y486848D01*
X305708Y486557D01*
X305750Y486265D01*
X305916Y485890D01*
X304833Y486015D01*
Y487140D01*
G01X305250Y488823D02*
X305000Y489073D01*
X304875Y489365D01*
X304833Y489698D01*
X304916Y490115D01*
X305125Y490407D01*
X305375Y490490D01*
X305625Y490448D01*
X305833Y490282D01*
X306250Y489448D01*
X306541Y489073D01*
X306958Y488823D01*
X307333Y488740D01*
Y490490D01*
G01X300611Y503619D02*
Y506119D01*
X301652D01*
X301986Y505994D01*
X302194Y505827D01*
X302277Y505494D01*
X302194Y505161D01*
X301944Y504952D01*
X301652Y504827D01*
X300611D01*
G01X301652D02*
X302277Y503619D01*
G01X305044D02*
Y506119D01*
X303502Y504327D01*
X305586D01*
G01X306852Y505702D02*
X307102Y505952D01*
X307394Y506077D01*
X307727Y506119D01*
X308144Y506036D01*
X308436Y505827D01*
X308519Y505577D01*
X308477Y505327D01*
X308311Y505119D01*
X307477Y504702D01*
X307102Y504411D01*
X306852Y503994D01*
X306769Y503619D01*
X308519D01*
G01X309952Y504661D02*
X310244Y504952D01*
X310494Y505119D01*
X310827Y505202D01*
X311119Y505119D01*
X311327Y504952D01*
X311494Y504702D01*
X311536Y504411D01*
X311494Y504161D01*
X311327Y503911D01*
X311077Y503702D01*
X310786Y503619D01*
X310452Y503702D01*
X310161Y503952D01*
X309994Y504327D01*
X309952Y504744D01*
X310036Y505286D01*
X310161Y505577D01*
X310369Y505869D01*
X310661Y506077D01*
X310952Y506119D01*
X311244Y506036D01*
X311452Y505827D01*
G01X309041Y484332D02*
X308916Y484082D01*
X308833Y483790D01*
Y483457D01*
X308958Y483082D01*
X309166Y482790D01*
X309416Y482582D01*
X309833Y482415D01*
X310208Y482373D01*
X310583Y482457D01*
X310833Y482582D01*
X311083Y482832D01*
X311250Y483123D01*
X311333Y483415D01*
Y483707D01*
X311250Y483998D01*
X311125Y484248D01*
X310958Y484457D01*
G01X309250Y485723D02*
X309000Y485973D01*
X308875Y486265D01*
X308833Y486598D01*
X308916Y487015D01*
X309125Y487307D01*
X309375Y487390D01*
X309625Y487348D01*
X309833Y487182D01*
X310250Y486348D01*
X310541Y485973D01*
X310958Y485723D01*
X311333Y485640D01*
Y487390D01*
G01Y489615D02*
X311291Y489907D01*
X311166Y490240D01*
X310958Y490448D01*
X310666Y490532D01*
X310375Y490448D01*
X310125Y490198D01*
X310000Y489823D01*
Y489407D01*
X309916Y489157D01*
X309708Y488948D01*
X309416Y488865D01*
X309125Y488990D01*
X308916Y489282D01*
X308833Y489615D01*
X308916Y489948D01*
X309125Y490240D01*
X309416Y490365D01*
X309708Y490282D01*
X309916Y490073D01*
X310000Y489823D01*
Y489407D01*
X310125Y489032D01*
X310375Y488782D01*
X310666Y488698D01*
X310958Y488782D01*
X311166Y488990D01*
X311291Y489323D01*
X311333Y489615D01*
G01Y492715D02*
X308833D01*
X309333Y492215D01*
G01X311333D02*
Y493215D01*
G01X302420Y510264D02*
X302170Y510389D01*
X301878Y510472D01*
X301545D01*
X301170Y510347D01*
X300878Y510139D01*
X300670Y509889D01*
X300503Y509472D01*
X300461Y509097D01*
X300545Y508722D01*
X300670Y508472D01*
X300920Y508222D01*
X301211Y508055D01*
X301503Y507972D01*
X301795D01*
X302086Y508055D01*
X302336Y508180D01*
X302545Y508347D01*
G01X303811Y510055D02*
X304061Y510305D01*
X304353Y510430D01*
X304686Y510472D01*
X305103Y510389D01*
X305395Y510180D01*
X305478Y509930D01*
X305436Y509680D01*
X305270Y509472D01*
X304436Y509055D01*
X304061Y508764D01*
X303811Y508347D01*
X303728Y507972D01*
X305478D01*
G01X307620D02*
X307703Y508514D01*
X307828Y508972D01*
X307995Y509389D01*
X308203Y509847D01*
X308536Y510472D01*
X306870D01*
G01X310095Y508264D02*
X310386Y508055D01*
X310720Y507972D01*
X311053Y508055D01*
X311345Y508305D01*
X311553Y508680D01*
X311636Y509055D01*
Y509514D01*
X311553Y509889D01*
X311345Y510222D01*
X311095Y510389D01*
X310803Y510472D01*
X310470Y510389D01*
X310220Y510222D01*
X310053Y509972D01*
X309970Y509639D01*
X310053Y509347D01*
X310261Y509055D01*
X310511Y508889D01*
X310803Y508847D01*
X311136Y508930D01*
X311386Y509139D01*
X311636Y509514D01*
G01X325022Y537155D02*
Y539655D01*
X326063D01*
X326397Y539530D01*
X326605Y539363D01*
X326688Y539030D01*
X326605Y538697D01*
X326355Y538488D01*
X326063Y538363D01*
X325022D01*
G01X326063D02*
X326688Y537155D01*
G01X328038Y537655D02*
X328288Y537363D01*
X328622Y537197D01*
X328997Y537155D01*
X329330Y537197D01*
X329663Y537405D01*
X329872Y537655D01*
X329913Y537905D01*
X329830Y538197D01*
X329538Y538405D01*
X329247Y538488D01*
X328872D01*
G01X329247D02*
X329497Y538613D01*
X329705Y538822D01*
X329788Y539072D01*
X329705Y539322D01*
X329497Y539530D01*
X329122Y539655D01*
X328747Y539613D01*
X328372Y539447D01*
G01X332055Y539655D02*
X331722Y539572D01*
X331472Y539363D01*
X331305Y539113D01*
X331180Y538780D01*
X331138Y538405D01*
X331180Y538030D01*
X331305Y537697D01*
X331472Y537447D01*
X331722Y537238D01*
X332055Y537155D01*
X332388Y537238D01*
X332638Y537447D01*
X332805Y537697D01*
X332930Y538030D01*
X332972Y538405D01*
X332930Y538780D01*
X332805Y539113D01*
X332638Y539363D01*
X332388Y539572D01*
X332055Y539655D01*
G01X334447Y537447D02*
X334738Y537238D01*
X335072Y537155D01*
X335405Y537238D01*
X335697Y537488D01*
X335905Y537863D01*
X335988Y538238D01*
Y538697D01*
X335905Y539072D01*
X335697Y539405D01*
X335447Y539572D01*
X335155Y539655D01*
X334822Y539572D01*
X334572Y539405D01*
X334405Y539155D01*
X334322Y538822D01*
X334405Y538530D01*
X334613Y538238D01*
X334863Y538072D01*
X335155Y538030D01*
X335488Y538113D01*
X335738Y538322D01*
X335988Y538697D01*
G01X337547Y537447D02*
X337838Y537238D01*
X338172Y537155D01*
X338505Y537238D01*
X338797Y537488D01*
X339005Y537863D01*
X339088Y538238D01*
Y538697D01*
X339005Y539072D01*
X338797Y539405D01*
X338547Y539572D01*
X338255Y539655D01*
X337922Y539572D01*
X337672Y539405D01*
X337505Y539155D01*
X337422Y538822D01*
X337505Y538530D01*
X337713Y538238D01*
X337963Y538072D01*
X338255Y538030D01*
X338588Y538113D01*
X338838Y538322D01*
X339088Y538697D01*
G01X313700Y540300D02*
Y536300D01*
X321100D01*
G01X325022Y541155D02*
Y543655D01*
X326063D01*
X326397Y543530D01*
X326605Y543363D01*
X326688Y543030D01*
X326605Y542697D01*
X326355Y542488D01*
X326063Y542363D01*
X325022D01*
G01X326063D02*
X326688Y541155D01*
G01X328038Y541530D02*
X328288Y541322D01*
X328580Y541197D01*
X328955Y541155D01*
X329330Y541238D01*
X329622Y541405D01*
X329830Y541697D01*
X329872Y542030D01*
X329788Y542363D01*
X329580Y542572D01*
X329288Y542738D01*
X328997Y542780D01*
X328705Y542738D01*
X328330Y542572D01*
X328455Y543655D01*
X329580D01*
G01X331972Y541155D02*
X332055Y541697D01*
X332180Y542155D01*
X332347Y542572D01*
X332555Y543030D01*
X332888Y543655D01*
X331222D01*
G01X335072Y541155D02*
X335155Y541697D01*
X335280Y542155D01*
X335447Y542572D01*
X335655Y543030D01*
X335988Y543655D01*
X334322D01*
G01X337463Y543238D02*
X337713Y543488D01*
X338005Y543613D01*
X338338Y543655D01*
X338755Y543572D01*
X339047Y543363D01*
X339130Y543113D01*
X339088Y542863D01*
X338922Y542655D01*
X338088Y542238D01*
X337713Y541947D01*
X337463Y541530D01*
X337380Y541155D01*
X339130D01*
G01X321100Y540500D02*
Y544500D01*
X313700D01*
G01X326772Y535447D02*
X326522Y535572D01*
X326230Y535655D01*
X325897D01*
X325522Y535530D01*
X325230Y535322D01*
X325022Y535072D01*
X324855Y534655D01*
X324813Y534280D01*
X324897Y533905D01*
X325022Y533655D01*
X325272Y533405D01*
X325563Y533238D01*
X325855Y533155D01*
X326147D01*
X326438Y533238D01*
X326688Y533363D01*
X326897Y533530D01*
G01X328955Y533155D02*
X329247Y533197D01*
X329580Y533322D01*
X329788Y533530D01*
X329872Y533822D01*
X329788Y534113D01*
X329538Y534363D01*
X329163Y534488D01*
X328747D01*
X328497Y534572D01*
X328288Y534780D01*
X328205Y535072D01*
X328330Y535363D01*
X328622Y535572D01*
X328955Y535655D01*
X329288Y535572D01*
X329580Y535363D01*
X329705Y535072D01*
X329622Y534780D01*
X329413Y534572D01*
X329163Y534488D01*
X328747D01*
X328372Y534363D01*
X328122Y534113D01*
X328038Y533822D01*
X328122Y533530D01*
X328330Y533322D01*
X328663Y533197D01*
X328955Y533155D01*
G01X332055Y535655D02*
X331722Y535572D01*
X331472Y535363D01*
X331305Y535113D01*
X331180Y534780D01*
X331138Y534405D01*
X331180Y534030D01*
X331305Y533697D01*
X331472Y533447D01*
X331722Y533238D01*
X332055Y533155D01*
X332388Y533238D01*
X332638Y533447D01*
X332805Y533697D01*
X332930Y534030D01*
X332972Y534405D01*
X332930Y534780D01*
X332805Y535113D01*
X332638Y535363D01*
X332388Y535572D01*
X332055Y535655D01*
G01X335155Y533155D02*
X335447Y533197D01*
X335780Y533322D01*
X335988Y533530D01*
X336072Y533822D01*
X335988Y534113D01*
X335738Y534363D01*
X335363Y534488D01*
X334947D01*
X334697Y534572D01*
X334488Y534780D01*
X334405Y535072D01*
X334530Y535363D01*
X334822Y535572D01*
X335155Y535655D01*
X335488Y535572D01*
X335780Y535363D01*
X335905Y535072D01*
X335822Y534780D01*
X335613Y534572D01*
X335363Y534488D01*
X334947D01*
X334572Y534363D01*
X334322Y534113D01*
X334238Y533822D01*
X334322Y533530D01*
X334530Y533322D01*
X334863Y533197D01*
X335155Y533155D01*
G01X337547Y533447D02*
X337838Y533238D01*
X338172Y533155D01*
X338505Y533238D01*
X338797Y533488D01*
X339005Y533863D01*
X339088Y534238D01*
Y534697D01*
X339005Y535072D01*
X338797Y535405D01*
X338547Y535572D01*
X338255Y535655D01*
X337922Y535572D01*
X337672Y535405D01*
X337505Y535155D01*
X337422Y534822D01*
X337505Y534530D01*
X337713Y534238D01*
X337963Y534072D01*
X338255Y534030D01*
X338588Y534113D01*
X338838Y534322D01*
X339088Y534697D01*
G01X302979Y576865D02*
Y579365D01*
X304020D01*
X304354Y579240D01*
X304562Y579073D01*
X304645Y578740D01*
X304562Y578407D01*
X304312Y578198D01*
X304020Y578073D01*
X302979D01*
G01X304020D02*
X304645Y576865D01*
G01X306912D02*
Y579365D01*
X306412Y578865D01*
G01Y576865D02*
X307412D01*
G01X309304Y577157D02*
X309595Y576948D01*
X309929Y576865D01*
X310262Y576948D01*
X310554Y577198D01*
X310762Y577573D01*
X310845Y577948D01*
Y578407D01*
X310762Y578782D01*
X310554Y579115D01*
X310304Y579282D01*
X310012Y579365D01*
X309679Y579282D01*
X309429Y579115D01*
X309262Y578865D01*
X309179Y578532D01*
X309262Y578240D01*
X309470Y577948D01*
X309720Y577782D01*
X310012Y577740D01*
X310345Y577823D01*
X310595Y578032D01*
X310845Y578407D01*
G01X313029Y576865D02*
X313112Y577407D01*
X313237Y577865D01*
X313404Y578282D01*
X313612Y578740D01*
X313945Y579365D01*
X312279D01*
G01X302979Y581865D02*
Y584365D01*
X304020D01*
X304354Y584240D01*
X304562Y584073D01*
X304645Y583740D01*
X304562Y583407D01*
X304312Y583198D01*
X304020Y583073D01*
X302979D01*
G01X304020D02*
X304645Y581865D01*
G01X306912D02*
Y584365D01*
X306412Y583865D01*
G01Y581865D02*
X307412D01*
G01X309304Y582157D02*
X309595Y581948D01*
X309929Y581865D01*
X310262Y581948D01*
X310554Y582198D01*
X310762Y582573D01*
X310845Y582948D01*
Y583407D01*
X310762Y583782D01*
X310554Y584115D01*
X310304Y584282D01*
X310012Y584365D01*
X309679Y584282D01*
X309429Y584115D01*
X309262Y583865D01*
X309179Y583532D01*
X309262Y583240D01*
X309470Y582948D01*
X309720Y582782D01*
X310012Y582740D01*
X310345Y582823D01*
X310595Y583032D01*
X310845Y583407D01*
G01X313112Y581865D02*
X313404Y581907D01*
X313737Y582032D01*
X313945Y582240D01*
X314029Y582532D01*
X313945Y582823D01*
X313695Y583073D01*
X313320Y583198D01*
X312904D01*
X312654Y583282D01*
X312445Y583490D01*
X312362Y583782D01*
X312487Y584073D01*
X312779Y584282D01*
X313112Y584365D01*
X313445Y584282D01*
X313737Y584073D01*
X313862Y583782D01*
X313779Y583490D01*
X313570Y583282D01*
X313320Y583198D01*
X312904D01*
X312529Y583073D01*
X312279Y582823D01*
X312195Y582532D01*
X312279Y582240D01*
X312487Y582032D01*
X312820Y581907D01*
X313112Y581865D01*
G01X302979Y587365D02*
Y589865D01*
X304020D01*
X304354Y589740D01*
X304562Y589573D01*
X304645Y589240D01*
X304562Y588907D01*
X304312Y588698D01*
X304020Y588573D01*
X302979D01*
G01X304020D02*
X304645Y587365D01*
G01X306912D02*
Y589865D01*
X306412Y589365D01*
G01Y587365D02*
X307412D01*
G01X309304Y587657D02*
X309595Y587448D01*
X309929Y587365D01*
X310262Y587448D01*
X310554Y587698D01*
X310762Y588073D01*
X310845Y588448D01*
Y588907D01*
X310762Y589282D01*
X310554Y589615D01*
X310304Y589782D01*
X310012Y589865D01*
X309679Y589782D01*
X309429Y589615D01*
X309262Y589365D01*
X309179Y589032D01*
X309262Y588740D01*
X309470Y588448D01*
X309720Y588282D01*
X310012Y588240D01*
X310345Y588323D01*
X310595Y588532D01*
X310845Y588907D01*
G01X312404Y587657D02*
X312695Y587448D01*
X313029Y587365D01*
X313362Y587448D01*
X313654Y587698D01*
X313862Y588073D01*
X313945Y588448D01*
Y588907D01*
X313862Y589282D01*
X313654Y589615D01*
X313404Y589782D01*
X313112Y589865D01*
X312779Y589782D01*
X312529Y589615D01*
X312362Y589365D01*
X312279Y589032D01*
X312362Y588740D01*
X312570Y588448D01*
X312820Y588282D01*
X313112Y588240D01*
X313445Y588323D01*
X313695Y588532D01*
X313945Y588907D01*
G01X313719Y708077D02*
X313469Y708202D01*
X313177Y708285D01*
X312844D01*
X312469Y708160D01*
X312177Y707952D01*
X311969Y707702D01*
X311802Y707285D01*
X311760Y706910D01*
X311844Y706535D01*
X311969Y706285D01*
X312219Y706035D01*
X312510Y705868D01*
X312802Y705785D01*
X313094D01*
X313385Y705868D01*
X313635Y705993D01*
X313844Y706160D01*
G01X316402Y705785D02*
Y708285D01*
X314860Y706493D01*
X316944D01*
G01X319002Y705785D02*
Y708285D01*
X318502Y707785D01*
G01Y705785D02*
X319502D01*
G01X322102Y708285D02*
X321769Y708202D01*
X321519Y707993D01*
X321352Y707743D01*
X321227Y707410D01*
X321185Y707035D01*
X321227Y706660D01*
X321352Y706327D01*
X321519Y706077D01*
X321769Y705868D01*
X322102Y705785D01*
X322435Y705868D01*
X322685Y706077D01*
X322852Y706327D01*
X322977Y706660D01*
X323019Y707035D01*
X322977Y707410D01*
X322852Y707743D01*
X322685Y707993D01*
X322435Y708202D01*
X322102Y708285D01*
G01X325202Y705785D02*
X325494Y705827D01*
X325827Y705952D01*
X326035Y706160D01*
X326119Y706452D01*
X326035Y706743D01*
X325785Y706993D01*
X325410Y707118D01*
X324994D01*
X324744Y707202D01*
X324535Y707410D01*
X324452Y707702D01*
X324577Y707993D01*
X324869Y708202D01*
X325202Y708285D01*
X325535Y708202D01*
X325827Y707993D01*
X325952Y707702D01*
X325869Y707410D01*
X325660Y707202D01*
X325410Y707118D01*
X324994D01*
X324619Y706993D01*
X324369Y706743D01*
X324285Y706452D01*
X324369Y706160D01*
X324577Y705952D01*
X324910Y705827D01*
X325202Y705785D01*
G01X306406Y753398D02*
Y739398D01*
G01X312406Y725098D02*
X308406D01*
Y717698D01*
G01Y725098D02*
X304406D01*
Y717698D01*
G01Y725098D02*
X300406D01*
Y717698D01*
G01X316500Y725200D02*
X312500D01*
Y717800D01*
G01X302000Y774500D02*
X306000D01*
Y781900D01*
G01X310216Y777873D02*
X307716D01*
Y778914D01*
X307841Y779248D01*
X308008Y779456D01*
X308341Y779539D01*
X308674Y779456D01*
X308883Y779206D01*
X309008Y778914D01*
Y777873D01*
G01Y778914D02*
X310216Y779539D01*
G01Y781723D02*
X309674Y781806D01*
X309216Y781931D01*
X308799Y782098D01*
X308341Y782306D01*
X307716Y782639D01*
Y780973D01*
G01X309924Y784198D02*
X310133Y784489D01*
X310216Y784823D01*
X310133Y785156D01*
X309883Y785448D01*
X309508Y785656D01*
X309133Y785739D01*
X308674D01*
X308299Y785656D01*
X307966Y785448D01*
X307799Y785198D01*
X307716Y784906D01*
X307799Y784573D01*
X307966Y784323D01*
X308216Y784156D01*
X308549Y784073D01*
X308841Y784156D01*
X309133Y784364D01*
X309299Y784614D01*
X309341Y784906D01*
X309258Y785239D01*
X309049Y785489D01*
X308674Y785739D01*
G01X309174Y787214D02*
X308883Y787506D01*
X308716Y787756D01*
X308633Y788089D01*
X308716Y788381D01*
X308883Y788589D01*
X309133Y788756D01*
X309424Y788798D01*
X309674Y788756D01*
X309924Y788589D01*
X310133Y788339D01*
X310216Y788048D01*
X310133Y787714D01*
X309883Y787423D01*
X309508Y787256D01*
X309091Y787214D01*
X308549Y787298D01*
X308258Y787423D01*
X307966Y787631D01*
X307758Y787923D01*
X307716Y788214D01*
X307799Y788506D01*
X308008Y788714D01*
G01X309716Y790189D02*
X310008Y790439D01*
X310174Y790773D01*
X310216Y791148D01*
X310174Y791481D01*
X309966Y791814D01*
X309716Y792023D01*
X309466Y792064D01*
X309174Y791981D01*
X308966Y791689D01*
X308883Y791398D01*
Y791023D01*
G01Y791398D02*
X308758Y791648D01*
X308549Y791856D01*
X308299Y791939D01*
X308049Y791856D01*
X307841Y791648D01*
X307716Y791273D01*
X307758Y790898D01*
X307924Y790523D01*
G01X305406Y766698D02*
X309406D01*
Y774098D01*
G01X314216Y777873D02*
X311716D01*
Y778914D01*
X311841Y779248D01*
X312008Y779456D01*
X312341Y779539D01*
X312674Y779456D01*
X312883Y779206D01*
X313008Y778914D01*
Y777873D01*
G01Y778914D02*
X314216Y779539D01*
G01Y781723D02*
X313674Y781806D01*
X313216Y781931D01*
X312799Y782098D01*
X312341Y782306D01*
X311716Y782639D01*
Y780973D01*
G01X313924Y784198D02*
X314133Y784489D01*
X314216Y784823D01*
X314133Y785156D01*
X313883Y785448D01*
X313508Y785656D01*
X313133Y785739D01*
X312674D01*
X312299Y785656D01*
X311966Y785448D01*
X311799Y785198D01*
X311716Y784906D01*
X311799Y784573D01*
X311966Y784323D01*
X312216Y784156D01*
X312549Y784073D01*
X312841Y784156D01*
X313133Y784364D01*
X313299Y784614D01*
X313341Y784906D01*
X313258Y785239D01*
X313049Y785489D01*
X312674Y785739D01*
G01X314216Y788506D02*
X311716D01*
X313508Y786964D01*
Y789048D01*
G01X314216Y791106D02*
X314174Y791398D01*
X314049Y791731D01*
X313841Y791939D01*
X313549Y792023D01*
X313258Y791939D01*
X313008Y791689D01*
X312883Y791314D01*
Y790898D01*
X312799Y790648D01*
X312591Y790439D01*
X312299Y790356D01*
X312008Y790481D01*
X311799Y790773D01*
X311716Y791106D01*
X311799Y791439D01*
X312008Y791731D01*
X312299Y791856D01*
X312591Y791773D01*
X312799Y791564D01*
X312883Y791314D01*
Y790898D01*
X313008Y790523D01*
X313258Y790273D01*
X313549Y790189D01*
X313841Y790273D01*
X314049Y790481D01*
X314174Y790814D01*
X314216Y791106D01*
G01X309406Y766698D02*
X313406D01*
Y774098D01*
G01X318216Y777873D02*
X315716D01*
Y778914D01*
X315841Y779248D01*
X316008Y779456D01*
X316341Y779539D01*
X316674Y779456D01*
X316883Y779206D01*
X317008Y778914D01*
Y777873D01*
G01Y778914D02*
X318216Y779539D01*
G01Y781723D02*
X317674Y781806D01*
X317216Y781931D01*
X316799Y782098D01*
X316341Y782306D01*
X315716Y782639D01*
Y780973D01*
G01X317924Y784198D02*
X318133Y784489D01*
X318216Y784823D01*
X318133Y785156D01*
X317883Y785448D01*
X317508Y785656D01*
X317133Y785739D01*
X316674D01*
X316299Y785656D01*
X315966Y785448D01*
X315799Y785198D01*
X315716Y784906D01*
X315799Y784573D01*
X315966Y784323D01*
X316216Y784156D01*
X316549Y784073D01*
X316841Y784156D01*
X317133Y784364D01*
X317299Y784614D01*
X317341Y784906D01*
X317258Y785239D01*
X317049Y785489D01*
X316674Y785739D01*
G01X317716Y787089D02*
X318008Y787339D01*
X318174Y787673D01*
X318216Y788048D01*
X318174Y788381D01*
X317966Y788714D01*
X317716Y788923D01*
X317466Y788964D01*
X317174Y788881D01*
X316966Y788589D01*
X316883Y788298D01*
Y787923D01*
G01Y788298D02*
X316758Y788548D01*
X316549Y788756D01*
X316299Y788839D01*
X316049Y788756D01*
X315841Y788548D01*
X315716Y788173D01*
X315758Y787798D01*
X315924Y787423D01*
G01X317716Y790189D02*
X318008Y790439D01*
X318174Y790773D01*
X318216Y791148D01*
X318174Y791481D01*
X317966Y791814D01*
X317716Y792023D01*
X317466Y792064D01*
X317174Y791981D01*
X316966Y791689D01*
X316883Y791398D01*
Y791023D01*
G01Y791398D02*
X316758Y791648D01*
X316549Y791856D01*
X316299Y791939D01*
X316049Y791856D01*
X315841Y791648D01*
X315716Y791273D01*
X315758Y790898D01*
X315924Y790523D01*
G01X313406Y766698D02*
X317406D01*
Y774098D01*
G01X301300Y766600D02*
X305300D01*
Y774000D01*
G01X305269Y783871D02*
X302769D01*
Y784912D01*
X302894Y785246D01*
X303061Y785454D01*
X303394Y785537D01*
X303727Y785454D01*
X303936Y785204D01*
X304061Y784912D01*
Y783871D01*
G01Y784912D02*
X305269Y785537D01*
G01X304977Y787096D02*
X305186Y787387D01*
X305269Y787721D01*
X305186Y788054D01*
X304936Y788346D01*
X304561Y788554D01*
X304186Y788637D01*
X303727D01*
X303352Y788554D01*
X303019Y788346D01*
X302852Y788096D01*
X302769Y787804D01*
X302852Y787471D01*
X303019Y787221D01*
X303269Y787054D01*
X303602Y786971D01*
X303894Y787054D01*
X304186Y787262D01*
X304352Y787512D01*
X304394Y787804D01*
X304311Y788137D01*
X304102Y788387D01*
X303727Y788637D01*
G01X302769Y790904D02*
X302852Y790571D01*
X303061Y790321D01*
X303311Y790154D01*
X303644Y790029D01*
X304019Y789987D01*
X304394Y790029D01*
X304727Y790154D01*
X304977Y790321D01*
X305186Y790571D01*
X305269Y790904D01*
X305186Y791237D01*
X304977Y791487D01*
X304727Y791654D01*
X304394Y791779D01*
X304019Y791821D01*
X303644Y791779D01*
X303311Y791654D01*
X303061Y791487D01*
X302852Y791237D01*
X302769Y790904D01*
G01X304769Y793087D02*
X305061Y793337D01*
X305227Y793671D01*
X305269Y794046D01*
X305227Y794379D01*
X305019Y794712D01*
X304769Y794921D01*
X304519Y794962D01*
X304227Y794879D01*
X304019Y794587D01*
X303936Y794296D01*
Y793921D01*
G01Y794296D02*
X303811Y794546D01*
X303602Y794754D01*
X303352Y794837D01*
X303102Y794754D01*
X302894Y794546D01*
X302769Y794171D01*
X302811Y793796D01*
X302977Y793421D01*
G01X304977Y796396D02*
X305186Y796687D01*
X305269Y797021D01*
X305186Y797354D01*
X304936Y797646D01*
X304561Y797854D01*
X304186Y797937D01*
X303727D01*
X303352Y797854D01*
X303019Y797646D01*
X302852Y797396D01*
X302769Y797104D01*
X302852Y796771D01*
X303019Y796521D01*
X303269Y796354D01*
X303602Y796271D01*
X303894Y796354D01*
X304186Y796562D01*
X304352Y796812D01*
X304394Y797104D01*
X304311Y797437D01*
X304102Y797687D01*
X303727Y797937D01*
G01X311608Y844767D02*
X311483Y844517D01*
X311400Y844225D01*
Y843892D01*
X311525Y843517D01*
X311733Y843225D01*
X311983Y843017D01*
X312400Y842850D01*
X312775Y842808D01*
X313150Y842892D01*
X313400Y843017D01*
X313650Y843267D01*
X313817Y843558D01*
X313900Y843850D01*
Y844142D01*
X313817Y844433D01*
X313692Y844683D01*
X313525Y844892D01*
G01X313400Y846033D02*
X313692Y846283D01*
X313858Y846617D01*
X313900Y846992D01*
X313858Y847325D01*
X313650Y847658D01*
X313400Y847867D01*
X313150Y847908D01*
X312858Y847825D01*
X312650Y847533D01*
X312567Y847242D01*
Y846867D01*
G01Y847242D02*
X312442Y847492D01*
X312233Y847700D01*
X311983Y847783D01*
X311733Y847700D01*
X311525Y847492D01*
X311400Y847117D01*
X311442Y846742D01*
X311608Y846367D01*
G01X313525Y849133D02*
X313733Y849383D01*
X313858Y849675D01*
X313900Y850050D01*
X313817Y850425D01*
X313650Y850717D01*
X313358Y850925D01*
X313025Y850967D01*
X312692Y850883D01*
X312483Y850675D01*
X312317Y850383D01*
X312275Y850092D01*
X312317Y849800D01*
X312483Y849425D01*
X311400Y849550D01*
Y850675D01*
G01X311817Y852358D02*
X311567Y852608D01*
X311442Y852900D01*
X311400Y853233D01*
X311483Y853650D01*
X311692Y853942D01*
X311942Y854025D01*
X312192Y853983D01*
X312400Y853817D01*
X312817Y852983D01*
X313108Y852608D01*
X313525Y852358D01*
X313900Y852275D01*
Y854025D01*
G01X317408Y844567D02*
X317283Y844317D01*
X317200Y844025D01*
Y843692D01*
X317325Y843317D01*
X317533Y843025D01*
X317783Y842817D01*
X318200Y842650D01*
X318575Y842608D01*
X318950Y842692D01*
X319200Y842817D01*
X319450Y843067D01*
X319617Y843358D01*
X319700Y843650D01*
Y843942D01*
X319617Y844233D01*
X319492Y844483D01*
X319325Y844692D01*
G01X319200Y845833D02*
X319492Y846083D01*
X319658Y846417D01*
X319700Y846792D01*
X319658Y847125D01*
X319450Y847458D01*
X319200Y847667D01*
X318950Y847708D01*
X318658Y847625D01*
X318450Y847333D01*
X318367Y847042D01*
Y846667D01*
G01Y847042D02*
X318242Y847292D01*
X318033Y847500D01*
X317783Y847583D01*
X317533Y847500D01*
X317325Y847292D01*
X317200Y846917D01*
X317242Y846542D01*
X317408Y846167D01*
G01X319325Y848933D02*
X319533Y849183D01*
X319658Y849475D01*
X319700Y849850D01*
X319617Y850225D01*
X319450Y850517D01*
X319158Y850725D01*
X318825Y850767D01*
X318492Y850683D01*
X318283Y850475D01*
X318117Y850183D01*
X318075Y849892D01*
X318117Y849600D01*
X318283Y849225D01*
X317200Y849350D01*
Y850475D01*
G01X319700Y852950D02*
X317200D01*
X317700Y852450D01*
G01X319700D02*
Y853450D01*
G01X330108Y844367D02*
X329983Y844117D01*
X329900Y843825D01*
Y843492D01*
X330025Y843117D01*
X330233Y842825D01*
X330483Y842617D01*
X330900Y842450D01*
X331275Y842408D01*
X331650Y842492D01*
X331900Y842617D01*
X332150Y842867D01*
X332317Y843158D01*
X332400Y843450D01*
Y843742D01*
X332317Y844033D01*
X332192Y844283D01*
X332025Y844492D01*
G01X331900Y845633D02*
X332192Y845883D01*
X332358Y846217D01*
X332400Y846592D01*
X332358Y846925D01*
X332150Y847258D01*
X331900Y847467D01*
X331650Y847508D01*
X331358Y847425D01*
X331150Y847133D01*
X331067Y846842D01*
Y846467D01*
G01Y846842D02*
X330942Y847092D01*
X330733Y847300D01*
X330483Y847383D01*
X330233Y847300D01*
X330025Y847092D01*
X329900Y846717D01*
X329942Y846342D01*
X330108Y845967D01*
G01X332025Y848733D02*
X332233Y848983D01*
X332358Y849275D01*
X332400Y849650D01*
X332317Y850025D01*
X332150Y850317D01*
X331858Y850525D01*
X331525Y850567D01*
X331192Y850483D01*
X330983Y850275D01*
X330817Y849983D01*
X330775Y849692D01*
X330817Y849400D01*
X330983Y849025D01*
X329900Y849150D01*
Y850275D01*
G01Y852750D02*
X329983Y852417D01*
X330192Y852167D01*
X330442Y852000D01*
X330775Y851875D01*
X331150Y851833D01*
X331525Y851875D01*
X331858Y852000D01*
X332108Y852167D01*
X332317Y852417D01*
X332400Y852750D01*
X332317Y853083D01*
X332108Y853333D01*
X331858Y853500D01*
X331525Y853625D01*
X331150Y853667D01*
X330775Y853625D01*
X330442Y853500D01*
X330192Y853333D01*
X329983Y853083D01*
X329900Y852750D01*
G01X323908Y844667D02*
X323783Y844417D01*
X323700Y844125D01*
Y843792D01*
X323825Y843417D01*
X324033Y843125D01*
X324283Y842917D01*
X324700Y842750D01*
X325075Y842708D01*
X325450Y842792D01*
X325700Y842917D01*
X325950Y843167D01*
X326117Y843458D01*
X326200Y843750D01*
Y844042D01*
X326117Y844333D01*
X325992Y844583D01*
X325825Y844792D01*
G01X325700Y845933D02*
X325992Y846183D01*
X326158Y846517D01*
X326200Y846892D01*
X326158Y847225D01*
X325950Y847558D01*
X325700Y847767D01*
X325450Y847808D01*
X325158Y847725D01*
X324950Y847433D01*
X324867Y847142D01*
Y846767D01*
G01Y847142D02*
X324742Y847392D01*
X324533Y847600D01*
X324283Y847683D01*
X324033Y847600D01*
X323825Y847392D01*
X323700Y847017D01*
X323742Y846642D01*
X323908Y846267D01*
G01X326200Y850450D02*
X323700D01*
X325492Y848908D01*
Y850992D01*
G01X325908Y852342D02*
X326117Y852633D01*
X326200Y852967D01*
X326117Y853300D01*
X325867Y853592D01*
X325492Y853800D01*
X325117Y853883D01*
X324658D01*
X324283Y853800D01*
X323950Y853592D01*
X323783Y853342D01*
X323700Y853050D01*
X323783Y852717D01*
X323950Y852467D01*
X324200Y852300D01*
X324533Y852217D01*
X324825Y852300D01*
X325117Y852508D01*
X325283Y852758D01*
X325325Y853050D01*
X325242Y853383D01*
X325033Y853633D01*
X324658Y853883D01*
G01X344500Y162517D02*
X342000D01*
Y163517D01*
X342125Y163850D01*
X342417Y164100D01*
X342750Y164183D01*
X343083Y164100D01*
X343333Y163892D01*
X343458Y163517D01*
Y162517D01*
G01X342208Y167367D02*
X342083Y167117D01*
X342000Y166825D01*
Y166492D01*
X342125Y166117D01*
X342333Y165825D01*
X342583Y165617D01*
X343000Y165450D01*
X343375Y165408D01*
X343750Y165492D01*
X344000Y165617D01*
X344250Y165867D01*
X344417Y166158D01*
X344500Y166450D01*
Y166742D01*
X344417Y167033D01*
X344292Y167283D01*
X344125Y167492D01*
G01X344000Y168633D02*
X344292Y168883D01*
X344458Y169217D01*
X344500Y169592D01*
X344458Y169925D01*
X344250Y170258D01*
X344000Y170467D01*
X343750Y170508D01*
X343458Y170425D01*
X343250Y170133D01*
X343167Y169842D01*
Y169467D01*
G01Y169842D02*
X343042Y170092D01*
X342833Y170300D01*
X342583Y170383D01*
X342333Y170300D01*
X342125Y170092D01*
X342000Y169717D01*
X342042Y169342D01*
X342208Y168967D01*
G01X344208Y171942D02*
X344417Y172233D01*
X344500Y172567D01*
X344417Y172900D01*
X344167Y173192D01*
X343792Y173400D01*
X343417Y173483D01*
X342958D01*
X342583Y173400D01*
X342250Y173192D01*
X342083Y172942D01*
X342000Y172650D01*
X342083Y172317D01*
X342250Y172067D01*
X342500Y171900D01*
X342833Y171817D01*
X343125Y171900D01*
X343417Y172108D01*
X343583Y172358D01*
X343625Y172650D01*
X343542Y172983D01*
X343333Y173233D01*
X342958Y173483D01*
G01X336500Y162517D02*
X334000D01*
Y163517D01*
X334125Y163850D01*
X334417Y164100D01*
X334750Y164183D01*
X335083Y164100D01*
X335333Y163892D01*
X335458Y163517D01*
Y162517D01*
G01X334208Y167367D02*
X334083Y167117D01*
X334000Y166825D01*
Y166492D01*
X334125Y166117D01*
X334333Y165825D01*
X334583Y165617D01*
X335000Y165450D01*
X335375Y165408D01*
X335750Y165492D01*
X336000Y165617D01*
X336250Y165867D01*
X336417Y166158D01*
X336500Y166450D01*
Y166742D01*
X336417Y167033D01*
X336292Y167283D01*
X336125Y167492D01*
G01X336500Y170050D02*
X334000D01*
X335792Y168508D01*
Y170592D01*
G01X334000Y172650D02*
X334083Y172317D01*
X334292Y172067D01*
X334542Y171900D01*
X334875Y171775D01*
X335250Y171733D01*
X335625Y171775D01*
X335958Y171900D01*
X336208Y172067D01*
X336417Y172317D01*
X336500Y172650D01*
X336417Y172983D01*
X336208Y173233D01*
X335958Y173400D01*
X335625Y173525D01*
X335250Y173567D01*
X334875Y173525D01*
X334542Y173400D01*
X334292Y173233D01*
X334083Y172983D01*
X334000Y172650D01*
G01X353691Y188584D02*
Y191084D01*
X354691D01*
X355024Y190959D01*
X355274Y190667D01*
X355357Y190334D01*
X355274Y190001D01*
X355066Y189751D01*
X354691Y189626D01*
X353691D01*
G01X357874Y189834D02*
X358707D01*
Y189084D01*
X358457Y188834D01*
X358166Y188667D01*
X357749Y188584D01*
X357332Y188667D01*
X357041Y188834D01*
X356791Y189084D01*
X356624Y189376D01*
X356541Y189709D01*
Y190001D01*
X356624Y190251D01*
X356791Y190542D01*
X357041Y190792D01*
X357291Y190959D01*
X357624Y191084D01*
X357916D01*
X358249Y191001D01*
X358499Y190834D01*
G01X359807Y188959D02*
X360057Y188751D01*
X360349Y188626D01*
X360724Y188584D01*
X361099Y188667D01*
X361391Y188834D01*
X361599Y189126D01*
X361641Y189459D01*
X361557Y189792D01*
X361349Y190001D01*
X361057Y190167D01*
X360766Y190209D01*
X360474Y190167D01*
X360099Y190001D01*
X360224Y191084D01*
X361349D01*
G01X353691Y195984D02*
Y198484D01*
X354691D01*
X355024Y198359D01*
X355274Y198067D01*
X355357Y197734D01*
X355274Y197401D01*
X355066Y197151D01*
X354691Y197026D01*
X353691D01*
G01X357874Y197234D02*
X358707D01*
Y196484D01*
X358457Y196234D01*
X358166Y196067D01*
X357749Y195984D01*
X357332Y196067D01*
X357041Y196234D01*
X356791Y196484D01*
X356624Y196776D01*
X356541Y197109D01*
Y197401D01*
X356624Y197651D01*
X356791Y197942D01*
X357041Y198192D01*
X357291Y198359D01*
X357624Y198484D01*
X357916D01*
X358249Y198401D01*
X358499Y198234D01*
G01X359932Y197026D02*
X360224Y197317D01*
X360474Y197484D01*
X360807Y197567D01*
X361099Y197484D01*
X361307Y197317D01*
X361474Y197067D01*
X361516Y196776D01*
X361474Y196526D01*
X361307Y196276D01*
X361057Y196067D01*
X360766Y195984D01*
X360432Y196067D01*
X360141Y196317D01*
X359974Y196692D01*
X359932Y197109D01*
X360016Y197651D01*
X360141Y197942D01*
X360349Y198234D01*
X360641Y198442D01*
X360932Y198484D01*
X361224Y198401D01*
X361432Y198192D01*
G01X353691Y192284D02*
Y194784D01*
X354691D01*
X355024Y194659D01*
X355274Y194367D01*
X355357Y194034D01*
X355274Y193701D01*
X355066Y193451D01*
X354691Y193326D01*
X353691D01*
G01X357874Y193534D02*
X358707D01*
Y192784D01*
X358457Y192534D01*
X358166Y192367D01*
X357749Y192284D01*
X357332Y192367D01*
X357041Y192534D01*
X356791Y192784D01*
X356624Y193076D01*
X356541Y193409D01*
Y193701D01*
X356624Y193951D01*
X356791Y194242D01*
X357041Y194492D01*
X357291Y194659D01*
X357624Y194784D01*
X357916D01*
X358249Y194701D01*
X358499Y194534D01*
G01X360641Y192284D02*
X360724Y192826D01*
X360849Y193284D01*
X361016Y193701D01*
X361224Y194159D01*
X361557Y194784D01*
X359891D01*
G01X353691Y184884D02*
Y187384D01*
X354691D01*
X355024Y187259D01*
X355274Y186967D01*
X355357Y186634D01*
X355274Y186301D01*
X355066Y186051D01*
X354691Y185926D01*
X353691D01*
G01X357874Y186134D02*
X358707D01*
Y185384D01*
X358457Y185134D01*
X358166Y184967D01*
X357749Y184884D01*
X357332Y184967D01*
X357041Y185134D01*
X356791Y185384D01*
X356624Y185676D01*
X356541Y186009D01*
Y186301D01*
X356624Y186551D01*
X356791Y186842D01*
X357041Y187092D01*
X357291Y187259D01*
X357624Y187384D01*
X357916D01*
X358249Y187301D01*
X358499Y187134D01*
G01X360724Y184884D02*
X361016Y184926D01*
X361349Y185051D01*
X361557Y185259D01*
X361641Y185551D01*
X361557Y185842D01*
X361307Y186092D01*
X360932Y186217D01*
X360516D01*
X360266Y186301D01*
X360057Y186509D01*
X359974Y186801D01*
X360099Y187092D01*
X360391Y187301D01*
X360724Y187384D01*
X361057Y187301D01*
X361349Y187092D01*
X361474Y186801D01*
X361391Y186509D01*
X361182Y186301D01*
X360932Y186217D01*
X360516D01*
X360141Y186092D01*
X359891Y185842D01*
X359807Y185551D01*
X359891Y185259D01*
X360099Y185051D01*
X360432Y184926D01*
X360724Y184884D01*
G01X353691Y203384D02*
Y205884D01*
X354691D01*
X355024Y205759D01*
X355274Y205467D01*
X355357Y205134D01*
X355274Y204801D01*
X355066Y204551D01*
X354691Y204426D01*
X353691D01*
G01X357874Y204634D02*
X358707D01*
Y203884D01*
X358457Y203634D01*
X358166Y203467D01*
X357749Y203384D01*
X357332Y203467D01*
X357041Y203634D01*
X356791Y203884D01*
X356624Y204176D01*
X356541Y204509D01*
Y204801D01*
X356624Y205051D01*
X356791Y205342D01*
X357041Y205592D01*
X357291Y205759D01*
X357624Y205884D01*
X357916D01*
X358249Y205801D01*
X358499Y205634D01*
G01X361224Y203384D02*
Y205884D01*
X359682Y204092D01*
X361766D01*
G01X353691Y199684D02*
Y202184D01*
X354691D01*
X355024Y202059D01*
X355274Y201767D01*
X355357Y201434D01*
X355274Y201101D01*
X355066Y200851D01*
X354691Y200726D01*
X353691D01*
G01X357874Y200934D02*
X358707D01*
Y200184D01*
X358457Y199934D01*
X358166Y199767D01*
X357749Y199684D01*
X357332Y199767D01*
X357041Y199934D01*
X356791Y200184D01*
X356624Y200476D01*
X356541Y200809D01*
Y201101D01*
X356624Y201351D01*
X356791Y201642D01*
X357041Y201892D01*
X357291Y202059D01*
X357624Y202184D01*
X357916D01*
X358249Y202101D01*
X358499Y201934D01*
G01X360016Y199976D02*
X360307Y199767D01*
X360641Y199684D01*
X360974Y199767D01*
X361266Y200017D01*
X361474Y200392D01*
X361557Y200767D01*
Y201226D01*
X361474Y201601D01*
X361266Y201934D01*
X361016Y202101D01*
X360724Y202184D01*
X360391Y202101D01*
X360141Y201934D01*
X359974Y201684D01*
X359891Y201351D01*
X359974Y201059D01*
X360182Y200767D01*
X360432Y200601D01*
X360724Y200559D01*
X361057Y200642D01*
X361307Y200851D01*
X361557Y201226D01*
G01X353267Y209567D02*
X353475Y209317D01*
X353725Y209150D01*
X354017Y209067D01*
X354350Y209150D01*
X354600Y209317D01*
X354850Y209567D01*
X354933Y209900D01*
Y211567D01*
G01X356367Y209067D02*
Y211567D01*
X357367D01*
X357700Y211442D01*
X357950Y211150D01*
X358033Y210817D01*
X357950Y210484D01*
X357742Y210234D01*
X357367Y210109D01*
X356367D01*
G01X360300Y209067D02*
Y211567D01*
X359800Y211067D01*
G01Y209067D02*
X360800D01*
G01X350403Y216640D02*
X350570Y216765D01*
X350695Y216974D01*
X350778Y217265D01*
X350695Y217515D01*
X350528Y217682D01*
X350237Y217807D01*
X349112D01*
Y215307D01*
X350487D01*
X350778Y215474D01*
X350945Y215724D01*
X351028Y216015D01*
X350945Y216307D01*
X350695Y216557D01*
X350403Y216640D01*
X349112D01*
G01X352087Y215307D02*
Y217807D01*
X353170Y215724D01*
X354253Y217807D01*
Y215307D01*
G01X357187Y217599D02*
X356937Y217724D01*
X356645Y217807D01*
X356312D01*
X355937Y217682D01*
X355645Y217474D01*
X355437Y217224D01*
X355270Y216807D01*
X355228Y216432D01*
X355312Y216057D01*
X355437Y215807D01*
X355687Y215557D01*
X355978Y215390D01*
X356270Y215307D01*
X356562D01*
X356853Y215390D01*
X357103Y215515D01*
X357312Y215682D01*
G01X363303Y215307D02*
X361637D01*
Y217807D01*
X363303D01*
G01X362637Y216599D02*
X361637D01*
G01X364612Y215307D02*
Y217807D01*
X366528Y215307D01*
Y217807D01*
G01X337058Y217383D02*
X337308Y217633D01*
X337600Y217758D01*
X337933Y217800D01*
X338350Y217717D01*
X338642Y217508D01*
X338725Y217258D01*
X338683Y217008D01*
X338517Y216800D01*
X337683Y216383D01*
X337308Y216092D01*
X337058Y215675D01*
X336975Y215300D01*
X338725D01*
G01X340408Y216133D02*
X341492D01*
G01X343133Y215800D02*
X343383Y215508D01*
X343717Y215342D01*
X344092Y215300D01*
X344425Y215342D01*
X344758Y215550D01*
X344967Y215800D01*
X345008Y216050D01*
X344925Y216342D01*
X344633Y216550D01*
X344342Y216633D01*
X343967D01*
G01X344342D02*
X344592Y216758D01*
X344800Y216967D01*
X344883Y217217D01*
X344800Y217467D01*
X344592Y217675D01*
X344217Y217800D01*
X343842Y217758D01*
X343467Y217592D01*
G01X346600Y213800D02*
Y219300D01*
X336100D01*
Y213800D01*
X346600D01*
G01X342817Y221400D02*
Y223900D01*
X343858D01*
X344192Y223775D01*
X344400Y223608D01*
X344483Y223275D01*
X344400Y222942D01*
X344150Y222733D01*
X343858Y222608D01*
X342817D01*
G01X343858D02*
X344483Y221400D01*
G01X345833Y221900D02*
X346083Y221608D01*
X346417Y221442D01*
X346792Y221400D01*
X347125Y221442D01*
X347458Y221650D01*
X347667Y221900D01*
X347708Y222150D01*
X347625Y222442D01*
X347333Y222650D01*
X347042Y222733D01*
X346667D01*
G01X347042D02*
X347292Y222858D01*
X347500Y223067D01*
X347583Y223317D01*
X347500Y223567D01*
X347292Y223775D01*
X346917Y223900D01*
X346542Y223858D01*
X346167Y223692D01*
G01X348933Y221900D02*
X349183Y221608D01*
X349517Y221442D01*
X349892Y221400D01*
X350225Y221442D01*
X350558Y221650D01*
X350767Y221900D01*
X350808Y222150D01*
X350725Y222442D01*
X350433Y222650D01*
X350142Y222733D01*
X349767D01*
G01X350142D02*
X350392Y222858D01*
X350600Y223067D01*
X350683Y223317D01*
X350600Y223567D01*
X350392Y223775D01*
X350017Y223900D01*
X349642Y223858D01*
X349267Y223692D01*
G01X352242Y221692D02*
X352533Y221483D01*
X352867Y221400D01*
X353200Y221483D01*
X353492Y221733D01*
X353700Y222108D01*
X353783Y222483D01*
Y222942D01*
X353700Y223317D01*
X353492Y223650D01*
X353242Y223817D01*
X352950Y223900D01*
X352617Y223817D01*
X352367Y223650D01*
X352200Y223400D01*
X352117Y223067D01*
X352200Y222775D01*
X352408Y222483D01*
X352658Y222317D01*
X352950Y222275D01*
X353283Y222358D01*
X353533Y222567D01*
X353783Y222942D01*
G01X359367Y259278D02*
X359575Y259611D01*
X359700Y259986D01*
Y260320D01*
X359575Y260653D01*
X359367Y260903D01*
X359075Y261028D01*
X358783Y260945D01*
X358533Y260736D01*
X358367Y260361D01*
X358283Y259861D01*
X358117Y259570D01*
X357825Y259445D01*
X357533Y259528D01*
X357325Y259736D01*
X357200Y260028D01*
Y260320D01*
X357283Y260611D01*
X357492Y260861D01*
G01X359700Y262336D02*
X357200D01*
G01Y263920D02*
X358742Y262336D01*
G01X359700Y264170D02*
X358033Y263045D01*
G01X357200Y266353D02*
X359700D01*
G01X357200Y265395D02*
Y267311D01*
G01X359325Y268536D02*
X359533Y268786D01*
X359658Y269078D01*
X359700Y269453D01*
X359617Y269828D01*
X359450Y270120D01*
X359158Y270328D01*
X358825Y270370D01*
X358492Y270286D01*
X358283Y270078D01*
X358117Y269786D01*
X358075Y269495D01*
X358117Y269203D01*
X358283Y268828D01*
X357200Y268953D01*
Y270078D01*
G01X351384Y268511D02*
X346784Y263911D01*
X351434Y259261D01*
G01X353345Y261470D02*
X355137D01*
X355512Y261637D01*
X355762Y261970D01*
X355845Y262387D01*
X355762Y262804D01*
X355512Y263137D01*
X355137Y263304D01*
X353345D01*
G01X355345Y264570D02*
X355637Y264820D01*
X355803Y265154D01*
X355845Y265529D01*
X355803Y265862D01*
X355595Y266195D01*
X355345Y266404D01*
X355095Y266445D01*
X354803Y266362D01*
X354595Y266070D01*
X354512Y265779D01*
Y265404D01*
G01Y265779D02*
X354387Y266029D01*
X354178Y266237D01*
X353928Y266320D01*
X353678Y266237D01*
X353470Y266029D01*
X353345Y265654D01*
X353387Y265279D01*
X353553Y264904D01*
G01X354803Y267795D02*
X354512Y268087D01*
X354345Y268337D01*
X354262Y268670D01*
X354345Y268962D01*
X354512Y269170D01*
X354762Y269337D01*
X355053Y269379D01*
X355303Y269337D01*
X355553Y269170D01*
X355762Y268920D01*
X355845Y268629D01*
X355762Y268295D01*
X355512Y268004D01*
X355137Y267837D01*
X354720Y267795D01*
X354178Y267879D01*
X353887Y268004D01*
X353595Y268212D01*
X353387Y268504D01*
X353345Y268795D01*
X353428Y269087D01*
X353637Y269295D01*
G01X340364Y264211D02*
X342334Y266181D01*
G01Y262241D02*
X340364Y264211D01*
G01X342334Y276911D02*
Y251511D01*
G01X351482Y309068D02*
X351815Y308860D01*
X352190Y308735D01*
X352524D01*
X352857Y308860D01*
X353107Y309068D01*
X353232Y309360D01*
X353149Y309652D01*
X352940Y309902D01*
X352565Y310068D01*
X352065Y310152D01*
X351774Y310318D01*
X351649Y310610D01*
X351732Y310902D01*
X351940Y311110D01*
X352232Y311235D01*
X352524D01*
X352815Y311152D01*
X353065Y310943D01*
G01X354624Y308735D02*
Y311235D01*
X355665D01*
X355999Y311110D01*
X356207Y310943D01*
X356290Y310610D01*
X356207Y310277D01*
X355957Y310068D01*
X355665Y309943D01*
X354624D01*
G01X355665D02*
X356290Y308735D01*
G01X357849Y309027D02*
X358140Y308818D01*
X358474Y308735D01*
X358807Y308818D01*
X359099Y309068D01*
X359307Y309443D01*
X359390Y309818D01*
Y310277D01*
X359307Y310652D01*
X359099Y310985D01*
X358849Y311152D01*
X358557Y311235D01*
X358224Y311152D01*
X357974Y310985D01*
X357807Y310735D01*
X357724Y310402D01*
X357807Y310110D01*
X358015Y309818D01*
X358265Y309652D01*
X358557Y309610D01*
X358890Y309693D01*
X359140Y309902D01*
X359390Y310277D01*
G01X360740Y309110D02*
X360990Y308902D01*
X361282Y308777D01*
X361657Y308735D01*
X362032Y308818D01*
X362324Y308985D01*
X362532Y309277D01*
X362574Y309610D01*
X362490Y309943D01*
X362282Y310152D01*
X361990Y310318D01*
X361699Y310360D01*
X361407Y310318D01*
X361032Y310152D01*
X361157Y311235D01*
X362282D01*
G01X364757D02*
X364424Y311152D01*
X364174Y310943D01*
X364007Y310693D01*
X363882Y310360D01*
X363840Y309985D01*
X363882Y309610D01*
X364007Y309277D01*
X364174Y309027D01*
X364424Y308818D01*
X364757Y308735D01*
X365090Y308818D01*
X365340Y309027D01*
X365507Y309277D01*
X365632Y309610D01*
X365674Y309985D01*
X365632Y310360D01*
X365507Y310693D01*
X365340Y310943D01*
X365090Y311152D01*
X364757Y311235D01*
G01X334682Y309168D02*
X335015Y308960D01*
X335390Y308835D01*
X335724D01*
X336057Y308960D01*
X336307Y309168D01*
X336432Y309460D01*
X336349Y309752D01*
X336140Y310002D01*
X335765Y310168D01*
X335265Y310252D01*
X334974Y310418D01*
X334849Y310710D01*
X334932Y311002D01*
X335140Y311210D01*
X335432Y311335D01*
X335724D01*
X336015Y311252D01*
X336265Y311043D01*
G01X337824Y308835D02*
Y311335D01*
X338865D01*
X339199Y311210D01*
X339407Y311043D01*
X339490Y310710D01*
X339407Y310377D01*
X339157Y310168D01*
X338865Y310043D01*
X337824D01*
G01X338865D02*
X339490Y308835D01*
G01X341049Y309127D02*
X341340Y308918D01*
X341674Y308835D01*
X342007Y308918D01*
X342299Y309168D01*
X342507Y309543D01*
X342590Y309918D01*
Y310377D01*
X342507Y310752D01*
X342299Y311085D01*
X342049Y311252D01*
X341757Y311335D01*
X341424Y311252D01*
X341174Y311085D01*
X341007Y310835D01*
X340924Y310502D01*
X341007Y310210D01*
X341215Y309918D01*
X341465Y309752D01*
X341757Y309710D01*
X342090Y309793D01*
X342340Y310002D01*
X342590Y310377D01*
G01X345357Y308835D02*
Y311335D01*
X343815Y309543D01*
X345899D01*
G01X347874Y308835D02*
X347957Y309377D01*
X348082Y309835D01*
X348249Y310252D01*
X348457Y310710D01*
X348790Y311335D01*
X347124D01*
G01X350000Y295819D02*
X347500D01*
Y296860D01*
X347625Y297194D01*
X347792Y297402D01*
X348125Y297485D01*
X348458Y297402D01*
X348667Y297152D01*
X348792Y296860D01*
Y295819D01*
G01Y296860D02*
X350000Y297485D01*
G01Y300252D02*
X347500D01*
X349292Y298710D01*
Y300794D01*
G01X347917Y302060D02*
X347667Y302310D01*
X347542Y302602D01*
X347500Y302935D01*
X347583Y303352D01*
X347792Y303644D01*
X348042Y303727D01*
X348292Y303685D01*
X348500Y303519D01*
X348917Y302685D01*
X349208Y302310D01*
X349625Y302060D01*
X350000Y301977D01*
Y303727D01*
G01X349500Y305035D02*
X349792Y305285D01*
X349958Y305619D01*
X350000Y305994D01*
X349958Y306327D01*
X349750Y306660D01*
X349500Y306869D01*
X349250Y306910D01*
X348958Y306827D01*
X348750Y306535D01*
X348667Y306244D01*
Y305869D01*
G01Y306244D02*
X348542Y306494D01*
X348333Y306702D01*
X348083Y306785D01*
X347833Y306702D01*
X347625Y306494D01*
X347500Y306119D01*
X347542Y305744D01*
X347708Y305369D01*
G01X335410Y290460D02*
X339410D01*
Y297860D01*
G01X350991Y315364D02*
Y313572D01*
X351158Y313197D01*
X351491Y312947D01*
X351908Y312864D01*
X352325Y312947D01*
X352658Y313197D01*
X352825Y313572D01*
Y315364D01*
G01X355008Y312864D02*
Y315364D01*
X354508Y314864D01*
G01Y312864D02*
X355508D01*
G01X358108D02*
X358400Y312906D01*
X358733Y313031D01*
X358941Y313239D01*
X359025Y313531D01*
X358941Y313822D01*
X358691Y314072D01*
X358316Y314197D01*
X357900D01*
X357650Y314281D01*
X357441Y314489D01*
X357358Y314781D01*
X357483Y315072D01*
X357775Y315281D01*
X358108Y315364D01*
X358441Y315281D01*
X358733Y315072D01*
X358858Y314781D01*
X358775Y314489D01*
X358566Y314281D01*
X358316Y314197D01*
X357900D01*
X357525Y314072D01*
X357275Y313822D01*
X357191Y313531D01*
X357275Y313239D01*
X357483Y313031D01*
X357816Y312906D01*
X358108Y312864D01*
G01X361125D02*
X361208Y313406D01*
X361333Y313864D01*
X361500Y314281D01*
X361708Y314739D01*
X362041Y315364D01*
X360375D01*
G01X342141Y331880D02*
Y331730D01*
X340891Y330480D01*
X339691Y331680D01*
Y331930D01*
G01X343522Y339408D02*
X343855Y339200D01*
X344230Y339075D01*
X344564D01*
X344897Y339200D01*
X345147Y339408D01*
X345272Y339700D01*
X345189Y339992D01*
X344980Y340242D01*
X344605Y340408D01*
X344105Y340492D01*
X343814Y340658D01*
X343689Y340950D01*
X343772Y341242D01*
X343980Y341450D01*
X344272Y341575D01*
X344564D01*
X344855Y341492D01*
X345105Y341283D01*
G01X346664Y339075D02*
Y341575D01*
X347705D01*
X348039Y341450D01*
X348247Y341283D01*
X348330Y340950D01*
X348247Y340617D01*
X347997Y340408D01*
X347705Y340283D01*
X346664D01*
G01X347705D02*
X348330Y339075D01*
G01X349889Y339367D02*
X350180Y339158D01*
X350514Y339075D01*
X350847Y339158D01*
X351139Y339408D01*
X351347Y339783D01*
X351430Y340158D01*
Y340617D01*
X351347Y340992D01*
X351139Y341325D01*
X350889Y341492D01*
X350597Y341575D01*
X350264Y341492D01*
X350014Y341325D01*
X349847Y341075D01*
X349764Y340742D01*
X349847Y340450D01*
X350055Y340158D01*
X350305Y339992D01*
X350597Y339950D01*
X350930Y340033D01*
X351180Y340242D01*
X351430Y340617D01*
G01X354197Y339075D02*
Y341575D01*
X352655Y339783D01*
X354739D01*
G01X356797Y339075D02*
X357089Y339117D01*
X357422Y339242D01*
X357630Y339450D01*
X357714Y339742D01*
X357630Y340033D01*
X357380Y340283D01*
X357005Y340408D01*
X356589D01*
X356339Y340492D01*
X356130Y340700D01*
X356047Y340992D01*
X356172Y341283D01*
X356464Y341492D01*
X356797Y341575D01*
X357130Y341492D01*
X357422Y341283D01*
X357547Y340992D01*
X357464Y340700D01*
X357255Y340492D01*
X357005Y340408D01*
X356589D01*
X356214Y340283D01*
X355964Y340033D01*
X355880Y339742D01*
X355964Y339450D01*
X356172Y339242D01*
X356505Y339117D01*
X356797Y339075D01*
G01X342000Y337600D02*
Y333600D01*
X349400D01*
G01X350000Y316500D02*
Y320500D01*
X342600D01*
G01X361948Y320819D02*
X362156Y321152D01*
X362281Y321527D01*
Y321861D01*
X362156Y322194D01*
X361948Y322444D01*
X361656Y322569D01*
X361364Y322486D01*
X361114Y322277D01*
X360948Y321902D01*
X360864Y321402D01*
X360698Y321111D01*
X360406Y320986D01*
X360114Y321069D01*
X359906Y321277D01*
X359781Y321569D01*
Y321861D01*
X359864Y322152D01*
X360073Y322402D01*
G01X362281Y323961D02*
X359781D01*
Y325002D01*
X359906Y325336D01*
X360073Y325544D01*
X360406Y325627D01*
X360739Y325544D01*
X360948Y325294D01*
X361073Y325002D01*
Y323961D01*
G01Y325002D02*
X362281Y325627D01*
G01Y327894D02*
X362239Y328186D01*
X362114Y328519D01*
X361906Y328727D01*
X361614Y328811D01*
X361323Y328727D01*
X361073Y328477D01*
X360948Y328102D01*
Y327686D01*
X360864Y327436D01*
X360656Y327227D01*
X360364Y327144D01*
X360073Y327269D01*
X359864Y327561D01*
X359781Y327894D01*
X359864Y328227D01*
X360073Y328519D01*
X360364Y328644D01*
X360656Y328561D01*
X360864Y328352D01*
X360948Y328102D01*
Y327686D01*
X361073Y327311D01*
X361323Y327061D01*
X361614Y326977D01*
X361906Y327061D01*
X362114Y327269D01*
X362239Y327602D01*
X362281Y327894D01*
G01Y331494D02*
X359781D01*
X361573Y329952D01*
Y332036D01*
G01X360198Y333302D02*
X359948Y333552D01*
X359823Y333844D01*
X359781Y334177D01*
X359864Y334594D01*
X360073Y334886D01*
X360323Y334969D01*
X360573Y334927D01*
X360781Y334761D01*
X361198Y333927D01*
X361489Y333552D01*
X361906Y333302D01*
X362281Y333219D01*
Y334969D01*
G01X357200Y334200D02*
X353200D01*
Y326800D01*
G01X367510Y377297D02*
X365010D01*
Y378338D01*
X365135Y378672D01*
X365302Y378880D01*
X365635Y378963D01*
X365968Y378880D01*
X366177Y378630D01*
X366302Y378338D01*
Y377297D01*
G01Y378338D02*
X367510Y378963D01*
G01Y381230D02*
X365010D01*
X365510Y380730D01*
G01X367510D02*
Y381730D01*
G01X366468Y383538D02*
X366177Y383830D01*
X366010Y384080D01*
X365927Y384413D01*
X366010Y384705D01*
X366177Y384913D01*
X366427Y385080D01*
X366718Y385122D01*
X366968Y385080D01*
X367218Y384913D01*
X367427Y384663D01*
X367510Y384372D01*
X367427Y384038D01*
X367177Y383747D01*
X366802Y383580D01*
X366385Y383538D01*
X365843Y383622D01*
X365552Y383747D01*
X365260Y383955D01*
X365052Y384247D01*
X365010Y384538D01*
X365093Y384830D01*
X365302Y385038D01*
G01X366468Y386638D02*
X366177Y386930D01*
X366010Y387180D01*
X365927Y387513D01*
X366010Y387805D01*
X366177Y388013D01*
X366427Y388180D01*
X366718Y388222D01*
X366968Y388180D01*
X367218Y388013D01*
X367427Y387763D01*
X367510Y387472D01*
X367427Y387138D01*
X367177Y386847D01*
X366802Y386680D01*
X366385Y386638D01*
X365843Y386722D01*
X365552Y386847D01*
X365260Y387055D01*
X365052Y387347D01*
X365010Y387638D01*
X365093Y387930D01*
X365302Y388138D01*
G01X365140Y390760D02*
X367640D01*
G01X365140Y389802D02*
Y391718D01*
G01X367640Y393027D02*
X365140D01*
Y394027D01*
X365265Y394360D01*
X365557Y394610D01*
X365890Y394693D01*
X366223Y394610D01*
X366473Y394402D01*
X366598Y394027D01*
Y393027D01*
G01X367640Y396960D02*
X365140D01*
X365640Y396460D01*
G01X367640D02*
Y397460D01*
G01X367265Y399143D02*
X367473Y399393D01*
X367598Y399685D01*
X367640Y400060D01*
X367557Y400435D01*
X367390Y400727D01*
X367098Y400935D01*
X366765Y400977D01*
X366432Y400893D01*
X366223Y400685D01*
X366057Y400393D01*
X366015Y400102D01*
X366057Y399810D01*
X366223Y399435D01*
X365140Y399560D01*
Y400685D01*
G01Y403160D02*
X365223Y402827D01*
X365432Y402577D01*
X365682Y402410D01*
X366015Y402285D01*
X366390Y402243D01*
X366765Y402285D01*
X367098Y402410D01*
X367348Y402577D01*
X367557Y402827D01*
X367640Y403160D01*
X367557Y403493D01*
X367348Y403743D01*
X367098Y403910D01*
X366765Y404035D01*
X366390Y404077D01*
X366015Y404035D01*
X365682Y403910D01*
X365432Y403743D01*
X365223Y403493D01*
X365140Y403160D01*
G01X359940Y384177D02*
X357440D01*
Y385218D01*
X357565Y385552D01*
X357732Y385760D01*
X358065Y385843D01*
X358398Y385760D01*
X358607Y385510D01*
X358732Y385218D01*
Y384177D01*
G01Y385218D02*
X359940Y385843D01*
G01Y388610D02*
X357440D01*
X359232Y387068D01*
Y389152D01*
G01X359940Y391127D02*
X359398Y391210D01*
X358940Y391335D01*
X358523Y391502D01*
X358065Y391710D01*
X357440Y392043D01*
Y390377D01*
G01X359940Y394810D02*
X357440D01*
X359232Y393268D01*
Y395352D01*
G01X361848Y387327D02*
X361723Y387077D01*
X361640Y386785D01*
Y386452D01*
X361765Y386077D01*
X361973Y385785D01*
X362223Y385577D01*
X362640Y385410D01*
X363015Y385368D01*
X363390Y385452D01*
X363640Y385577D01*
X363890Y385827D01*
X364057Y386118D01*
X364140Y386410D01*
Y386702D01*
X364057Y386993D01*
X363932Y387243D01*
X363765Y387452D01*
G01X363098Y388718D02*
X362807Y389010D01*
X362640Y389260D01*
X362557Y389593D01*
X362640Y389885D01*
X362807Y390093D01*
X363057Y390260D01*
X363348Y390302D01*
X363598Y390260D01*
X363848Y390093D01*
X364057Y389843D01*
X364140Y389552D01*
X364057Y389218D01*
X363807Y388927D01*
X363432Y388760D01*
X363015Y388718D01*
X362473Y388802D01*
X362182Y388927D01*
X361890Y389135D01*
X361682Y389427D01*
X361640Y389718D01*
X361723Y390010D01*
X361932Y390218D01*
G01X363640Y391693D02*
X363932Y391943D01*
X364098Y392277D01*
X364140Y392652D01*
X364098Y392985D01*
X363890Y393318D01*
X363640Y393527D01*
X363390Y393568D01*
X363098Y393485D01*
X362890Y393193D01*
X362807Y392902D01*
Y392527D01*
G01Y392902D02*
X362682Y393152D01*
X362473Y393360D01*
X362223Y393443D01*
X361973Y393360D01*
X361765Y393152D01*
X361640Y392777D01*
X361682Y392402D01*
X361848Y392027D01*
G01X364140Y395627D02*
X363598Y395710D01*
X363140Y395835D01*
X362723Y396002D01*
X362265Y396210D01*
X361640Y396543D01*
Y394877D01*
G01X344208Y399767D02*
X344083Y399517D01*
X344000Y399225D01*
Y398892D01*
X344125Y398517D01*
X344333Y398225D01*
X344583Y398017D01*
X345000Y397850D01*
X345375Y397808D01*
X345750Y397892D01*
X346000Y398017D01*
X346250Y398267D01*
X346417Y398558D01*
X346500Y398850D01*
Y399142D01*
X346417Y399433D01*
X346292Y399683D01*
X346125Y399892D01*
G01X345458Y401158D02*
X345167Y401450D01*
X345000Y401700D01*
X344917Y402033D01*
X345000Y402325D01*
X345167Y402533D01*
X345417Y402700D01*
X345708Y402742D01*
X345958Y402700D01*
X346208Y402533D01*
X346417Y402283D01*
X346500Y401992D01*
X346417Y401658D01*
X346167Y401367D01*
X345792Y401200D01*
X345375Y401158D01*
X344833Y401242D01*
X344542Y401367D01*
X344250Y401575D01*
X344042Y401867D01*
X344000Y402158D01*
X344083Y402450D01*
X344292Y402658D01*
G01X344417Y404258D02*
X344167Y404508D01*
X344042Y404800D01*
X344000Y405133D01*
X344083Y405550D01*
X344292Y405842D01*
X344542Y405925D01*
X344792Y405883D01*
X345000Y405717D01*
X345417Y404883D01*
X345708Y404508D01*
X346125Y404258D01*
X346500Y404175D01*
Y405925D01*
G01X344000Y408150D02*
X344083Y407817D01*
X344292Y407567D01*
X344542Y407400D01*
X344875Y407275D01*
X345250Y407233D01*
X345625Y407275D01*
X345958Y407400D01*
X346208Y407567D01*
X346417Y407817D01*
X346500Y408150D01*
X346417Y408483D01*
X346208Y408733D01*
X345958Y408900D01*
X345625Y409025D01*
X345250Y409067D01*
X344875Y409025D01*
X344542Y408900D01*
X344292Y408733D01*
X344083Y408483D01*
X344000Y408150D01*
G01X340600Y414600D02*
X343100D01*
G01X340600Y413642D02*
Y415558D01*
G01X343100Y416867D02*
X340600D01*
Y417867D01*
X340725Y418200D01*
X341017Y418450D01*
X341350Y418533D01*
X341683Y418450D01*
X341933Y418242D01*
X342058Y417867D01*
Y416867D01*
G01X343100Y420800D02*
X340600D01*
X341100Y420300D01*
G01X343100D02*
Y421300D01*
G01X342725Y422983D02*
X342933Y423233D01*
X343058Y423525D01*
X343100Y423900D01*
X343017Y424275D01*
X342850Y424567D01*
X342558Y424775D01*
X342225Y424817D01*
X341892Y424733D01*
X341683Y424525D01*
X341517Y424233D01*
X341475Y423942D01*
X341517Y423650D01*
X341683Y423275D01*
X340600Y423400D01*
Y424525D01*
G01X341017Y426208D02*
X340767Y426458D01*
X340642Y426750D01*
X340600Y427083D01*
X340683Y427500D01*
X340892Y427792D01*
X341142Y427875D01*
X341392Y427833D01*
X341600Y427667D01*
X342017Y426833D01*
X342308Y426458D01*
X342725Y426208D01*
X343100Y426125D01*
Y427875D01*
G01X349010Y447970D02*
Y445470D01*
G01X348052Y447970D02*
X349968D01*
G01X351277Y445470D02*
Y447970D01*
X352277D01*
X352610Y447845D01*
X352860Y447553D01*
X352943Y447220D01*
X352860Y446887D01*
X352652Y446637D01*
X352277Y446512D01*
X351277D01*
G01X355210Y445470D02*
Y447970D01*
X354710Y447470D01*
G01Y445470D02*
X355710D01*
G01X357518Y446512D02*
X357810Y446803D01*
X358060Y446970D01*
X358393Y447053D01*
X358685Y446970D01*
X358893Y446803D01*
X359060Y446553D01*
X359102Y446262D01*
X359060Y446012D01*
X358893Y445762D01*
X358643Y445553D01*
X358352Y445470D01*
X358018Y445553D01*
X357727Y445803D01*
X357560Y446178D01*
X357518Y446595D01*
X357602Y447137D01*
X357727Y447428D01*
X357935Y447720D01*
X358227Y447928D01*
X358518Y447970D01*
X358810Y447887D01*
X359018Y447678D01*
G01X360493Y445970D02*
X360743Y445678D01*
X361077Y445512D01*
X361452Y445470D01*
X361785Y445512D01*
X362118Y445720D01*
X362327Y445970D01*
X362368Y446220D01*
X362285Y446512D01*
X361993Y446720D01*
X361702Y446803D01*
X361327D01*
G01X361702D02*
X361952Y446928D01*
X362160Y447137D01*
X362243Y447387D01*
X362160Y447637D01*
X361952Y447845D01*
X361577Y447970D01*
X361202Y447928D01*
X360827Y447762D01*
G01X334376Y427827D02*
X334251Y427577D01*
X334168Y427285D01*
Y426952D01*
X334293Y426577D01*
X334501Y426285D01*
X334751Y426077D01*
X335168Y425910D01*
X335543Y425868D01*
X335918Y425952D01*
X336168Y426077D01*
X336418Y426327D01*
X336585Y426618D01*
X336668Y426910D01*
Y427202D01*
X336585Y427493D01*
X336460Y427743D01*
X336293Y427952D01*
G01X336168Y429093D02*
X336460Y429343D01*
X336626Y429677D01*
X336668Y430052D01*
X336626Y430385D01*
X336418Y430718D01*
X336168Y430927D01*
X335918Y430968D01*
X335626Y430885D01*
X335418Y430593D01*
X335335Y430302D01*
Y429927D01*
G01Y430302D02*
X335210Y430552D01*
X335001Y430760D01*
X334751Y430843D01*
X334501Y430760D01*
X334293Y430552D01*
X334168Y430177D01*
X334210Y429802D01*
X334376Y429427D01*
G01X336668Y433027D02*
X336126Y433110D01*
X335668Y433235D01*
X335251Y433402D01*
X334793Y433610D01*
X334168Y433943D01*
Y432277D01*
G01X336668Y436127D02*
X336126Y436210D01*
X335668Y436335D01*
X335251Y436502D01*
X334793Y436710D01*
X334168Y437043D01*
Y435377D01*
G01X344148Y447027D02*
X344023Y446777D01*
X343940Y446485D01*
Y446152D01*
X344065Y445777D01*
X344273Y445485D01*
X344523Y445277D01*
X344940Y445110D01*
X345315Y445068D01*
X345690Y445152D01*
X345940Y445277D01*
X346190Y445527D01*
X346357Y445818D01*
X346440Y446110D01*
Y446402D01*
X346357Y446693D01*
X346232Y446943D01*
X346065Y447152D01*
G01X345398Y448418D02*
X345107Y448710D01*
X344940Y448960D01*
X344857Y449293D01*
X344940Y449585D01*
X345107Y449793D01*
X345357Y449960D01*
X345648Y450002D01*
X345898Y449960D01*
X346148Y449793D01*
X346357Y449543D01*
X346440Y449252D01*
X346357Y448918D01*
X346107Y448627D01*
X345732Y448460D01*
X345315Y448418D01*
X344773Y448502D01*
X344482Y448627D01*
X344190Y448835D01*
X343982Y449127D01*
X343940Y449418D01*
X344023Y449710D01*
X344232Y449918D01*
G01X345940Y451393D02*
X346232Y451643D01*
X346398Y451977D01*
X346440Y452352D01*
X346398Y452685D01*
X346190Y453018D01*
X345940Y453227D01*
X345690Y453268D01*
X345398Y453185D01*
X345190Y452893D01*
X345107Y452602D01*
Y452227D01*
G01Y452602D02*
X344982Y452852D01*
X344773Y453060D01*
X344523Y453143D01*
X344273Y453060D01*
X344065Y452852D01*
X343940Y452477D01*
X343982Y452102D01*
X344148Y451727D01*
G01X346440Y455410D02*
X346398Y455702D01*
X346273Y456035D01*
X346065Y456243D01*
X345773Y456327D01*
X345482Y456243D01*
X345232Y455993D01*
X345107Y455618D01*
Y455202D01*
X345023Y454952D01*
X344815Y454743D01*
X344523Y454660D01*
X344232Y454785D01*
X344023Y455077D01*
X343940Y455410D01*
X344023Y455743D01*
X344232Y456035D01*
X344523Y456160D01*
X344815Y456077D01*
X345023Y455868D01*
X345107Y455618D01*
Y455202D01*
X345232Y454827D01*
X345482Y454577D01*
X345773Y454493D01*
X346065Y454577D01*
X346273Y454785D01*
X346398Y455118D01*
X346440Y455410D01*
G01X360840Y421243D02*
X362632D01*
X363007Y421410D01*
X363257Y421743D01*
X363340Y422160D01*
X363257Y422577D01*
X363007Y422910D01*
X362632Y423077D01*
X360840D01*
G01X361257Y424468D02*
X361007Y424718D01*
X360882Y425010D01*
X360840Y425343D01*
X360923Y425760D01*
X361132Y426052D01*
X361382Y426135D01*
X361632Y426093D01*
X361840Y425927D01*
X362257Y425093D01*
X362548Y424718D01*
X362965Y424468D01*
X363340Y424385D01*
Y426135D01*
G01X360840Y428360D02*
X360923Y428027D01*
X361132Y427777D01*
X361382Y427610D01*
X361715Y427485D01*
X362090Y427443D01*
X362465Y427485D01*
X362798Y427610D01*
X363048Y427777D01*
X363257Y428027D01*
X363340Y428360D01*
X363257Y428693D01*
X363048Y428943D01*
X362798Y429110D01*
X362465Y429235D01*
X362090Y429277D01*
X361715Y429235D01*
X361382Y429110D01*
X361132Y428943D01*
X360923Y428693D01*
X360840Y428360D01*
G01X350140Y451077D02*
X347640D01*
Y452118D01*
X347765Y452452D01*
X347932Y452660D01*
X348265Y452743D01*
X348598Y452660D01*
X348807Y452410D01*
X348932Y452118D01*
Y451077D01*
G01Y452118D02*
X350140Y452743D01*
G01Y455510D02*
X347640D01*
X349432Y453968D01*
Y456052D01*
G01X347640Y458110D02*
X347723Y457777D01*
X347932Y457527D01*
X348182Y457360D01*
X348515Y457235D01*
X348890Y457193D01*
X349265Y457235D01*
X349598Y457360D01*
X349848Y457527D01*
X350057Y457777D01*
X350140Y458110D01*
X350057Y458443D01*
X349848Y458693D01*
X349598Y458860D01*
X349265Y458985D01*
X348890Y459027D01*
X348515Y458985D01*
X348182Y458860D01*
X347932Y458693D01*
X347723Y458443D01*
X347640Y458110D01*
G01X349640Y460293D02*
X349932Y460543D01*
X350098Y460877D01*
X350140Y461252D01*
X350098Y461585D01*
X349890Y461918D01*
X349640Y462127D01*
X349390Y462168D01*
X349098Y462085D01*
X348890Y461793D01*
X348807Y461502D01*
Y461127D01*
G01Y461502D02*
X348682Y461752D01*
X348473Y461960D01*
X348223Y462043D01*
X347973Y461960D01*
X347765Y461752D01*
X347640Y461377D01*
X347682Y461002D01*
X347848Y460627D01*
G01X354640Y450777D02*
X352140D01*
Y451818D01*
X352265Y452152D01*
X352432Y452360D01*
X352765Y452443D01*
X353098Y452360D01*
X353307Y452110D01*
X353432Y451818D01*
Y450777D01*
G01Y451818D02*
X354640Y452443D01*
G01Y455210D02*
X352140D01*
X353932Y453668D01*
Y455752D01*
G01X352140Y457810D02*
X352223Y457477D01*
X352432Y457227D01*
X352682Y457060D01*
X353015Y456935D01*
X353390Y456893D01*
X353765Y456935D01*
X354098Y457060D01*
X354348Y457227D01*
X354557Y457477D01*
X354640Y457810D01*
X354557Y458143D01*
X354348Y458393D01*
X354098Y458560D01*
X353765Y458685D01*
X353390Y458727D01*
X353015Y458685D01*
X352682Y458560D01*
X352432Y458393D01*
X352223Y458143D01*
X352140Y457810D01*
G01X354640Y460910D02*
X352140D01*
X352640Y460410D01*
G01X354640D02*
Y461410D01*
G01X357148Y452727D02*
X357023Y452477D01*
X356940Y452185D01*
Y451852D01*
X357065Y451477D01*
X357273Y451185D01*
X357523Y450977D01*
X357940Y450810D01*
X358315Y450768D01*
X358690Y450852D01*
X358940Y450977D01*
X359190Y451227D01*
X359357Y451518D01*
X359440Y451810D01*
Y452102D01*
X359357Y452393D01*
X359232Y452643D01*
X359065Y452852D01*
G01X358398Y454118D02*
X358107Y454410D01*
X357940Y454660D01*
X357857Y454993D01*
X357940Y455285D01*
X358107Y455493D01*
X358357Y455660D01*
X358648Y455702D01*
X358898Y455660D01*
X359148Y455493D01*
X359357Y455243D01*
X359440Y454952D01*
X359357Y454618D01*
X359107Y454327D01*
X358732Y454160D01*
X358315Y454118D01*
X357773Y454202D01*
X357482Y454327D01*
X357190Y454535D01*
X356982Y454827D01*
X356940Y455118D01*
X357023Y455410D01*
X357232Y455618D01*
G01X357357Y457218D02*
X357107Y457468D01*
X356982Y457760D01*
X356940Y458093D01*
X357023Y458510D01*
X357232Y458802D01*
X357482Y458885D01*
X357732Y458843D01*
X357940Y458677D01*
X358357Y457843D01*
X358648Y457468D01*
X359065Y457218D01*
X359440Y457135D01*
Y458885D01*
G01Y461110D02*
X359398Y461402D01*
X359273Y461735D01*
X359065Y461943D01*
X358773Y462027D01*
X358482Y461943D01*
X358232Y461693D01*
X358107Y461318D01*
Y460902D01*
X358023Y460652D01*
X357815Y460443D01*
X357523Y460360D01*
X357232Y460485D01*
X357023Y460777D01*
X356940Y461110D01*
X357023Y461443D01*
X357232Y461735D01*
X357523Y461860D01*
X357815Y461777D01*
X358023Y461568D01*
X358107Y461318D01*
Y460902D01*
X358232Y460527D01*
X358482Y460277D01*
X358773Y460193D01*
X359065Y460277D01*
X359273Y460485D01*
X359398Y460818D01*
X359440Y461110D01*
G01X363113Y454593D02*
X362988Y454343D01*
X362905Y454051D01*
Y453718D01*
X363030Y453343D01*
X363238Y453051D01*
X363488Y452843D01*
X363905Y452676D01*
X364280Y452634D01*
X364655Y452718D01*
X364905Y452843D01*
X365155Y453093D01*
X365322Y453384D01*
X365405Y453676D01*
Y453968D01*
X365322Y454259D01*
X365197Y454509D01*
X365030Y454718D01*
G01X364363Y455984D02*
X364072Y456276D01*
X363905Y456526D01*
X363822Y456859D01*
X363905Y457151D01*
X364072Y457359D01*
X364322Y457526D01*
X364613Y457568D01*
X364863Y457526D01*
X365113Y457359D01*
X365322Y457109D01*
X365405Y456818D01*
X365322Y456484D01*
X365072Y456193D01*
X364697Y456026D01*
X364280Y455984D01*
X363738Y456068D01*
X363447Y456193D01*
X363155Y456401D01*
X362947Y456693D01*
X362905Y456984D01*
X362988Y457276D01*
X363197Y457484D01*
G01X365405Y460376D02*
X362905D01*
X364697Y458834D01*
Y460918D01*
G01X364905Y462059D02*
X365197Y462309D01*
X365363Y462643D01*
X365405Y463018D01*
X365363Y463351D01*
X365155Y463684D01*
X364905Y463893D01*
X364655Y463934D01*
X364363Y463851D01*
X364155Y463559D01*
X364072Y463268D01*
Y462893D01*
G01Y463268D02*
X363947Y463518D01*
X363738Y463726D01*
X363488Y463809D01*
X363238Y463726D01*
X363030Y463518D01*
X362905Y463143D01*
X362947Y462768D01*
X363113Y462393D01*
G01X340290Y737222D02*
X340040Y737347D01*
X339748Y737430D01*
X339415D01*
X339040Y737305D01*
X338748Y737097D01*
X338540Y736847D01*
X338373Y736430D01*
X338331Y736055D01*
X338415Y735680D01*
X338540Y735430D01*
X338790Y735180D01*
X339081Y735013D01*
X339373Y734930D01*
X339665D01*
X339956Y735013D01*
X340206Y735138D01*
X340415Y735305D01*
G01X342973Y734930D02*
Y737430D01*
X341431Y735638D01*
X343515D01*
G01X345573Y734930D02*
Y737430D01*
X345073Y736930D01*
G01Y734930D02*
X346073D01*
G01X347756Y735430D02*
X348006Y735138D01*
X348340Y734972D01*
X348715Y734930D01*
X349048Y734972D01*
X349381Y735180D01*
X349590Y735430D01*
X349631Y735680D01*
X349548Y735972D01*
X349256Y736180D01*
X348965Y736263D01*
X348590D01*
G01X348965D02*
X349215Y736388D01*
X349423Y736597D01*
X349506Y736847D01*
X349423Y737097D01*
X349215Y737305D01*
X348840Y737430D01*
X348465Y737388D01*
X348090Y737222D01*
G01X350981Y735972D02*
X351273Y736263D01*
X351523Y736430D01*
X351856Y736513D01*
X352148Y736430D01*
X352356Y736263D01*
X352523Y736013D01*
X352565Y735722D01*
X352523Y735472D01*
X352356Y735222D01*
X352106Y735013D01*
X351815Y734930D01*
X351481Y735013D01*
X351190Y735263D01*
X351023Y735638D01*
X350981Y736055D01*
X351065Y736597D01*
X351190Y736888D01*
X351398Y737180D01*
X351690Y737388D01*
X351981Y737430D01*
X352273Y737347D01*
X352481Y737138D01*
G01X367193Y844704D02*
X367068Y844454D01*
X366985Y844162D01*
Y843829D01*
X367110Y843454D01*
X367318Y843162D01*
X367568Y842954D01*
X367985Y842787D01*
X368360Y842745D01*
X368735Y842829D01*
X368985Y842954D01*
X369235Y843204D01*
X369402Y843495D01*
X369485Y843787D01*
Y844079D01*
X369402Y844370D01*
X369277Y844620D01*
X369110Y844829D01*
G01X368985Y845970D02*
X369277Y846220D01*
X369443Y846554D01*
X369485Y846929D01*
X369443Y847262D01*
X369235Y847595D01*
X368985Y847804D01*
X368735Y847845D01*
X368443Y847762D01*
X368235Y847470D01*
X368152Y847179D01*
Y846804D01*
G01Y847179D02*
X368027Y847429D01*
X367818Y847637D01*
X367568Y847720D01*
X367318Y847637D01*
X367110Y847429D01*
X366985Y847054D01*
X367027Y846679D01*
X367193Y846304D01*
G01X369485Y849904D02*
X368943Y849987D01*
X368485Y850112D01*
X368068Y850279D01*
X367610Y850487D01*
X366985Y850820D01*
Y849154D01*
G01X369193Y852379D02*
X369402Y852670D01*
X369485Y853004D01*
X369402Y853337D01*
X369152Y853629D01*
X368777Y853837D01*
X368402Y853920D01*
X367943D01*
X367568Y853837D01*
X367235Y853629D01*
X367068Y853379D01*
X366985Y853087D01*
X367068Y852754D01*
X367235Y852504D01*
X367485Y852337D01*
X367818Y852254D01*
X368110Y852337D01*
X368402Y852545D01*
X368568Y852795D01*
X368610Y853087D01*
X368527Y853420D01*
X368318Y853670D01*
X367943Y853920D01*
G01X361908Y845067D02*
X361783Y844817D01*
X361700Y844525D01*
Y844192D01*
X361825Y843817D01*
X362033Y843525D01*
X362283Y843317D01*
X362700Y843150D01*
X363075Y843108D01*
X363450Y843192D01*
X363700Y843317D01*
X363950Y843567D01*
X364117Y843858D01*
X364200Y844150D01*
Y844442D01*
X364117Y844733D01*
X363992Y844983D01*
X363825Y845192D01*
G01X363700Y846333D02*
X363992Y846583D01*
X364158Y846917D01*
X364200Y847292D01*
X364158Y847625D01*
X363950Y847958D01*
X363700Y848167D01*
X363450Y848208D01*
X363158Y848125D01*
X362950Y847833D01*
X362867Y847542D01*
Y847167D01*
G01Y847542D02*
X362742Y847792D01*
X362533Y848000D01*
X362283Y848083D01*
X362033Y848000D01*
X361825Y847792D01*
X361700Y847417D01*
X361742Y847042D01*
X361908Y846667D01*
G01X364200Y850267D02*
X363658Y850350D01*
X363200Y850475D01*
X362783Y850642D01*
X362325Y850850D01*
X361700Y851183D01*
Y849517D01*
G01X364200Y853450D02*
X364158Y853742D01*
X364033Y854075D01*
X363825Y854283D01*
X363533Y854367D01*
X363242Y854283D01*
X362992Y854033D01*
X362867Y853658D01*
Y853242D01*
X362783Y852992D01*
X362575Y852783D01*
X362283Y852700D01*
X361992Y852825D01*
X361783Y853117D01*
X361700Y853450D01*
X361783Y853783D01*
X361992Y854075D01*
X362283Y854200D01*
X362575Y854117D01*
X362783Y853908D01*
X362867Y853658D01*
Y853242D01*
X362992Y852867D01*
X363242Y852617D01*
X363533Y852533D01*
X363825Y852617D01*
X364033Y852825D01*
X364158Y853158D01*
X364200Y853450D01*
G01X342508Y844567D02*
X342383Y844317D01*
X342300Y844025D01*
Y843692D01*
X342425Y843317D01*
X342633Y843025D01*
X342883Y842817D01*
X343300Y842650D01*
X343675Y842608D01*
X344050Y842692D01*
X344300Y842817D01*
X344550Y843067D01*
X344717Y843358D01*
X344800Y843650D01*
Y843942D01*
X344717Y844233D01*
X344592Y844483D01*
X344425Y844692D01*
G01X344300Y845833D02*
X344592Y846083D01*
X344758Y846417D01*
X344800Y846792D01*
X344758Y847125D01*
X344550Y847458D01*
X344300Y847667D01*
X344050Y847708D01*
X343758Y847625D01*
X343550Y847333D01*
X343467Y847042D01*
Y846667D01*
G01Y847042D02*
X343342Y847292D01*
X343133Y847500D01*
X342883Y847583D01*
X342633Y847500D01*
X342425Y847292D01*
X342300Y846917D01*
X342342Y846542D01*
X342508Y846167D01*
G01X344800Y850350D02*
X342300D01*
X344092Y848808D01*
Y850892D01*
G01X344800Y852950D02*
X344758Y853242D01*
X344633Y853575D01*
X344425Y853783D01*
X344133Y853867D01*
X343842Y853783D01*
X343592Y853533D01*
X343467Y853158D01*
Y852742D01*
X343383Y852492D01*
X343175Y852283D01*
X342883Y852200D01*
X342592Y852325D01*
X342383Y852617D01*
X342300Y852950D01*
X342383Y853283D01*
X342592Y853575D01*
X342883Y853700D01*
X343175Y853617D01*
X343383Y853408D01*
X343467Y853158D01*
Y852742D01*
X343592Y852367D01*
X343842Y852117D01*
X344133Y852033D01*
X344425Y852117D01*
X344633Y852325D01*
X344758Y852658D01*
X344800Y852950D01*
G01X336408Y844867D02*
X336283Y844617D01*
X336200Y844325D01*
Y843992D01*
X336325Y843617D01*
X336533Y843325D01*
X336783Y843117D01*
X337200Y842950D01*
X337575Y842908D01*
X337950Y842992D01*
X338200Y843117D01*
X338450Y843367D01*
X338617Y843658D01*
X338700Y843950D01*
Y844242D01*
X338617Y844533D01*
X338492Y844783D01*
X338325Y844992D01*
G01X338200Y846133D02*
X338492Y846383D01*
X338658Y846717D01*
X338700Y847092D01*
X338658Y847425D01*
X338450Y847758D01*
X338200Y847967D01*
X337950Y848008D01*
X337658Y847925D01*
X337450Y847633D01*
X337367Y847342D01*
Y846967D01*
G01Y847342D02*
X337242Y847592D01*
X337033Y847800D01*
X336783Y847883D01*
X336533Y847800D01*
X336325Y847592D01*
X336200Y847217D01*
X336242Y846842D01*
X336408Y846467D01*
G01X338700Y850650D02*
X336200D01*
X337992Y849108D01*
Y851192D01*
G01X338700Y853167D02*
X338158Y853250D01*
X337700Y853375D01*
X337283Y853542D01*
X336825Y853750D01*
X336200Y854083D01*
Y852417D01*
G01X349508Y844467D02*
X349383Y844217D01*
X349300Y843925D01*
Y843592D01*
X349425Y843217D01*
X349633Y842925D01*
X349883Y842717D01*
X350300Y842550D01*
X350675Y842508D01*
X351050Y842592D01*
X351300Y842717D01*
X351550Y842967D01*
X351717Y843258D01*
X351800Y843550D01*
Y843842D01*
X351717Y844133D01*
X351592Y844383D01*
X351425Y844592D01*
G01X351300Y845733D02*
X351592Y845983D01*
X351758Y846317D01*
X351800Y846692D01*
X351758Y847025D01*
X351550Y847358D01*
X351300Y847567D01*
X351050Y847608D01*
X350758Y847525D01*
X350550Y847233D01*
X350467Y846942D01*
Y846567D01*
G01Y846942D02*
X350342Y847192D01*
X350133Y847400D01*
X349883Y847483D01*
X349633Y847400D01*
X349425Y847192D01*
X349300Y846817D01*
X349342Y846442D01*
X349508Y846067D01*
G01X351800Y850250D02*
X349300D01*
X351092Y848708D01*
Y850792D01*
G01X350758Y852058D02*
X350467Y852350D01*
X350300Y852600D01*
X350217Y852933D01*
X350300Y853225D01*
X350467Y853433D01*
X350717Y853600D01*
X351008Y853642D01*
X351258Y853600D01*
X351508Y853433D01*
X351717Y853183D01*
X351800Y852892D01*
X351717Y852558D01*
X351467Y852267D01*
X351092Y852100D01*
X350675Y852058D01*
X350133Y852142D01*
X349842Y852267D01*
X349550Y852475D01*
X349342Y852767D01*
X349300Y853058D01*
X349383Y853350D01*
X349592Y853558D01*
G01X355108Y844467D02*
X354983Y844217D01*
X354900Y843925D01*
Y843592D01*
X355025Y843217D01*
X355233Y842925D01*
X355483Y842717D01*
X355900Y842550D01*
X356275Y842508D01*
X356650Y842592D01*
X356900Y842717D01*
X357150Y842967D01*
X357317Y843258D01*
X357400Y843550D01*
Y843842D01*
X357317Y844133D01*
X357192Y844383D01*
X357025Y844592D01*
G01X356900Y845733D02*
X357192Y845983D01*
X357358Y846317D01*
X357400Y846692D01*
X357358Y847025D01*
X357150Y847358D01*
X356900Y847567D01*
X356650Y847608D01*
X356358Y847525D01*
X356150Y847233D01*
X356067Y846942D01*
Y846567D01*
G01Y846942D02*
X355942Y847192D01*
X355733Y847400D01*
X355483Y847483D01*
X355233Y847400D01*
X355025Y847192D01*
X354900Y846817D01*
X354942Y846442D01*
X355108Y846067D01*
G01X357400Y850250D02*
X354900D01*
X356692Y848708D01*
Y850792D01*
G01X357025Y851933D02*
X357233Y852183D01*
X357358Y852475D01*
X357400Y852850D01*
X357317Y853225D01*
X357150Y853517D01*
X356858Y853725D01*
X356525Y853767D01*
X356192Y853683D01*
X355983Y853475D01*
X355817Y853183D01*
X355775Y852892D01*
X355817Y852600D01*
X355983Y852225D01*
X354900Y852350D01*
Y853475D01*
G01X379671Y143883D02*
X380171Y144300D01*
X380504Y144800D01*
X380671Y145383D01*
X380504Y146050D01*
X380171Y146550D01*
X379671Y147050D01*
X379004Y147217D01*
X375671D01*
G01X380671Y149483D02*
X375671D01*
Y151483D01*
X375921Y152150D01*
X376504Y152650D01*
X377171Y152817D01*
X377838Y152650D01*
X378338Y152233D01*
X378588Y151483D01*
Y149483D01*
G01X380671Y157750D02*
X375671D01*
X379254Y154667D01*
Y158833D01*
G01X380838Y162350D02*
X380754Y162183D01*
X380588D01*
X380504Y162350D01*
X380588Y162517D01*
X380754D01*
X380838Y162350D01*
G01X378588D02*
X378504Y162183D01*
X378338D01*
X378254Y162350D01*
X378338Y162517D01*
X378504D01*
X378588Y162350D01*
G01X378004Y168617D02*
X377754Y168950D01*
X377338Y169200D01*
X376754Y169367D01*
X376254Y169200D01*
X375921Y168867D01*
X375671Y168283D01*
Y166033D01*
X380671D01*
Y168783D01*
X380338Y169367D01*
X379838Y169700D01*
X379254Y169867D01*
X378671Y169700D01*
X378171Y169200D01*
X378004Y168617D01*
Y166033D01*
G01X380671Y171383D02*
X375671D01*
X379838Y173550D01*
X375671Y175717D01*
X380671D01*
G01X376088Y180983D02*
X375838Y180483D01*
X375671Y179900D01*
Y179233D01*
X375921Y178483D01*
X376338Y177900D01*
X376838Y177483D01*
X377671Y177150D01*
X378421Y177067D01*
X379171Y177233D01*
X379671Y177483D01*
X380171Y177983D01*
X380504Y178567D01*
X380671Y179150D01*
Y179733D01*
X380504Y180317D01*
X380254Y180817D01*
X379921Y181233D01*
G01X380671Y188267D02*
X375671Y190350D01*
X380671Y192433D01*
G01X378921Y191683D02*
Y189017D01*
G01X380671Y194117D02*
X375671D01*
Y195783D01*
X375921Y196450D01*
X376254Y196950D01*
X376754Y197367D01*
X377338Y197700D01*
X378171Y197783D01*
X379004Y197700D01*
X379588Y197367D01*
X380088Y196950D01*
X380421Y196450D01*
X380671Y195783D01*
Y194117D01*
G01Y199717D02*
X375671D01*
Y201383D01*
X375921Y202050D01*
X376254Y202550D01*
X376754Y202967D01*
X377338Y203300D01*
X378171Y203383D01*
X379004Y203300D01*
X379588Y202967D01*
X380088Y202550D01*
X380421Y202050D01*
X380671Y201383D01*
Y199717D01*
G01Y205483D02*
X375671D01*
Y207567D01*
X375921Y208233D01*
X376254Y208650D01*
X376921Y208817D01*
X377588Y208650D01*
X378004Y208150D01*
X378254Y207567D01*
Y205483D01*
G01Y207567D02*
X380671Y208817D01*
G01Y212750D02*
X375671D01*
X376671Y211750D01*
G01X380671D02*
Y213750D01*
G01Y222117D02*
X375671D01*
Y223783D01*
X375921Y224450D01*
X376254Y224950D01*
X376754Y225367D01*
X377338Y225700D01*
X378171Y225783D01*
X379004Y225700D01*
X379588Y225367D01*
X380088Y224950D01*
X380421Y224450D01*
X380671Y223783D01*
Y222117D01*
G01Y231217D02*
Y227883D01*
X375671D01*
Y231217D01*
G01X378088Y229883D02*
Y227883D01*
G01X380671Y233567D02*
X375671D01*
Y236733D01*
G01X378088Y235567D02*
Y233567D01*
G01X380671Y238667D02*
X375671Y240750D01*
X380671Y242833D01*
G01X378921Y242083D02*
Y239417D01*
G01X375671Y244517D02*
X379254D01*
X380004Y244850D01*
X380504Y245517D01*
X380671Y246350D01*
X380504Y247183D01*
X380004Y247850D01*
X379254Y248183D01*
X375671D01*
G01Y250283D02*
X380671D01*
Y253617D01*
G01X375671Y257550D02*
X380671D01*
G01X375671Y255633D02*
Y259467D01*
G01X380671Y268750D02*
X375671D01*
X376671Y267750D01*
G01X380671D02*
Y269750D01*
G01X379004Y273267D02*
Y275433D01*
G01X376504Y278367D02*
X376004Y278867D01*
X375754Y279450D01*
X375671Y280117D01*
X375838Y280950D01*
X376254Y281533D01*
X376754Y281700D01*
X377254Y281617D01*
X377671Y281283D01*
X378504Y279617D01*
X379088Y278867D01*
X379921Y278367D01*
X380671Y278200D01*
Y281700D01*
G01X394704Y143583D02*
X395204Y144000D01*
X395537Y144500D01*
X395704Y145083D01*
X395537Y145750D01*
X395204Y146250D01*
X394704Y146750D01*
X394037Y146917D01*
X390704D01*
G01X395704Y149183D02*
X390704D01*
Y151183D01*
X390954Y151850D01*
X391537Y152350D01*
X392204Y152517D01*
X392871Y152350D01*
X393371Y151933D01*
X393621Y151183D01*
Y149183D01*
G01X395704Y156450D02*
X390704D01*
X391704Y155450D01*
G01X395704D02*
Y157450D01*
G01X395871Y162050D02*
X395787Y161883D01*
X395621D01*
X395537Y162050D01*
X395621Y162217D01*
X395787D01*
X395871Y162050D01*
G01X393621D02*
X393537Y161883D01*
X393371D01*
X393287Y162050D01*
X393371Y162217D01*
X393537D01*
X393621Y162050D01*
G01X393037Y168317D02*
X392787Y168650D01*
X392371Y168900D01*
X391787Y169067D01*
X391287Y168900D01*
X390954Y168567D01*
X390704Y167983D01*
Y165733D01*
X395704D01*
Y168483D01*
X395371Y169067D01*
X394871Y169400D01*
X394287Y169567D01*
X393704Y169400D01*
X393204Y168900D01*
X393037Y168317D01*
Y165733D01*
G01X395704Y171083D02*
X390704D01*
X394871Y173250D01*
X390704Y175417D01*
X395704D01*
G01X391121Y180683D02*
X390871Y180183D01*
X390704Y179600D01*
Y178933D01*
X390954Y178183D01*
X391371Y177600D01*
X391871Y177183D01*
X392704Y176850D01*
X393454Y176767D01*
X394204Y176933D01*
X394704Y177183D01*
X395204Y177683D01*
X395537Y178267D01*
X395704Y178850D01*
Y179433D01*
X395537Y180017D01*
X395287Y180517D01*
X394954Y180933D01*
G01X395704Y191717D02*
Y188383D01*
X390704D01*
Y191717D01*
G01X393121Y190383D02*
Y188383D01*
G01X395704Y193733D02*
X390704D01*
X395704Y197567D01*
X390704D01*
G01X395704Y205017D02*
X390704D01*
Y206683D01*
X390954Y207350D01*
X391287Y207850D01*
X391787Y208267D01*
X392371Y208600D01*
X393204Y208683D01*
X394037Y208600D01*
X394621Y208267D01*
X395121Y207850D01*
X395454Y207350D01*
X395704Y206683D01*
Y205017D01*
G01Y214117D02*
Y210783D01*
X390704D01*
Y214117D01*
G01X393121Y212783D02*
Y210783D01*
G01X395704Y216467D02*
X390704D01*
Y219633D01*
G01X393121Y218467D02*
Y216467D01*
G01X395704Y221567D02*
X390704Y223650D01*
X395704Y225733D01*
G01X393954Y224983D02*
Y222317D01*
G01X390704Y227417D02*
X394287D01*
X395037Y227750D01*
X395537Y228417D01*
X395704Y229250D01*
X395537Y230083D01*
X395037Y230750D01*
X394287Y231083D01*
X390704D01*
G01Y233183D02*
X395704D01*
Y236517D01*
G01X390704Y240450D02*
X395704D01*
G01X390704Y238533D02*
Y242367D01*
G01X391537Y250067D02*
X391037Y250567D01*
X390787Y251150D01*
X390704Y251817D01*
X390871Y252650D01*
X391287Y253233D01*
X391787Y253400D01*
X392287Y253317D01*
X392704Y252983D01*
X393537Y251317D01*
X394121Y250567D01*
X394954Y250067D01*
X395704Y249900D01*
Y253400D01*
G01X394037Y256167D02*
Y258333D01*
G01X394704Y261017D02*
X395287Y261517D01*
X395621Y262183D01*
X395704Y262933D01*
X395621Y263600D01*
X395204Y264267D01*
X394704Y264683D01*
X394204Y264767D01*
X393621Y264600D01*
X393204Y264017D01*
X393037Y263433D01*
Y262683D01*
G01Y263433D02*
X392787Y263933D01*
X392371Y264350D01*
X391871Y264517D01*
X391371Y264350D01*
X390954Y263933D01*
X390704Y263183D01*
X390787Y262433D01*
X391121Y261683D01*
G01X387104Y143783D02*
X387604Y144200D01*
X387937Y144700D01*
X388104Y145283D01*
X387937Y145950D01*
X387604Y146450D01*
X387104Y146950D01*
X386437Y147117D01*
X383104D01*
G01X388104Y149383D02*
X383104D01*
Y151383D01*
X383354Y152050D01*
X383937Y152550D01*
X384604Y152717D01*
X385271Y152550D01*
X385771Y152133D01*
X386021Y151383D01*
Y149383D01*
G01Y155067D02*
X385437Y155650D01*
X385104Y156150D01*
X384937Y156817D01*
X385104Y157400D01*
X385437Y157817D01*
X385937Y158150D01*
X386521Y158233D01*
X387021Y158150D01*
X387521Y157817D01*
X387937Y157317D01*
X388104Y156733D01*
X387937Y156067D01*
X387437Y155483D01*
X386687Y155150D01*
X385854Y155067D01*
X384771Y155233D01*
X384187Y155483D01*
X383604Y155900D01*
X383187Y156483D01*
X383104Y157067D01*
X383271Y157650D01*
X383687Y158067D01*
G01X388271Y162250D02*
X388187Y162083D01*
X388021D01*
X387937Y162250D01*
X388021Y162417D01*
X388187D01*
X388271Y162250D01*
G01X386021D02*
X385937Y162083D01*
X385771D01*
X385687Y162250D01*
X385771Y162417D01*
X385937D01*
X386021Y162250D01*
G01X385437Y168517D02*
X385187Y168850D01*
X384771Y169100D01*
X384187Y169267D01*
X383687Y169100D01*
X383354Y168767D01*
X383104Y168183D01*
Y165933D01*
X388104D01*
Y168683D01*
X387771Y169267D01*
X387271Y169600D01*
X386687Y169767D01*
X386104Y169600D01*
X385604Y169100D01*
X385437Y168517D01*
Y165933D01*
G01X388104Y171283D02*
X383104D01*
X387271Y173450D01*
X383104Y175617D01*
X388104D01*
G01X383521Y180883D02*
X383271Y180383D01*
X383104Y179800D01*
Y179133D01*
X383354Y178383D01*
X383771Y177800D01*
X384271Y177383D01*
X385104Y177050D01*
X385854Y176967D01*
X386604Y177133D01*
X387104Y177383D01*
X387604Y177883D01*
X387937Y178467D01*
X388104Y179050D01*
Y179633D01*
X387937Y180217D01*
X387687Y180717D01*
X387354Y181133D01*
G01X388104Y188167D02*
X383104Y190250D01*
X388104Y192333D01*
G01X386354Y191583D02*
Y188917D01*
G01X388104Y194017D02*
X383104D01*
Y195683D01*
X383354Y196350D01*
X383687Y196850D01*
X384187Y197267D01*
X384771Y197600D01*
X385604Y197683D01*
X386437Y197600D01*
X387021Y197267D01*
X387521Y196850D01*
X387854Y196350D01*
X388104Y195683D01*
Y194017D01*
G01Y199617D02*
X383104D01*
Y201283D01*
X383354Y201950D01*
X383687Y202450D01*
X384187Y202867D01*
X384771Y203200D01*
X385604Y203283D01*
X386437Y203200D01*
X387021Y202867D01*
X387521Y202450D01*
X387854Y201950D01*
X388104Y201283D01*
Y199617D01*
G01Y205383D02*
X383104D01*
Y207467D01*
X383354Y208133D01*
X383687Y208550D01*
X384354Y208717D01*
X385021Y208550D01*
X385437Y208050D01*
X385687Y207467D01*
Y205383D01*
G01Y207467D02*
X388104Y208717D01*
G01X383937Y211067D02*
X383437Y211567D01*
X383187Y212150D01*
X383104Y212817D01*
X383271Y213650D01*
X383687Y214233D01*
X384187Y214400D01*
X384687Y214317D01*
X385104Y213983D01*
X385937Y212317D01*
X386521Y211567D01*
X387354Y211067D01*
X388104Y210900D01*
Y214400D01*
G01Y222017D02*
X383104D01*
Y223683D01*
X383354Y224350D01*
X383687Y224850D01*
X384187Y225267D01*
X384771Y225600D01*
X385604Y225683D01*
X386437Y225600D01*
X387021Y225267D01*
X387521Y224850D01*
X387854Y224350D01*
X388104Y223683D01*
Y222017D01*
G01Y231117D02*
Y227783D01*
X383104D01*
Y231117D01*
G01X385521Y229783D02*
Y227783D01*
G01X388104Y233467D02*
X383104D01*
Y236633D01*
G01X385521Y235467D02*
Y233467D01*
G01X388104Y238567D02*
X383104Y240650D01*
X388104Y242733D01*
G01X386354Y241983D02*
Y239317D01*
G01X383104Y244417D02*
X386687D01*
X387437Y244750D01*
X387937Y245417D01*
X388104Y246250D01*
X387937Y247083D01*
X387437Y247750D01*
X386687Y248083D01*
X383104D01*
G01Y250183D02*
X388104D01*
Y253517D01*
G01X383104Y257450D02*
X388104D01*
G01X383104Y255533D02*
Y259367D01*
G01X388104Y268650D02*
X383104D01*
X384104Y267650D01*
G01X388104D02*
Y269650D01*
G01X386437Y273167D02*
Y275333D01*
G01X383937Y278267D02*
X383437Y278767D01*
X383187Y279350D01*
X383104Y280017D01*
X383271Y280850D01*
X383687Y281433D01*
X384187Y281600D01*
X384687Y281517D01*
X385104Y281183D01*
X385937Y279517D01*
X386521Y278767D01*
X387354Y278267D01*
X388104Y278100D01*
Y281600D01*
G01X371640Y377277D02*
X369140D01*
Y378318D01*
X369265Y378652D01*
X369432Y378860D01*
X369765Y378943D01*
X370098Y378860D01*
X370307Y378610D01*
X370432Y378318D01*
Y377277D01*
G01Y378318D02*
X371640Y378943D01*
G01Y381710D02*
X369140D01*
X370932Y380168D01*
Y382252D01*
G01X371640Y384310D02*
X369140D01*
X369640Y383810D01*
G01X371640D02*
Y384810D01*
G01X371348Y386702D02*
X371557Y386993D01*
X371640Y387327D01*
X371557Y387660D01*
X371307Y387952D01*
X370932Y388160D01*
X370557Y388243D01*
X370098D01*
X369723Y388160D01*
X369390Y387952D01*
X369223Y387702D01*
X369140Y387410D01*
X369223Y387077D01*
X369390Y386827D01*
X369640Y386660D01*
X369973Y386577D01*
X370265Y386660D01*
X370557Y386868D01*
X370723Y387118D01*
X370765Y387410D01*
X370682Y387743D01*
X370473Y387993D01*
X370098Y388243D01*
G01X393340Y407360D02*
X395840D01*
G01X393340Y406402D02*
Y408318D01*
G01X395840Y409627D02*
X393340D01*
Y410627D01*
X393465Y410960D01*
X393757Y411210D01*
X394090Y411293D01*
X394423Y411210D01*
X394673Y411002D01*
X394798Y410627D01*
Y409627D01*
G01X395840Y413560D02*
X393340D01*
X393840Y413060D01*
G01X395840D02*
Y414060D01*
G01X394798Y415868D02*
X394507Y416160D01*
X394340Y416410D01*
X394257Y416743D01*
X394340Y417035D01*
X394507Y417243D01*
X394757Y417410D01*
X395048Y417452D01*
X395298Y417410D01*
X395548Y417243D01*
X395757Y416993D01*
X395840Y416702D01*
X395757Y416368D01*
X395507Y416077D01*
X395132Y415910D01*
X394715Y415868D01*
X394173Y415952D01*
X393882Y416077D01*
X393590Y416285D01*
X393382Y416577D01*
X393340Y416868D01*
X393423Y417160D01*
X393632Y417368D01*
G01X395465Y418843D02*
X395673Y419093D01*
X395798Y419385D01*
X395840Y419760D01*
X395757Y420135D01*
X395590Y420427D01*
X395298Y420635D01*
X394965Y420677D01*
X394632Y420593D01*
X394423Y420385D01*
X394257Y420093D01*
X394215Y419802D01*
X394257Y419510D01*
X394423Y419135D01*
X393340Y419260D01*
Y420385D01*
G01X378150Y386620D02*
X380650D01*
G01X378150Y385662D02*
Y387578D01*
G01X380650Y388887D02*
X378150D01*
Y389887D01*
X378275Y390220D01*
X378567Y390470D01*
X378900Y390553D01*
X379233Y390470D01*
X379483Y390262D01*
X379608Y389887D01*
Y388887D01*
G01X380650Y392820D02*
X378150D01*
X378650Y392320D01*
G01X380650D02*
Y393320D01*
G01Y396420D02*
X378150D01*
X379942Y394878D01*
Y396962D01*
G01X380650Y399020D02*
X380608Y399312D01*
X380483Y399645D01*
X380275Y399853D01*
X379983Y399937D01*
X379692Y399853D01*
X379442Y399603D01*
X379317Y399228D01*
Y398812D01*
X379233Y398562D01*
X379025Y398353D01*
X378733Y398270D01*
X378442Y398395D01*
X378233Y398687D01*
X378150Y399020D01*
X378233Y399353D01*
X378442Y399645D01*
X378733Y399770D01*
X379025Y399687D01*
X379233Y399478D01*
X379317Y399228D01*
Y398812D01*
X379442Y398437D01*
X379692Y398187D01*
X379983Y398103D01*
X380275Y398187D01*
X380483Y398395D01*
X380608Y398728D01*
X380650Y399020D01*
G01X372640Y387960D02*
X375140D01*
G01X372640Y387002D02*
Y388918D01*
G01X375140Y390227D02*
X372640D01*
Y391227D01*
X372765Y391560D01*
X373057Y391810D01*
X373390Y391893D01*
X373723Y391810D01*
X373973Y391602D01*
X374098Y391227D01*
Y390227D01*
G01X375140Y394160D02*
X372640D01*
X373140Y393660D01*
G01X375140D02*
Y394660D01*
G01Y397760D02*
X372640D01*
X374432Y396218D01*
Y398302D01*
G01X374848Y399652D02*
X375057Y399943D01*
X375140Y400277D01*
X375057Y400610D01*
X374807Y400902D01*
X374432Y401110D01*
X374057Y401193D01*
X373598D01*
X373223Y401110D01*
X372890Y400902D01*
X372723Y400652D01*
X372640Y400360D01*
X372723Y400027D01*
X372890Y399777D01*
X373140Y399610D01*
X373473Y399527D01*
X373765Y399610D01*
X374057Y399818D01*
X374223Y400068D01*
X374265Y400360D01*
X374182Y400693D01*
X373973Y400943D01*
X373598Y401193D01*
G01X386857Y403027D02*
Y405527D01*
X387898D01*
X388232Y405402D01*
X388440Y405235D01*
X388523Y404902D01*
X388440Y404569D01*
X388190Y404360D01*
X387898Y404235D01*
X386857D01*
G01X387898D02*
X388523Y403027D01*
G01X391290D02*
Y405527D01*
X389748Y403735D01*
X391832D01*
G01X393890Y405527D02*
X393557Y405444D01*
X393307Y405235D01*
X393140Y404985D01*
X393015Y404652D01*
X392973Y404277D01*
X393015Y403902D01*
X393140Y403569D01*
X393307Y403319D01*
X393557Y403110D01*
X393890Y403027D01*
X394223Y403110D01*
X394473Y403319D01*
X394640Y403569D01*
X394765Y403902D01*
X394807Y404277D01*
X394765Y404652D01*
X394640Y404985D01*
X394473Y405235D01*
X394223Y405444D01*
X393890Y405527D01*
G01X396198Y404069D02*
X396490Y404360D01*
X396740Y404527D01*
X397073Y404610D01*
X397365Y404527D01*
X397573Y404360D01*
X397740Y404110D01*
X397782Y403819D01*
X397740Y403569D01*
X397573Y403319D01*
X397323Y403110D01*
X397032Y403027D01*
X396698Y403110D01*
X396407Y403360D01*
X396240Y403735D01*
X396198Y404152D01*
X396282Y404694D01*
X396407Y404985D01*
X396615Y405277D01*
X396907Y405485D01*
X397198Y405527D01*
X397490Y405444D01*
X397698Y405235D01*
G01X402173Y403377D02*
X399673D01*
Y404418D01*
X399798Y404752D01*
X399965Y404960D01*
X400298Y405043D01*
X400631Y404960D01*
X400840Y404710D01*
X400965Y404418D01*
Y403377D01*
G01Y404418D02*
X402173Y405043D01*
G01Y407810D02*
X399673D01*
X401465Y406268D01*
Y408352D01*
G01X399673Y410410D02*
X399756Y410077D01*
X399965Y409827D01*
X400215Y409660D01*
X400548Y409535D01*
X400923Y409493D01*
X401298Y409535D01*
X401631Y409660D01*
X401881Y409827D01*
X402090Y410077D01*
X402173Y410410D01*
X402090Y410743D01*
X401881Y410993D01*
X401631Y411160D01*
X401298Y411285D01*
X400923Y411327D01*
X400548Y411285D01*
X400215Y411160D01*
X399965Y410993D01*
X399756Y410743D01*
X399673Y410410D01*
G01X402173Y414010D02*
X399673D01*
X401465Y412468D01*
Y414552D01*
G01X380357Y409027D02*
Y411527D01*
X381398D01*
X381732Y411402D01*
X381940Y411235D01*
X382023Y410902D01*
X381940Y410569D01*
X381690Y410360D01*
X381398Y410235D01*
X380357D01*
G01X381398D02*
X382023Y409027D01*
G01X383373Y409527D02*
X383623Y409235D01*
X383957Y409069D01*
X384332Y409027D01*
X384665Y409069D01*
X384998Y409277D01*
X385207Y409527D01*
X385248Y409777D01*
X385165Y410069D01*
X384873Y410277D01*
X384582Y410360D01*
X384207D01*
G01X384582D02*
X384832Y410485D01*
X385040Y410694D01*
X385123Y410944D01*
X385040Y411194D01*
X384832Y411402D01*
X384457Y411527D01*
X384082Y411485D01*
X383707Y411319D01*
G01X387307Y409027D02*
X387390Y409569D01*
X387515Y410027D01*
X387682Y410444D01*
X387890Y410902D01*
X388223Y411527D01*
X386557D01*
G01X389782Y409319D02*
X390073Y409110D01*
X390407Y409027D01*
X390740Y409110D01*
X391032Y409360D01*
X391240Y409735D01*
X391323Y410110D01*
Y410569D01*
X391240Y410944D01*
X391032Y411277D01*
X390782Y411444D01*
X390490Y411527D01*
X390157Y411444D01*
X389907Y411277D01*
X389740Y411027D01*
X389657Y410694D01*
X389740Y410402D01*
X389948Y410110D01*
X390198Y409944D01*
X390490Y409902D01*
X390823Y409985D01*
X391073Y410194D01*
X391323Y410569D01*
G01X384307Y397527D02*
Y400027D01*
X385348D01*
X385682Y399902D01*
X385890Y399735D01*
X385973Y399402D01*
X385890Y399069D01*
X385640Y398860D01*
X385348Y398735D01*
X384307D01*
G01X385348D02*
X385973Y397527D01*
G01X387448Y399610D02*
X387698Y399860D01*
X387990Y399985D01*
X388323Y400027D01*
X388740Y399944D01*
X389032Y399735D01*
X389115Y399485D01*
X389073Y399235D01*
X388907Y399027D01*
X388073Y398610D01*
X387698Y398319D01*
X387448Y397902D01*
X387365Y397527D01*
X389115D01*
G01X390632Y397819D02*
X390923Y397610D01*
X391257Y397527D01*
X391590Y397610D01*
X391882Y397860D01*
X392090Y398235D01*
X392173Y398610D01*
Y399069D01*
X392090Y399444D01*
X391882Y399777D01*
X391632Y399944D01*
X391340Y400027D01*
X391007Y399944D01*
X390757Y399777D01*
X390590Y399527D01*
X390507Y399194D01*
X390590Y398902D01*
X390798Y398610D01*
X391048Y398444D01*
X391340Y398402D01*
X391673Y398485D01*
X391923Y398694D01*
X392173Y399069D01*
G01X394940Y397527D02*
Y400027D01*
X393398Y398235D01*
X395482D01*
G01X397540Y397527D02*
X397832Y397569D01*
X398165Y397694D01*
X398373Y397902D01*
X398457Y398194D01*
X398373Y398485D01*
X398123Y398735D01*
X397748Y398860D01*
X397332D01*
X397082Y398944D01*
X396873Y399152D01*
X396790Y399444D01*
X396915Y399735D01*
X397207Y399944D01*
X397540Y400027D01*
X397873Y399944D01*
X398165Y399735D01*
X398290Y399444D01*
X398207Y399152D01*
X397998Y398944D01*
X397748Y398860D01*
X397332D01*
X396957Y398735D01*
X396707Y398485D01*
X396623Y398194D01*
X396707Y397902D01*
X396915Y397694D01*
X397248Y397569D01*
X397540Y397527D01*
G01X377137Y403452D02*
X376887Y403577D01*
X376595Y403660D01*
X376262D01*
X375887Y403535D01*
X375595Y403327D01*
X375387Y403077D01*
X375220Y402660D01*
X375178Y402285D01*
X375262Y401910D01*
X375387Y401660D01*
X375637Y401410D01*
X375928Y401243D01*
X376220Y401160D01*
X376512D01*
X376803Y401243D01*
X377053Y401368D01*
X377262Y401535D01*
G01X378528Y402202D02*
X378820Y402493D01*
X379070Y402660D01*
X379403Y402743D01*
X379695Y402660D01*
X379903Y402493D01*
X380070Y402243D01*
X380112Y401952D01*
X380070Y401702D01*
X379903Y401452D01*
X379653Y401243D01*
X379362Y401160D01*
X379028Y401243D01*
X378737Y401493D01*
X378570Y401868D01*
X378528Y402285D01*
X378612Y402827D01*
X378737Y403118D01*
X378945Y403410D01*
X379237Y403618D01*
X379528Y403660D01*
X379820Y403577D01*
X380028Y403368D01*
G01X381503Y401660D02*
X381753Y401368D01*
X382087Y401202D01*
X382462Y401160D01*
X382795Y401202D01*
X383128Y401410D01*
X383337Y401660D01*
X383378Y401910D01*
X383295Y402202D01*
X383003Y402410D01*
X382712Y402493D01*
X382337D01*
G01X382712D02*
X382962Y402618D01*
X383170Y402827D01*
X383253Y403077D01*
X383170Y403327D01*
X382962Y403535D01*
X382587Y403660D01*
X382212Y403618D01*
X381837Y403452D01*
G01X385520Y401160D02*
Y403660D01*
X385020Y403160D01*
G01Y401160D02*
X386020D01*
G01X388857Y430260D02*
Y432760D01*
X389898D01*
X390232Y432635D01*
X390440Y432468D01*
X390523Y432135D01*
X390440Y431802D01*
X390190Y431593D01*
X389898Y431468D01*
X388857D01*
G01X389898D02*
X390523Y430260D01*
G01X391873Y430760D02*
X392123Y430468D01*
X392457Y430302D01*
X392832Y430260D01*
X393165Y430302D01*
X393498Y430510D01*
X393707Y430760D01*
X393748Y431010D01*
X393665Y431302D01*
X393373Y431510D01*
X393082Y431593D01*
X392707D01*
G01X393082D02*
X393332Y431718D01*
X393540Y431927D01*
X393623Y432177D01*
X393540Y432427D01*
X393332Y432635D01*
X392957Y432760D01*
X392582Y432718D01*
X392207Y432552D01*
G01X395182Y430552D02*
X395473Y430343D01*
X395807Y430260D01*
X396140Y430343D01*
X396432Y430593D01*
X396640Y430968D01*
X396723Y431343D01*
Y431802D01*
X396640Y432177D01*
X396432Y432510D01*
X396182Y432677D01*
X395890Y432760D01*
X395557Y432677D01*
X395307Y432510D01*
X395140Y432260D01*
X395057Y431927D01*
X395140Y431635D01*
X395348Y431343D01*
X395598Y431177D01*
X395890Y431135D01*
X396223Y431218D01*
X396473Y431427D01*
X396723Y431802D01*
G01X398073Y430760D02*
X398323Y430468D01*
X398657Y430302D01*
X399032Y430260D01*
X399365Y430302D01*
X399698Y430510D01*
X399907Y430760D01*
X399948Y431010D01*
X399865Y431302D01*
X399573Y431510D01*
X399282Y431593D01*
X398907D01*
G01X399282D02*
X399532Y431718D01*
X399740Y431927D01*
X399823Y432177D01*
X399740Y432427D01*
X399532Y432635D01*
X399157Y432760D01*
X398782Y432718D01*
X398407Y432552D01*
G01X388857Y434260D02*
Y436760D01*
X389898D01*
X390232Y436635D01*
X390440Y436468D01*
X390523Y436135D01*
X390440Y435802D01*
X390190Y435593D01*
X389898Y435468D01*
X388857D01*
G01X389898D02*
X390523Y434260D01*
G01X391873Y434760D02*
X392123Y434468D01*
X392457Y434302D01*
X392832Y434260D01*
X393165Y434302D01*
X393498Y434510D01*
X393707Y434760D01*
X393748Y435010D01*
X393665Y435302D01*
X393373Y435510D01*
X393082Y435593D01*
X392707D01*
G01X393082D02*
X393332Y435718D01*
X393540Y435927D01*
X393623Y436177D01*
X393540Y436427D01*
X393332Y436635D01*
X392957Y436760D01*
X392582Y436718D01*
X392207Y436552D01*
G01X395182Y434552D02*
X395473Y434343D01*
X395807Y434260D01*
X396140Y434343D01*
X396432Y434593D01*
X396640Y434968D01*
X396723Y435343D01*
Y435802D01*
X396640Y436177D01*
X396432Y436510D01*
X396182Y436677D01*
X395890Y436760D01*
X395557Y436677D01*
X395307Y436510D01*
X395140Y436260D01*
X395057Y435927D01*
X395140Y435635D01*
X395348Y435343D01*
X395598Y435177D01*
X395890Y435135D01*
X396223Y435218D01*
X396473Y435427D01*
X396723Y435802D01*
G01X398198Y436343D02*
X398448Y436593D01*
X398740Y436718D01*
X399073Y436760D01*
X399490Y436677D01*
X399782Y436468D01*
X399865Y436218D01*
X399823Y435968D01*
X399657Y435760D01*
X398823Y435343D01*
X398448Y435052D01*
X398198Y434635D01*
X398115Y434260D01*
X399865D01*
G01X388857Y426260D02*
Y428760D01*
X389898D01*
X390232Y428635D01*
X390440Y428468D01*
X390523Y428135D01*
X390440Y427802D01*
X390190Y427593D01*
X389898Y427468D01*
X388857D01*
G01X389898D02*
X390523Y426260D01*
G01X391873Y426760D02*
X392123Y426468D01*
X392457Y426302D01*
X392832Y426260D01*
X393165Y426302D01*
X393498Y426510D01*
X393707Y426760D01*
X393748Y427010D01*
X393665Y427302D01*
X393373Y427510D01*
X393082Y427593D01*
X392707D01*
G01X393082D02*
X393332Y427718D01*
X393540Y427927D01*
X393623Y428177D01*
X393540Y428427D01*
X393332Y428635D01*
X392957Y428760D01*
X392582Y428718D01*
X392207Y428552D01*
G01X395807Y426260D02*
X395890Y426802D01*
X396015Y427260D01*
X396182Y427677D01*
X396390Y428135D01*
X396723Y428760D01*
X395057D01*
G01X398198Y427302D02*
X398490Y427593D01*
X398740Y427760D01*
X399073Y427843D01*
X399365Y427760D01*
X399573Y427593D01*
X399740Y427343D01*
X399782Y427052D01*
X399740Y426802D01*
X399573Y426552D01*
X399323Y426343D01*
X399032Y426260D01*
X398698Y426343D01*
X398407Y426593D01*
X398240Y426968D01*
X398198Y427385D01*
X398282Y427927D01*
X398407Y428218D01*
X398615Y428510D01*
X398907Y428718D01*
X399198Y428760D01*
X399490Y428677D01*
X399698Y428468D01*
G01X388857Y422260D02*
Y424760D01*
X389898D01*
X390232Y424635D01*
X390440Y424468D01*
X390523Y424135D01*
X390440Y423802D01*
X390190Y423593D01*
X389898Y423468D01*
X388857D01*
G01X389898D02*
X390523Y422260D01*
G01X391873Y422760D02*
X392123Y422468D01*
X392457Y422302D01*
X392832Y422260D01*
X393165Y422302D01*
X393498Y422510D01*
X393707Y422760D01*
X393748Y423010D01*
X393665Y423302D01*
X393373Y423510D01*
X393082Y423593D01*
X392707D01*
G01X393082D02*
X393332Y423718D01*
X393540Y423927D01*
X393623Y424177D01*
X393540Y424427D01*
X393332Y424635D01*
X392957Y424760D01*
X392582Y424718D01*
X392207Y424552D01*
G01X395807Y422260D02*
X395890Y422802D01*
X396015Y423260D01*
X396182Y423677D01*
X396390Y424135D01*
X396723Y424760D01*
X395057D01*
G01X398073Y422635D02*
X398323Y422427D01*
X398615Y422302D01*
X398990Y422260D01*
X399365Y422343D01*
X399657Y422510D01*
X399865Y422802D01*
X399907Y423135D01*
X399823Y423468D01*
X399615Y423677D01*
X399323Y423843D01*
X399032Y423885D01*
X398740Y423843D01*
X398365Y423677D01*
X398490Y424760D01*
X399615D01*
G01X388597Y443010D02*
Y445510D01*
X389638D01*
X389972Y445385D01*
X390180Y445218D01*
X390263Y444885D01*
X390180Y444552D01*
X389930Y444343D01*
X389638Y444218D01*
X388597D01*
G01X389638D02*
X390263Y443010D01*
G01X391613Y443510D02*
X391863Y443218D01*
X392197Y443052D01*
X392572Y443010D01*
X392905Y443052D01*
X393238Y443260D01*
X393447Y443510D01*
X393488Y443760D01*
X393405Y444052D01*
X393113Y444260D01*
X392822Y444343D01*
X392447D01*
G01X392822D02*
X393072Y444468D01*
X393280Y444677D01*
X393363Y444927D01*
X393280Y445177D01*
X393072Y445385D01*
X392697Y445510D01*
X392322Y445468D01*
X391947Y445302D01*
G01X395630Y443010D02*
X395922Y443052D01*
X396255Y443177D01*
X396463Y443385D01*
X396547Y443677D01*
X396463Y443968D01*
X396213Y444218D01*
X395838Y444343D01*
X395422D01*
X395172Y444427D01*
X394963Y444635D01*
X394880Y444927D01*
X395005Y445218D01*
X395297Y445427D01*
X395630Y445510D01*
X395963Y445427D01*
X396255Y445218D01*
X396380Y444927D01*
X396297Y444635D01*
X396088Y444427D01*
X395838Y444343D01*
X395422D01*
X395047Y444218D01*
X394797Y443968D01*
X394713Y443677D01*
X394797Y443385D01*
X395005Y443177D01*
X395338Y443052D01*
X395630Y443010D01*
G01X397813Y443510D02*
X398063Y443218D01*
X398397Y443052D01*
X398772Y443010D01*
X399105Y443052D01*
X399438Y443260D01*
X399647Y443510D01*
X399688Y443760D01*
X399605Y444052D01*
X399313Y444260D01*
X399022Y444343D01*
X398647D01*
G01X399022D02*
X399272Y444468D01*
X399480Y444677D01*
X399563Y444927D01*
X399480Y445177D01*
X399272Y445385D01*
X398897Y445510D01*
X398522Y445468D01*
X398147Y445302D01*
G01X390707Y440352D02*
X390457Y440477D01*
X390165Y440560D01*
X389832D01*
X389457Y440435D01*
X389165Y440227D01*
X388957Y439977D01*
X388790Y439560D01*
X388748Y439185D01*
X388832Y438810D01*
X388957Y438560D01*
X389207Y438310D01*
X389498Y438143D01*
X389790Y438060D01*
X390082D01*
X390373Y438143D01*
X390623Y438268D01*
X390832Y438435D01*
G01X392098Y439102D02*
X392390Y439393D01*
X392640Y439560D01*
X392973Y439643D01*
X393265Y439560D01*
X393473Y439393D01*
X393640Y439143D01*
X393682Y438852D01*
X393640Y438602D01*
X393473Y438352D01*
X393223Y438143D01*
X392932Y438060D01*
X392598Y438143D01*
X392307Y438393D01*
X392140Y438768D01*
X392098Y439185D01*
X392182Y439727D01*
X392307Y440018D01*
X392515Y440310D01*
X392807Y440518D01*
X393098Y440560D01*
X393390Y440477D01*
X393598Y440268D01*
G01X395073Y438560D02*
X395323Y438268D01*
X395657Y438102D01*
X396032Y438060D01*
X396365Y438102D01*
X396698Y438310D01*
X396907Y438560D01*
X396948Y438810D01*
X396865Y439102D01*
X396573Y439310D01*
X396282Y439393D01*
X395907D01*
G01X396282D02*
X396532Y439518D01*
X396740Y439727D01*
X396823Y439977D01*
X396740Y440227D01*
X396532Y440435D01*
X396157Y440560D01*
X395782Y440518D01*
X395407Y440352D01*
G01X398298Y440143D02*
X398548Y440393D01*
X398840Y440518D01*
X399173Y440560D01*
X399590Y440477D01*
X399882Y440268D01*
X399965Y440018D01*
X399923Y439768D01*
X399757Y439560D01*
X398923Y439143D01*
X398548Y438852D01*
X398298Y438435D01*
X398215Y438060D01*
X399965D01*
G01X373149Y458822D02*
Y456322D01*
G01X372191Y458822D02*
X374107D01*
G01X375416Y456322D02*
Y458822D01*
X376416D01*
X376749Y458697D01*
X376999Y458405D01*
X377082Y458072D01*
X376999Y457739D01*
X376791Y457489D01*
X376416Y457364D01*
X375416D01*
G01X379349Y456322D02*
Y458822D01*
X378849Y458322D01*
G01Y456322D02*
X379849D01*
G01X382366D02*
X382449Y456864D01*
X382574Y457322D01*
X382741Y457739D01*
X382949Y458197D01*
X383282Y458822D01*
X381616D01*
G01X385549D02*
X385216Y458739D01*
X384966Y458530D01*
X384799Y458280D01*
X384674Y457947D01*
X384632Y457572D01*
X384674Y457197D01*
X384799Y456864D01*
X384966Y456614D01*
X385216Y456405D01*
X385549Y456322D01*
X385882Y456405D01*
X386132Y456614D01*
X386299Y456864D01*
X386424Y457197D01*
X386466Y457572D01*
X386424Y457947D01*
X386299Y458280D01*
X386132Y458530D01*
X385882Y458739D01*
X385549Y458822D01*
G01X373050Y452990D02*
Y450490D01*
G01X372092Y452990D02*
X374008D01*
G01X375317Y450490D02*
Y452990D01*
X376317D01*
X376650Y452865D01*
X376900Y452573D01*
X376983Y452240D01*
X376900Y451907D01*
X376692Y451657D01*
X376317Y451532D01*
X375317D01*
G01X379250Y450490D02*
Y452990D01*
X378750Y452490D01*
G01Y450490D02*
X379750D01*
G01X381433Y450865D02*
X381683Y450657D01*
X381975Y450532D01*
X382350Y450490D01*
X382725Y450573D01*
X383017Y450740D01*
X383225Y451032D01*
X383267Y451365D01*
X383183Y451698D01*
X382975Y451907D01*
X382683Y452073D01*
X382392Y452115D01*
X382100Y452073D01*
X381725Y451907D01*
X381850Y452990D01*
X382975D01*
G01X385450Y450490D02*
X385742Y450532D01*
X386075Y450657D01*
X386283Y450865D01*
X386367Y451157D01*
X386283Y451448D01*
X386033Y451698D01*
X385658Y451823D01*
X385242D01*
X384992Y451907D01*
X384783Y452115D01*
X384700Y452407D01*
X384825Y452698D01*
X385117Y452907D01*
X385450Y452990D01*
X385783Y452907D01*
X386075Y452698D01*
X386200Y452407D01*
X386117Y452115D01*
X385908Y451907D01*
X385658Y451823D01*
X385242D01*
X384867Y451698D01*
X384617Y451448D01*
X384533Y451157D01*
X384617Y450865D01*
X384825Y450657D01*
X385158Y450532D01*
X385450Y450490D01*
G01X388547Y447140D02*
Y449640D01*
X389588D01*
X389922Y449515D01*
X390130Y449348D01*
X390213Y449015D01*
X390130Y448682D01*
X389880Y448473D01*
X389588Y448348D01*
X388547D01*
G01X389588D02*
X390213Y447140D01*
G01X391563Y447640D02*
X391813Y447348D01*
X392147Y447182D01*
X392522Y447140D01*
X392855Y447182D01*
X393188Y447390D01*
X393397Y447640D01*
X393438Y447890D01*
X393355Y448182D01*
X393063Y448390D01*
X392772Y448473D01*
X392397D01*
G01X392772D02*
X393022Y448598D01*
X393230Y448807D01*
X393313Y449057D01*
X393230Y449307D01*
X393022Y449515D01*
X392647Y449640D01*
X392272Y449598D01*
X391897Y449432D01*
G01X395580Y447140D02*
X395872Y447182D01*
X396205Y447307D01*
X396413Y447515D01*
X396497Y447807D01*
X396413Y448098D01*
X396163Y448348D01*
X395788Y448473D01*
X395372D01*
X395122Y448557D01*
X394913Y448765D01*
X394830Y449057D01*
X394955Y449348D01*
X395247Y449557D01*
X395580Y449640D01*
X395913Y449557D01*
X396205Y449348D01*
X396330Y449057D01*
X396247Y448765D01*
X396038Y448557D01*
X395788Y448473D01*
X395372D01*
X394997Y448348D01*
X394747Y448098D01*
X394663Y447807D01*
X394747Y447515D01*
X394955Y447307D01*
X395288Y447182D01*
X395580Y447140D01*
G01X398597D02*
X398680Y447682D01*
X398805Y448140D01*
X398972Y448557D01*
X399180Y449015D01*
X399513Y449640D01*
X397847D01*
G01X386940Y462838D02*
X384440D01*
Y463879D01*
X384565Y464213D01*
X384732Y464421D01*
X385065Y464504D01*
X385398Y464421D01*
X385607Y464171D01*
X385732Y463879D01*
Y462838D01*
G01Y463879D02*
X386940Y464504D01*
G01Y467271D02*
X384440D01*
X386232Y465729D01*
Y467813D01*
G01X384440Y469871D02*
X384523Y469538D01*
X384732Y469288D01*
X384982Y469121D01*
X385315Y468996D01*
X385690Y468954D01*
X386065Y468996D01*
X386398Y469121D01*
X386648Y469288D01*
X386857Y469538D01*
X386940Y469871D01*
X386857Y470204D01*
X386648Y470454D01*
X386398Y470621D01*
X386065Y470746D01*
X385690Y470788D01*
X385315Y470746D01*
X384982Y470621D01*
X384732Y470454D01*
X384523Y470204D01*
X384440Y469871D01*
G01X386565Y472054D02*
X386773Y472304D01*
X386898Y472596D01*
X386940Y472971D01*
X386857Y473346D01*
X386690Y473638D01*
X386398Y473846D01*
X386065Y473888D01*
X385732Y473804D01*
X385523Y473596D01*
X385357Y473304D01*
X385315Y473013D01*
X385357Y472721D01*
X385523Y472346D01*
X384440Y472471D01*
Y473596D01*
G01X382870Y462727D02*
X380370D01*
Y463768D01*
X380495Y464102D01*
X380662Y464310D01*
X380995Y464393D01*
X381328Y464310D01*
X381537Y464060D01*
X381662Y463768D01*
Y462727D01*
G01Y463768D02*
X382870Y464393D01*
G01Y467160D02*
X380370D01*
X382162Y465618D01*
Y467702D01*
G01X380370Y469760D02*
X380453Y469427D01*
X380662Y469177D01*
X380912Y469010D01*
X381245Y468885D01*
X381620Y468843D01*
X381995Y468885D01*
X382328Y469010D01*
X382578Y469177D01*
X382787Y469427D01*
X382870Y469760D01*
X382787Y470093D01*
X382578Y470343D01*
X382328Y470510D01*
X381995Y470635D01*
X381620Y470677D01*
X381245Y470635D01*
X380912Y470510D01*
X380662Y470343D01*
X380453Y470093D01*
X380370Y469760D01*
G01X380787Y472068D02*
X380537Y472318D01*
X380412Y472610D01*
X380370Y472943D01*
X380453Y473360D01*
X380662Y473652D01*
X380912Y473735D01*
X381162Y473693D01*
X381370Y473527D01*
X381787Y472693D01*
X382078Y472318D01*
X382495Y472068D01*
X382870Y471985D01*
Y473735D01*
G01X388757Y451460D02*
Y453960D01*
X389798D01*
X390132Y453835D01*
X390340Y453668D01*
X390423Y453335D01*
X390340Y453002D01*
X390090Y452793D01*
X389798Y452668D01*
X388757D01*
G01X389798D02*
X390423Y451460D01*
G01X391773Y451960D02*
X392023Y451668D01*
X392357Y451502D01*
X392732Y451460D01*
X393065Y451502D01*
X393398Y451710D01*
X393607Y451960D01*
X393648Y452210D01*
X393565Y452502D01*
X393273Y452710D01*
X392982Y452793D01*
X392607D01*
G01X392982D02*
X393232Y452918D01*
X393440Y453127D01*
X393523Y453377D01*
X393440Y453627D01*
X393232Y453835D01*
X392857Y453960D01*
X392482Y453918D01*
X392107Y453752D01*
G01X395790Y451460D02*
X396082Y451502D01*
X396415Y451627D01*
X396623Y451835D01*
X396707Y452127D01*
X396623Y452418D01*
X396373Y452668D01*
X395998Y452793D01*
X395582D01*
X395332Y452877D01*
X395123Y453085D01*
X395040Y453377D01*
X395165Y453668D01*
X395457Y453877D01*
X395790Y453960D01*
X396123Y453877D01*
X396415Y453668D01*
X396540Y453377D01*
X396457Y453085D01*
X396248Y452877D01*
X395998Y452793D01*
X395582D01*
X395207Y452668D01*
X394957Y452418D01*
X394873Y452127D01*
X394957Y451835D01*
X395165Y451627D01*
X395498Y451502D01*
X395790Y451460D01*
G01X399390D02*
Y453960D01*
X397848Y452168D01*
X399932D01*
G01X388657Y455960D02*
Y458460D01*
X389698D01*
X390032Y458335D01*
X390240Y458168D01*
X390323Y457835D01*
X390240Y457502D01*
X389990Y457293D01*
X389698Y457168D01*
X388657D01*
G01X389698D02*
X390323Y455960D01*
G01X391673Y456460D02*
X391923Y456168D01*
X392257Y456002D01*
X392632Y455960D01*
X392965Y456002D01*
X393298Y456210D01*
X393507Y456460D01*
X393548Y456710D01*
X393465Y457002D01*
X393173Y457210D01*
X392882Y457293D01*
X392507D01*
G01X392882D02*
X393132Y457418D01*
X393340Y457627D01*
X393423Y457877D01*
X393340Y458127D01*
X393132Y458335D01*
X392757Y458460D01*
X392382Y458418D01*
X392007Y458252D01*
G01X395690Y455960D02*
X395982Y456002D01*
X396315Y456127D01*
X396523Y456335D01*
X396607Y456627D01*
X396523Y456918D01*
X396273Y457168D01*
X395898Y457293D01*
X395482D01*
X395232Y457377D01*
X395023Y457585D01*
X394940Y457877D01*
X395065Y458168D01*
X395357Y458377D01*
X395690Y458460D01*
X396023Y458377D01*
X396315Y458168D01*
X396440Y457877D01*
X396357Y457585D01*
X396148Y457377D01*
X395898Y457293D01*
X395482D01*
X395107Y457168D01*
X394857Y456918D01*
X394773Y456627D01*
X394857Y456335D01*
X395065Y456127D01*
X395398Y456002D01*
X395690Y455960D01*
G01X397998Y458043D02*
X398248Y458293D01*
X398540Y458418D01*
X398873Y458460D01*
X399290Y458377D01*
X399582Y458168D01*
X399665Y457918D01*
X399623Y457668D01*
X399457Y457460D01*
X398623Y457043D01*
X398248Y456752D01*
X397998Y456335D01*
X397915Y455960D01*
X399665D01*
G01X393877Y469332D02*
Y471832D01*
X394918D01*
X395252Y471707D01*
X395460Y471540D01*
X395543Y471207D01*
X395460Y470874D01*
X395210Y470665D01*
X394918Y470540D01*
X393877D01*
G01X394918D02*
X395543Y469332D01*
G01X396893Y469832D02*
X397143Y469540D01*
X397477Y469374D01*
X397852Y469332D01*
X398185Y469374D01*
X398518Y469582D01*
X398727Y469832D01*
X398768Y470082D01*
X398685Y470374D01*
X398393Y470582D01*
X398102Y470665D01*
X397727D01*
G01X398102D02*
X398352Y470790D01*
X398560Y470999D01*
X398643Y471249D01*
X398560Y471499D01*
X398352Y471707D01*
X397977Y471832D01*
X397602Y471790D01*
X397227Y471624D01*
G01X400827Y469332D02*
X400910Y469874D01*
X401035Y470332D01*
X401202Y470749D01*
X401410Y471207D01*
X401743Y471832D01*
X400077D01*
G01X403218Y471415D02*
X403468Y471665D01*
X403760Y471790D01*
X404093Y471832D01*
X404510Y471749D01*
X404802Y471540D01*
X404885Y471290D01*
X404843Y471040D01*
X404677Y470832D01*
X403843Y470415D01*
X403468Y470124D01*
X403218Y469707D01*
X403135Y469332D01*
X404885D01*
G01X391157Y462902D02*
X388657D01*
Y463943D01*
X388782Y464277D01*
X388949Y464485D01*
X389282Y464568D01*
X389615Y464485D01*
X389824Y464235D01*
X389949Y463943D01*
Y462902D01*
G01Y463943D02*
X391157Y464568D01*
G01Y467335D02*
X388657D01*
X390449Y465793D01*
Y467877D01*
G01X391157Y469935D02*
X388657D01*
X389157Y469435D01*
G01X391157D02*
Y470435D01*
G01X390115Y472243D02*
X389824Y472535D01*
X389657Y472785D01*
X389574Y473118D01*
X389657Y473410D01*
X389824Y473618D01*
X390074Y473785D01*
X390365Y473827D01*
X390615Y473785D01*
X390865Y473618D01*
X391074Y473368D01*
X391157Y473077D01*
X391074Y472743D01*
X390824Y472452D01*
X390449Y472285D01*
X390032Y472243D01*
X389490Y472327D01*
X389199Y472452D01*
X388907Y472660D01*
X388699Y472952D01*
X388657Y473243D01*
X388740Y473535D01*
X388949Y473743D01*
G01X393927Y465197D02*
Y467697D01*
X394968D01*
X395302Y467572D01*
X395510Y467405D01*
X395593Y467072D01*
X395510Y466739D01*
X395260Y466530D01*
X394968Y466405D01*
X393927D01*
G01X394968D02*
X395593Y465197D01*
G01X397068Y466239D02*
X397360Y466530D01*
X397610Y466697D01*
X397943Y466780D01*
X398235Y466697D01*
X398443Y466530D01*
X398610Y466280D01*
X398652Y465989D01*
X398610Y465739D01*
X398443Y465489D01*
X398193Y465280D01*
X397902Y465197D01*
X397568Y465280D01*
X397277Y465530D01*
X397110Y465905D01*
X397068Y466322D01*
X397152Y466864D01*
X397277Y467155D01*
X397485Y467447D01*
X397777Y467655D01*
X398068Y467697D01*
X398360Y467614D01*
X398568Y467405D01*
G01X401460Y465197D02*
Y467697D01*
X399918Y465905D01*
X402002D01*
G01X403268Y466239D02*
X403560Y466530D01*
X403810Y466697D01*
X404143Y466780D01*
X404435Y466697D01*
X404643Y466530D01*
X404810Y466280D01*
X404852Y465989D01*
X404810Y465739D01*
X404643Y465489D01*
X404393Y465280D01*
X404102Y465197D01*
X403768Y465280D01*
X403477Y465530D01*
X403310Y465905D01*
X403268Y466322D01*
X403352Y466864D01*
X403477Y467155D01*
X403685Y467447D01*
X403977Y467655D01*
X404268Y467697D01*
X404560Y467614D01*
X404768Y467405D01*
G01X367803Y454193D02*
X367678Y453943D01*
X367595Y453651D01*
Y453318D01*
X367720Y452943D01*
X367928Y452651D01*
X368178Y452443D01*
X368595Y452276D01*
X368970Y452234D01*
X369345Y452318D01*
X369595Y452443D01*
X369845Y452693D01*
X370012Y452984D01*
X370095Y453276D01*
Y453568D01*
X370012Y453859D01*
X369887Y454109D01*
X369720Y454318D01*
G01X369053Y455584D02*
X368762Y455876D01*
X368595Y456126D01*
X368512Y456459D01*
X368595Y456751D01*
X368762Y456959D01*
X369012Y457126D01*
X369303Y457168D01*
X369553Y457126D01*
X369803Y456959D01*
X370012Y456709D01*
X370095Y456418D01*
X370012Y456084D01*
X369762Y455793D01*
X369387Y455626D01*
X368970Y455584D01*
X368428Y455668D01*
X368137Y455793D01*
X367845Y456001D01*
X367637Y456293D01*
X367595Y456584D01*
X367678Y456876D01*
X367887Y457084D01*
G01X370095Y459976D02*
X367595D01*
X369387Y458434D01*
Y460518D01*
G01X368012Y461784D02*
X367762Y462034D01*
X367637Y462326D01*
X367595Y462659D01*
X367678Y463076D01*
X367887Y463368D01*
X368137Y463451D01*
X368387Y463409D01*
X368595Y463243D01*
X369012Y462409D01*
X369303Y462034D01*
X369720Y461784D01*
X370095Y461701D01*
Y463451D01*
G01X389341Y844504D02*
X389216Y844254D01*
X389133Y843962D01*
Y843629D01*
X389258Y843254D01*
X389466Y842962D01*
X389716Y842754D01*
X390133Y842587D01*
X390508Y842545D01*
X390883Y842629D01*
X391133Y842754D01*
X391383Y843004D01*
X391550Y843295D01*
X391633Y843587D01*
Y843879D01*
X391550Y844170D01*
X391425Y844420D01*
X391258Y844629D01*
G01X391633Y846687D02*
X389133D01*
X389633Y846187D01*
G01X391633D02*
Y847187D01*
G01X391258Y848870D02*
X391466Y849120D01*
X391591Y849412D01*
X391633Y849787D01*
X391550Y850162D01*
X391383Y850454D01*
X391091Y850662D01*
X390758Y850704D01*
X390425Y850620D01*
X390216Y850412D01*
X390050Y850120D01*
X390008Y849829D01*
X390050Y849537D01*
X390216Y849162D01*
X389133Y849287D01*
Y850412D01*
G01X391633Y852804D02*
X391091Y852887D01*
X390633Y853012D01*
X390216Y853179D01*
X389758Y853387D01*
X389133Y853720D01*
Y852054D01*
G01X383908Y844767D02*
X383783Y844517D01*
X383700Y844225D01*
Y843892D01*
X383825Y843517D01*
X384033Y843225D01*
X384283Y843017D01*
X384700Y842850D01*
X385075Y842808D01*
X385450Y842892D01*
X385700Y843017D01*
X385950Y843267D01*
X386117Y843558D01*
X386200Y843850D01*
Y844142D01*
X386117Y844433D01*
X385992Y844683D01*
X385825Y844892D01*
G01X386200Y846950D02*
X383700D01*
X384200Y846450D01*
G01X386200D02*
Y847450D01*
G01X385825Y849133D02*
X386033Y849383D01*
X386158Y849675D01*
X386200Y850050D01*
X386117Y850425D01*
X385950Y850717D01*
X385658Y850925D01*
X385325Y850967D01*
X384992Y850883D01*
X384783Y850675D01*
X384617Y850383D01*
X384575Y850092D01*
X384617Y849800D01*
X384783Y849425D01*
X383700Y849550D01*
Y850675D01*
G01X385158Y852358D02*
X384867Y852650D01*
X384700Y852900D01*
X384617Y853233D01*
X384700Y853525D01*
X384867Y853733D01*
X385117Y853900D01*
X385408Y853942D01*
X385658Y853900D01*
X385908Y853733D01*
X386117Y853483D01*
X386200Y853192D01*
X386117Y852858D01*
X385867Y852567D01*
X385492Y852400D01*
X385075Y852358D01*
X384533Y852442D01*
X384242Y852567D01*
X383950Y852775D01*
X383742Y853067D01*
X383700Y853358D01*
X383783Y853650D01*
X383992Y853858D01*
G01X396608Y844267D02*
X396483Y844017D01*
X396400Y843725D01*
Y843392D01*
X396525Y843017D01*
X396733Y842725D01*
X396983Y842517D01*
X397400Y842350D01*
X397775Y842308D01*
X398150Y842392D01*
X398400Y842517D01*
X398650Y842767D01*
X398817Y843058D01*
X398900Y843350D01*
Y843642D01*
X398817Y843933D01*
X398692Y844183D01*
X398525Y844392D01*
G01X398900Y846450D02*
X396400D01*
X396900Y845950D01*
G01X398900D02*
Y846950D01*
G01X398525Y848633D02*
X398733Y848883D01*
X398858Y849175D01*
X398900Y849550D01*
X398817Y849925D01*
X398650Y850217D01*
X398358Y850425D01*
X398025Y850467D01*
X397692Y850383D01*
X397483Y850175D01*
X397317Y849883D01*
X397275Y849592D01*
X397317Y849300D01*
X397483Y848925D01*
X396400Y849050D01*
Y850175D01*
G01X398900Y853150D02*
X396400D01*
X398192Y851608D01*
Y853692D01*
G01X437400Y62717D02*
X434900D01*
Y63758D01*
X435025Y64092D01*
X435192Y64300D01*
X435525Y64383D01*
X435858Y64300D01*
X436067Y64050D01*
X436192Y63758D01*
Y62717D01*
G01Y63758D02*
X437400Y64383D01*
G01Y66567D02*
X436858Y66650D01*
X436400Y66775D01*
X435983Y66942D01*
X435525Y67150D01*
X434900Y67483D01*
Y65817D01*
G01X437025Y68833D02*
X437233Y69083D01*
X437358Y69375D01*
X437400Y69750D01*
X437317Y70125D01*
X437150Y70417D01*
X436858Y70625D01*
X436525Y70667D01*
X436192Y70583D01*
X435983Y70375D01*
X435817Y70083D01*
X435775Y69792D01*
X435817Y69500D01*
X435983Y69125D01*
X434900Y69250D01*
Y70375D01*
G01X436900Y71933D02*
X437192Y72183D01*
X437358Y72517D01*
X437400Y72892D01*
X437358Y73225D01*
X437150Y73558D01*
X436900Y73767D01*
X436650Y73808D01*
X436358Y73725D01*
X436150Y73433D01*
X436067Y73142D01*
Y72767D01*
G01Y73142D02*
X435942Y73392D01*
X435733Y73600D01*
X435483Y73683D01*
X435233Y73600D01*
X435025Y73392D01*
X434900Y73017D01*
X434942Y72642D01*
X435108Y72267D01*
G01X433200Y62717D02*
X430700D01*
Y63758D01*
X430825Y64092D01*
X430992Y64300D01*
X431325Y64383D01*
X431658Y64300D01*
X431867Y64050D01*
X431992Y63758D01*
Y62717D01*
G01Y63758D02*
X433200Y64383D01*
G01Y66567D02*
X432658Y66650D01*
X432200Y66775D01*
X431783Y66942D01*
X431325Y67150D01*
X430700Y67483D01*
Y65817D01*
G01X432825Y68833D02*
X433033Y69083D01*
X433158Y69375D01*
X433200Y69750D01*
X433117Y70125D01*
X432950Y70417D01*
X432658Y70625D01*
X432325Y70667D01*
X431992Y70583D01*
X431783Y70375D01*
X431617Y70083D01*
X431575Y69792D01*
X431617Y69500D01*
X431783Y69125D01*
X430700Y69250D01*
Y70375D01*
G01Y72850D02*
X430783Y72517D01*
X430992Y72267D01*
X431242Y72100D01*
X431575Y71975D01*
X431950Y71933D01*
X432325Y71975D01*
X432658Y72100D01*
X432908Y72267D01*
X433117Y72517D01*
X433200Y72850D01*
X433117Y73183D01*
X432908Y73433D01*
X432658Y73600D01*
X432325Y73725D01*
X431950Y73767D01*
X431575Y73725D01*
X431242Y73600D01*
X430992Y73433D01*
X430783Y73183D01*
X430700Y72850D01*
G01X436867Y120917D02*
X431867Y123000D01*
X436867Y125083D01*
G01X435117Y124333D02*
Y121667D01*
G01X436867Y126433D02*
X431867D01*
X436034Y128600D01*
X431867Y130767D01*
X436867D01*
G01X434200Y134867D02*
X433950Y135200D01*
X433534Y135450D01*
X432950Y135617D01*
X432450Y135450D01*
X432117Y135117D01*
X431867Y134533D01*
Y132283D01*
X436867D01*
Y135033D01*
X436534Y135617D01*
X436034Y135950D01*
X435450Y136117D01*
X434867Y135950D01*
X434367Y135450D01*
X434200Y134867D01*
Y132283D01*
G01X431867Y138800D02*
Y140800D01*
G01Y139800D02*
X436867D01*
G01Y138800D02*
Y140800D01*
G01Y147067D02*
Y143733D01*
X431867D01*
Y147067D01*
G01X434284Y145733D02*
Y143733D01*
G01X436867Y149083D02*
X431867D01*
X436867Y152917D01*
X431867D01*
G01Y156600D02*
X436867D01*
G01X431867Y154683D02*
Y158517D01*
G01X436200Y166050D02*
X436617Y166717D01*
X436867Y167467D01*
Y168133D01*
X436617Y168800D01*
X436200Y169300D01*
X435617Y169550D01*
X435034Y169383D01*
X434534Y168967D01*
X434200Y168217D01*
X434034Y167217D01*
X433700Y166633D01*
X433117Y166383D01*
X432534Y166550D01*
X432117Y166967D01*
X431867Y167550D01*
Y168133D01*
X432034Y168717D01*
X432450Y169217D01*
G01X436867Y175067D02*
Y171733D01*
X431867D01*
Y175067D01*
G01X434284Y173733D02*
Y171733D01*
G01X436867Y177083D02*
X431867D01*
X436867Y180917D01*
X431867D01*
G01X436200Y182850D02*
X436617Y183517D01*
X436867Y184267D01*
Y184933D01*
X436617Y185600D01*
X436200Y186100D01*
X435617Y186350D01*
X435034Y186183D01*
X434534Y185767D01*
X434200Y185017D01*
X434034Y184017D01*
X433700Y183433D01*
X433117Y183183D01*
X432534Y183350D01*
X432117Y183767D01*
X431867Y184350D01*
Y184933D01*
X432034Y185517D01*
X432450Y186017D01*
G01X436867Y190200D02*
X436784Y189533D01*
X436450Y188950D01*
X435950Y188450D01*
X435367Y188117D01*
X434700Y187950D01*
X434034D01*
X433367Y188117D01*
X432784Y188450D01*
X432284Y188950D01*
X431950Y189533D01*
X431867Y190200D01*
X431950Y190867D01*
X432284Y191450D01*
X432784Y191950D01*
X433367Y192283D01*
X434034Y192450D01*
X434700D01*
X435367Y192283D01*
X435950Y191950D01*
X436450Y191450D01*
X436784Y190867D01*
X436867Y190200D01*
G01Y194133D02*
X431867D01*
Y196217D01*
X432117Y196883D01*
X432450Y197300D01*
X433117Y197467D01*
X433784Y197300D01*
X434200Y196800D01*
X434450Y196217D01*
Y194133D01*
G01Y196217D02*
X436867Y197467D01*
G01X414698Y145018D02*
X415198Y145435D01*
X415531Y145935D01*
X415698Y146518D01*
X415531Y147185D01*
X415198Y147685D01*
X414698Y148185D01*
X414031Y148352D01*
X410698D01*
G01X415698Y150618D02*
X410698D01*
Y152618D01*
X410948Y153285D01*
X411531Y153785D01*
X412198Y153952D01*
X412865Y153785D01*
X413365Y153368D01*
X413615Y152618D01*
Y150618D01*
G01X415698Y157885D02*
X410698D01*
X411698Y156885D01*
G01X415698D02*
Y158885D01*
G01X411531Y161902D02*
X411031Y162402D01*
X410781Y162985D01*
X410698Y163652D01*
X410865Y164485D01*
X411281Y165068D01*
X411781Y165235D01*
X412281Y165152D01*
X412698Y164818D01*
X413531Y163152D01*
X414115Y162402D01*
X414948Y161902D01*
X415698Y161735D01*
Y165235D01*
G01X415865Y169085D02*
X415781Y168918D01*
X415615D01*
X415531Y169085D01*
X415615Y169252D01*
X415781D01*
X415865Y169085D01*
G01X413615D02*
X413531Y168918D01*
X413365D01*
X413281Y169085D01*
X413365Y169252D01*
X413531D01*
X413615Y169085D01*
G01X415031Y178535D02*
X415448Y179202D01*
X415698Y179952D01*
Y180618D01*
X415448Y181285D01*
X415031Y181785D01*
X414448Y182035D01*
X413865Y181868D01*
X413365Y181452D01*
X413031Y180702D01*
X412865Y179702D01*
X412531Y179118D01*
X411948Y178868D01*
X411365Y179035D01*
X410948Y179452D01*
X410698Y180035D01*
Y180618D01*
X410865Y181202D01*
X411281Y181702D01*
G01X415698Y187552D02*
Y184218D01*
X410698D01*
Y187552D01*
G01X413115Y186218D02*
Y184218D01*
G01X411115Y193318D02*
X410865Y192818D01*
X410698Y192235D01*
Y191568D01*
X410948Y190818D01*
X411365Y190235D01*
X411865Y189818D01*
X412698Y189485D01*
X413448Y189402D01*
X414198Y189568D01*
X414698Y189818D01*
X415198Y190318D01*
X415531Y190902D01*
X415698Y191485D01*
Y192068D01*
X415531Y192652D01*
X415281Y193152D01*
X414948Y193568D01*
G01X410698Y195252D02*
X414281D01*
X415031Y195585D01*
X415531Y196252D01*
X415698Y197085D01*
X415531Y197918D01*
X415031Y198585D01*
X414281Y198918D01*
X410698D01*
G01X415698Y201018D02*
X410698D01*
Y203102D01*
X410948Y203768D01*
X411281Y204185D01*
X411948Y204352D01*
X412615Y204185D01*
X413031Y203685D01*
X413281Y203102D01*
Y201018D01*
G01Y203102D02*
X415698Y204352D01*
G01Y209952D02*
Y206618D01*
X410698D01*
Y209952D01*
G01X413115Y208618D02*
Y206618D01*
G01X410698Y216985D02*
X415698Y218152D01*
X410698Y219485D01*
X415698Y220818D01*
X410698Y221985D01*
G01X415698Y223418D02*
X410698D01*
Y225418D01*
X410948Y226085D01*
X411531Y226585D01*
X412198Y226752D01*
X412865Y226585D01*
X413365Y226168D01*
X413615Y225418D01*
Y223418D01*
G01X415698Y228768D02*
X410698D01*
X415698Y232602D01*
X410698D01*
G01X415698Y240052D02*
X410698D01*
Y241718D01*
X410948Y242385D01*
X411281Y242885D01*
X411781Y243302D01*
X412365Y243635D01*
X413198Y243718D01*
X414031Y243635D01*
X414615Y243302D01*
X415115Y242885D01*
X415448Y242385D01*
X415698Y241718D01*
Y240052D01*
G01X413448Y246235D02*
Y248902D01*
X412865Y248652D01*
X412531Y248235D01*
X412365Y247652D01*
X412448Y247068D01*
X412698Y246568D01*
X413281Y246235D01*
X413781Y246068D01*
X414281D01*
X414781Y246235D01*
X415281Y246652D01*
X415615Y247152D01*
X415698Y247735D01*
X415531Y248318D01*
X415031Y248902D01*
G01X415698Y252585D02*
X411448D01*
X411031Y252752D01*
X410781Y253085D01*
X410698Y253585D01*
X410865Y254085D01*
X411281Y254335D01*
G01X412698Y253335D02*
Y251668D01*
G01X415698Y260185D02*
X412365D01*
G01X412948D02*
X412615Y259852D01*
X412448Y259352D01*
X412365Y258768D01*
X412531Y258185D01*
X412865Y257685D01*
X413365Y257352D01*
X414031Y257185D01*
X414698Y257352D01*
X415198Y257685D01*
X415531Y258185D01*
X415698Y258768D01*
X415615Y259352D01*
X415365Y259852D01*
X415031Y260185D01*
G01X412365Y262868D02*
X414698D01*
X415281Y263202D01*
X415615Y263702D01*
X415698Y264285D01*
X415615Y264868D01*
X415281Y265368D01*
X414698Y265702D01*
G01X415698D02*
X412365D01*
G01X415698Y269885D02*
X410698D01*
G01Y275485D02*
X415698D01*
G01X412365Y274318D02*
Y276652D01*
G01X415698Y286685D02*
X410698D01*
X411698Y285685D01*
G01X415698D02*
Y287685D01*
G01X414031Y291202D02*
Y293368D01*
G01X411531Y296302D02*
X411031Y296802D01*
X410781Y297385D01*
X410698Y298052D01*
X410865Y298885D01*
X411281Y299468D01*
X411781Y299635D01*
X412281Y299552D01*
X412698Y299218D01*
X413531Y297552D01*
X414115Y296802D01*
X414948Y296302D01*
X415698Y296135D01*
Y299635D01*
G01X422598Y145118D02*
X423098Y145535D01*
X423431Y146035D01*
X423598Y146618D01*
X423431Y147285D01*
X423098Y147785D01*
X422598Y148285D01*
X421931Y148452D01*
X418598D01*
G01X423598Y150718D02*
X418598D01*
Y152718D01*
X418848Y153385D01*
X419431Y153885D01*
X420098Y154052D01*
X420765Y153885D01*
X421265Y153468D01*
X421515Y152718D01*
Y150718D01*
G01X423598Y157985D02*
X418598D01*
X419598Y156985D01*
G01X423598D02*
Y158985D01*
G01X422598Y161752D02*
X423181Y162252D01*
X423515Y162918D01*
X423598Y163668D01*
X423515Y164335D01*
X423098Y165002D01*
X422598Y165418D01*
X422098Y165502D01*
X421515Y165335D01*
X421098Y164752D01*
X420931Y164168D01*
Y163418D01*
G01Y164168D02*
X420681Y164668D01*
X420265Y165085D01*
X419765Y165252D01*
X419265Y165085D01*
X418848Y164668D01*
X418598Y163918D01*
X418681Y163168D01*
X419015Y162418D01*
G01X423765Y169185D02*
X423681Y169018D01*
X423515D01*
X423431Y169185D01*
X423515Y169352D01*
X423681D01*
X423765Y169185D01*
G01X421515D02*
X421431Y169018D01*
X421265D01*
X421181Y169185D01*
X421265Y169352D01*
X421431D01*
X421515Y169185D01*
G01X422931Y178635D02*
X423348Y179302D01*
X423598Y180052D01*
Y180718D01*
X423348Y181385D01*
X422931Y181885D01*
X422348Y182135D01*
X421765Y181968D01*
X421265Y181552D01*
X420931Y180802D01*
X420765Y179802D01*
X420431Y179218D01*
X419848Y178968D01*
X419265Y179135D01*
X418848Y179552D01*
X418598Y180135D01*
Y180718D01*
X418765Y181302D01*
X419181Y181802D01*
G01X423598Y187652D02*
Y184318D01*
X418598D01*
Y187652D01*
G01X421015Y186318D02*
Y184318D01*
G01X419015Y193418D02*
X418765Y192918D01*
X418598Y192335D01*
Y191668D01*
X418848Y190918D01*
X419265Y190335D01*
X419765Y189918D01*
X420598Y189585D01*
X421348Y189502D01*
X422098Y189668D01*
X422598Y189918D01*
X423098Y190418D01*
X423431Y191002D01*
X423598Y191585D01*
Y192168D01*
X423431Y192752D01*
X423181Y193252D01*
X422848Y193668D01*
G01X418598Y195352D02*
X422181D01*
X422931Y195685D01*
X423431Y196352D01*
X423598Y197185D01*
X423431Y198018D01*
X422931Y198685D01*
X422181Y199018D01*
X418598D01*
G01X423598Y201118D02*
X418598D01*
Y203202D01*
X418848Y203868D01*
X419181Y204285D01*
X419848Y204452D01*
X420515Y204285D01*
X420931Y203785D01*
X421181Y203202D01*
Y201118D01*
G01Y203202D02*
X423598Y204452D01*
G01Y210052D02*
Y206718D01*
X418598D01*
Y210052D01*
G01X421015Y208718D02*
Y206718D01*
G01X419015Y221418D02*
X418765Y220918D01*
X418598Y220335D01*
Y219668D01*
X418848Y218918D01*
X419265Y218335D01*
X419765Y217918D01*
X420598Y217585D01*
X421348Y217502D01*
X422098Y217668D01*
X422598Y217918D01*
X423098Y218418D01*
X423431Y219002D01*
X423598Y219585D01*
Y220168D01*
X423431Y220752D01*
X423181Y221252D01*
X422848Y221668D01*
G01X422931Y223435D02*
X423348Y224102D01*
X423598Y224852D01*
Y225518D01*
X423348Y226185D01*
X422931Y226685D01*
X422348Y226935D01*
X421765Y226768D01*
X421265Y226352D01*
X420931Y225602D01*
X420765Y224602D01*
X420431Y224018D01*
X419848Y223768D01*
X419265Y223935D01*
X418848Y224352D01*
X418598Y224935D01*
Y225518D01*
X418765Y226102D01*
X419181Y226602D01*
G01X423598Y234552D02*
X418598D01*
Y236218D01*
X418848Y236885D01*
X419181Y237385D01*
X419681Y237802D01*
X420265Y238135D01*
X421098Y238218D01*
X421931Y238135D01*
X422515Y237802D01*
X423015Y237385D01*
X423348Y236885D01*
X423598Y236218D01*
Y234552D01*
G01X421348Y240735D02*
Y243402D01*
X420765Y243152D01*
X420431Y242735D01*
X420265Y242152D01*
X420348Y241568D01*
X420598Y241068D01*
X421181Y240735D01*
X421681Y240568D01*
X422181D01*
X422681Y240735D01*
X423181Y241152D01*
X423515Y241652D01*
X423598Y242235D01*
X423431Y242818D01*
X422931Y243402D01*
G01X423598Y247085D02*
X419348D01*
X418931Y247252D01*
X418681Y247585D01*
X418598Y248085D01*
X418765Y248585D01*
X419181Y248835D01*
G01X420598Y247835D02*
Y246168D01*
G01X423598Y254685D02*
X420265D01*
G01X420848D02*
X420515Y254352D01*
X420348Y253852D01*
X420265Y253268D01*
X420431Y252685D01*
X420765Y252185D01*
X421265Y251852D01*
X421931Y251685D01*
X422598Y251852D01*
X423098Y252185D01*
X423431Y252685D01*
X423598Y253268D01*
X423515Y253852D01*
X423265Y254352D01*
X422931Y254685D01*
G01X420265Y257368D02*
X422598D01*
X423181Y257702D01*
X423515Y258202D01*
X423598Y258785D01*
X423515Y259368D01*
X423181Y259868D01*
X422598Y260202D01*
G01X423598D02*
X420265D01*
G01X423598Y264385D02*
X418598D01*
G01Y269985D02*
X423598D01*
G01X420265Y268818D02*
Y271152D01*
G01X423598Y281185D02*
X418598D01*
X419598Y280185D01*
G01X423598D02*
Y282185D01*
G01X421931Y285702D02*
Y287868D01*
G01X419431Y290802D02*
X418931Y291302D01*
X418681Y291885D01*
X418598Y292552D01*
X418765Y293385D01*
X419181Y293968D01*
X419681Y294135D01*
X420181Y294052D01*
X420598Y293718D01*
X421431Y292052D01*
X422015Y291302D01*
X422848Y290802D01*
X423598Y290635D01*
Y294135D01*
G01X407098Y145218D02*
X407598Y145635D01*
X407931Y146135D01*
X408098Y146718D01*
X407931Y147385D01*
X407598Y147885D01*
X407098Y148385D01*
X406431Y148552D01*
X403098D01*
G01X408098Y150818D02*
X403098D01*
Y152818D01*
X403348Y153485D01*
X403931Y153985D01*
X404598Y154152D01*
X405265Y153985D01*
X405765Y153568D01*
X406015Y152818D01*
Y150818D01*
G01X408098Y158085D02*
X403098D01*
X404098Y157085D01*
G01X408098D02*
Y159085D01*
G01X403098Y163685D02*
X403265Y163018D01*
X403681Y162518D01*
X404181Y162185D01*
X404848Y161935D01*
X405598Y161852D01*
X406348Y161935D01*
X407015Y162185D01*
X407515Y162518D01*
X407931Y163018D01*
X408098Y163685D01*
X407931Y164352D01*
X407515Y164852D01*
X407015Y165185D01*
X406348Y165435D01*
X405598Y165518D01*
X404848Y165435D01*
X404181Y165185D01*
X403681Y164852D01*
X403265Y164352D01*
X403098Y163685D01*
G01X408265Y169285D02*
X408181Y169118D01*
X408015D01*
X407931Y169285D01*
X408015Y169452D01*
X408181D01*
X408265Y169285D01*
G01X406015D02*
X405931Y169118D01*
X405765D01*
X405681Y169285D01*
X405765Y169452D01*
X405931D01*
X406015Y169285D01*
G01X407431Y173135D02*
X407848Y173802D01*
X408098Y174552D01*
Y175218D01*
X407848Y175885D01*
X407431Y176385D01*
X406848Y176635D01*
X406265Y176468D01*
X405765Y176052D01*
X405431Y175302D01*
X405265Y174302D01*
X404931Y173718D01*
X404348Y173468D01*
X403765Y173635D01*
X403348Y174052D01*
X403098Y174635D01*
Y175218D01*
X403265Y175802D01*
X403681Y176302D01*
G01X403098Y177985D02*
X408098Y179152D01*
X403098Y180485D01*
X408098Y181818D01*
X403098Y182985D01*
G01Y185085D02*
Y187085D01*
G01Y186085D02*
X408098D01*
G01Y185085D02*
Y187085D01*
G01X403098Y191685D02*
X408098D01*
G01X403098Y189768D02*
Y193602D01*
G01X403515Y199118D02*
X403265Y198618D01*
X403098Y198035D01*
Y197368D01*
X403348Y196618D01*
X403765Y196035D01*
X404265Y195618D01*
X405098Y195285D01*
X405848Y195202D01*
X406598Y195368D01*
X407098Y195618D01*
X407598Y196118D01*
X407931Y196702D01*
X408098Y197285D01*
Y197868D01*
X407931Y198452D01*
X407681Y198952D01*
X407348Y199368D01*
G01X408098Y201135D02*
X403098D01*
G01Y204635D02*
X408098D01*
G01X405598D02*
Y201135D01*
G01X408098Y212418D02*
X403098D01*
Y214502D01*
X403348Y215168D01*
X403681Y215585D01*
X404348Y215752D01*
X405015Y215585D01*
X405431Y215085D01*
X405681Y214502D01*
Y212418D01*
G01Y214502D02*
X408098Y215752D01*
G01Y221352D02*
Y218018D01*
X403098D01*
Y221352D01*
G01X405515Y220018D02*
Y218018D01*
G01X403515Y227118D02*
X403265Y226618D01*
X403098Y226035D01*
Y225368D01*
X403348Y224618D01*
X403765Y224035D01*
X404265Y223618D01*
X405098Y223285D01*
X405848Y223202D01*
X406598Y223368D01*
X407098Y223618D01*
X407598Y224118D01*
X407931Y224702D01*
X408098Y225285D01*
Y225868D01*
X407931Y226452D01*
X407681Y226952D01*
X407348Y227368D01*
G01X408098Y230885D02*
X408015Y230218D01*
X407681Y229635D01*
X407181Y229135D01*
X406598Y228802D01*
X405931Y228635D01*
X405265D01*
X404598Y228802D01*
X404015Y229135D01*
X403515Y229635D01*
X403181Y230218D01*
X403098Y230885D01*
X403181Y231552D01*
X403515Y232135D01*
X404015Y232635D01*
X404598Y232968D01*
X405265Y233135D01*
X405931D01*
X406598Y232968D01*
X407181Y232635D01*
X407681Y232135D01*
X408015Y231552D01*
X408098Y230885D01*
G01X403098Y234402D02*
X408098Y236485D01*
X403098Y238568D01*
G01X408098Y243752D02*
Y240418D01*
X403098D01*
Y243752D01*
G01X405515Y242418D02*
Y240418D01*
G01X408098Y246018D02*
X403098D01*
Y248102D01*
X403348Y248768D01*
X403681Y249185D01*
X404348Y249352D01*
X405015Y249185D01*
X405431Y248685D01*
X405681Y248102D01*
Y246018D01*
G01Y248102D02*
X408098Y249352D01*
G01Y257052D02*
X403098D01*
Y258718D01*
X403348Y259385D01*
X403681Y259885D01*
X404181Y260302D01*
X404765Y260635D01*
X405598Y260718D01*
X406431Y260635D01*
X407015Y260302D01*
X407515Y259885D01*
X407848Y259385D01*
X408098Y258718D01*
Y257052D01*
G01Y266152D02*
Y262818D01*
X403098D01*
Y266152D01*
G01X405515Y264818D02*
Y262818D01*
G01X408098Y268502D02*
X403098D01*
Y271668D01*
G01X405515Y270502D02*
Y268502D01*
G01X408098Y273602D02*
X403098Y275685D01*
X408098Y277768D01*
G01X406348Y277018D02*
Y274352D01*
G01X403098Y279452D02*
X406681D01*
X407431Y279785D01*
X407931Y280452D01*
X408098Y281285D01*
X407931Y282118D01*
X407431Y282785D01*
X406681Y283118D01*
X403098D01*
G01Y285218D02*
X408098D01*
Y288552D01*
G01X403098Y292485D02*
X408098D01*
G01X403098Y290568D02*
Y294402D01*
G01X408098Y303685D02*
X403098D01*
X404098Y302685D01*
G01X408098D02*
Y304685D01*
G01X406431Y308202D02*
Y310368D01*
G01X403931Y313302D02*
X403431Y313802D01*
X403181Y314385D01*
X403098Y315052D01*
X403265Y315885D01*
X403681Y316468D01*
X404181Y316635D01*
X404681Y316552D01*
X405098Y316218D01*
X405931Y314552D01*
X406515Y313802D01*
X407348Y313302D01*
X408098Y313135D01*
Y316635D01*
G01X406840Y409277D02*
X404340D01*
Y410318D01*
X404465Y410652D01*
X404632Y410860D01*
X404965Y410943D01*
X405298Y410860D01*
X405507Y410610D01*
X405632Y410318D01*
Y409277D01*
G01Y410318D02*
X406840Y410943D01*
G01X406340Y412293D02*
X406632Y412543D01*
X406798Y412877D01*
X406840Y413252D01*
X406798Y413585D01*
X406590Y413918D01*
X406340Y414127D01*
X406090Y414168D01*
X405798Y414085D01*
X405590Y413793D01*
X405507Y413502D01*
Y413127D01*
G01Y413502D02*
X405382Y413752D01*
X405173Y413960D01*
X404923Y414043D01*
X404673Y413960D01*
X404465Y413752D01*
X404340Y413377D01*
X404382Y413002D01*
X404548Y412627D01*
G01X406548Y415602D02*
X406757Y415893D01*
X406840Y416227D01*
X406757Y416560D01*
X406507Y416852D01*
X406132Y417060D01*
X405757Y417143D01*
X405298D01*
X404923Y417060D01*
X404590Y416852D01*
X404423Y416602D01*
X404340Y416310D01*
X404423Y415977D01*
X404590Y415727D01*
X404840Y415560D01*
X405173Y415477D01*
X405465Y415560D01*
X405757Y415768D01*
X405923Y416018D01*
X405965Y416310D01*
X405882Y416643D01*
X405673Y416893D01*
X405298Y417143D01*
G01X406465Y418493D02*
X406673Y418743D01*
X406798Y419035D01*
X406840Y419410D01*
X406757Y419785D01*
X406590Y420077D01*
X406298Y420285D01*
X405965Y420327D01*
X405632Y420243D01*
X405423Y420035D01*
X405257Y419743D01*
X405215Y419452D01*
X405257Y419160D01*
X405423Y418785D01*
X404340Y418910D01*
Y420035D01*
G01X406673Y422377D02*
X404173D01*
Y423418D01*
X404298Y423752D01*
X404465Y423960D01*
X404798Y424043D01*
X405131Y423960D01*
X405340Y423710D01*
X405465Y423418D01*
Y422377D01*
G01Y423418D02*
X406673Y424043D01*
G01X406173Y425393D02*
X406465Y425643D01*
X406631Y425977D01*
X406673Y426352D01*
X406631Y426685D01*
X406423Y427018D01*
X406173Y427227D01*
X405923Y427268D01*
X405631Y427185D01*
X405423Y426893D01*
X405340Y426602D01*
Y426227D01*
G01Y426602D02*
X405215Y426852D01*
X405006Y427060D01*
X404756Y427143D01*
X404506Y427060D01*
X404298Y426852D01*
X404173Y426477D01*
X404215Y426102D01*
X404381Y425727D01*
G01X406381Y428702D02*
X406590Y428993D01*
X406673Y429327D01*
X406590Y429660D01*
X406340Y429952D01*
X405965Y430160D01*
X405590Y430243D01*
X405131D01*
X404756Y430160D01*
X404423Y429952D01*
X404256Y429702D01*
X404173Y429410D01*
X404256Y429077D01*
X404423Y428827D01*
X404673Y428660D01*
X405006Y428577D01*
X405298Y428660D01*
X405590Y428868D01*
X405756Y429118D01*
X405798Y429410D01*
X405715Y429743D01*
X405506Y429993D01*
X405131Y430243D01*
G01X406673Y433010D02*
X404173D01*
X405965Y431468D01*
Y433552D01*
G01X420382Y454821D02*
Y462821D01*
X424816D01*
G01X423182Y458954D02*
X420382D01*
G01X414600Y522600D02*
X493200D01*
Y478800D01*
X414600D01*
Y522600D01*
G01X416000Y475000D02*
X538300D01*
Y445400D01*
X414400D01*
Y475000D01*
X416000D01*
G01X418116Y469787D02*
Y472287D01*
X419157D01*
X419491Y472162D01*
X419699Y471995D01*
X419782Y471662D01*
X419699Y471329D01*
X419449Y471120D01*
X419157Y470995D01*
X418116D01*
G01X419157D02*
X419782Y469787D01*
G01X421257Y470829D02*
X421549Y471120D01*
X421799Y471287D01*
X422132Y471370D01*
X422424Y471287D01*
X422632Y471120D01*
X422799Y470870D01*
X422841Y470579D01*
X422799Y470329D01*
X422632Y470079D01*
X422382Y469870D01*
X422091Y469787D01*
X421757Y469870D01*
X421466Y470120D01*
X421299Y470495D01*
X421257Y470912D01*
X421341Y471454D01*
X421466Y471745D01*
X421674Y472037D01*
X421966Y472245D01*
X422257Y472287D01*
X422549Y472204D01*
X422757Y471995D01*
G01X424357Y470829D02*
X424649Y471120D01*
X424899Y471287D01*
X425232Y471370D01*
X425524Y471287D01*
X425732Y471120D01*
X425899Y470870D01*
X425941Y470579D01*
X425899Y470329D01*
X425732Y470079D01*
X425482Y469870D01*
X425191Y469787D01*
X424857Y469870D01*
X424566Y470120D01*
X424399Y470495D01*
X424357Y470912D01*
X424441Y471454D01*
X424566Y471745D01*
X424774Y472037D01*
X425066Y472245D01*
X425357Y472287D01*
X425649Y472204D01*
X425857Y471995D01*
G01X428166Y469787D02*
X428249Y470329D01*
X428374Y470787D01*
X428541Y471204D01*
X428749Y471662D01*
X429082Y472287D01*
X427416D01*
G01X434347Y454338D02*
X431847D01*
Y455379D01*
X431972Y455713D01*
X432139Y455921D01*
X432472Y456004D01*
X432805Y455921D01*
X433014Y455671D01*
X433139Y455379D01*
Y454338D01*
G01Y455379D02*
X434347Y456004D01*
G01X432264Y457479D02*
X432014Y457729D01*
X431889Y458021D01*
X431847Y458354D01*
X431930Y458771D01*
X432139Y459063D01*
X432389Y459146D01*
X432639Y459104D01*
X432847Y458938D01*
X433264Y458104D01*
X433555Y457729D01*
X433972Y457479D01*
X434347Y457396D01*
Y459146D01*
G01X434055Y460663D02*
X434264Y460954D01*
X434347Y461288D01*
X434264Y461621D01*
X434014Y461913D01*
X433639Y462121D01*
X433264Y462204D01*
X432805D01*
X432430Y462121D01*
X432097Y461913D01*
X431930Y461663D01*
X431847Y461371D01*
X431930Y461038D01*
X432097Y460788D01*
X432347Y460621D01*
X432680Y460538D01*
X432972Y460621D01*
X433264Y460829D01*
X433430Y461079D01*
X433472Y461371D01*
X433389Y461704D01*
X433180Y461954D01*
X432805Y462204D01*
G01X433847Y463554D02*
X434139Y463804D01*
X434305Y464138D01*
X434347Y464513D01*
X434305Y464846D01*
X434097Y465179D01*
X433847Y465388D01*
X433597Y465429D01*
X433305Y465346D01*
X433097Y465054D01*
X433014Y464763D01*
Y464388D01*
G01Y464763D02*
X432889Y465013D01*
X432680Y465221D01*
X432430Y465304D01*
X432180Y465221D01*
X431972Y465013D01*
X431847Y464638D01*
X431889Y464263D01*
X432055Y463888D01*
G01X433847Y466654D02*
X434139Y466904D01*
X434305Y467238D01*
X434347Y467613D01*
X434305Y467946D01*
X434097Y468279D01*
X433847Y468488D01*
X433597Y468529D01*
X433305Y468446D01*
X433097Y468154D01*
X433014Y467863D01*
Y467488D01*
G01Y467863D02*
X432889Y468113D01*
X432680Y468321D01*
X432430Y468404D01*
X432180Y468321D01*
X431972Y468113D01*
X431847Y467738D01*
X431889Y467363D01*
X432055Y466988D01*
G01X430337Y454338D02*
X427837D01*
Y455379D01*
X427962Y455713D01*
X428129Y455921D01*
X428462Y456004D01*
X428795Y455921D01*
X429004Y455671D01*
X429129Y455379D01*
Y454338D01*
G01Y455379D02*
X430337Y456004D01*
G01X428254Y457479D02*
X428004Y457729D01*
X427879Y458021D01*
X427837Y458354D01*
X427920Y458771D01*
X428129Y459063D01*
X428379Y459146D01*
X428629Y459104D01*
X428837Y458938D01*
X429254Y458104D01*
X429545Y457729D01*
X429962Y457479D01*
X430337Y457396D01*
Y459146D01*
G01X430045Y460663D02*
X430254Y460954D01*
X430337Y461288D01*
X430254Y461621D01*
X430004Y461913D01*
X429629Y462121D01*
X429254Y462204D01*
X428795D01*
X428420Y462121D01*
X428087Y461913D01*
X427920Y461663D01*
X427837Y461371D01*
X427920Y461038D01*
X428087Y460788D01*
X428337Y460621D01*
X428670Y460538D01*
X428962Y460621D01*
X429254Y460829D01*
X429420Y461079D01*
X429462Y461371D01*
X429379Y461704D01*
X429170Y461954D01*
X428795Y462204D01*
G01X429837Y463554D02*
X430129Y463804D01*
X430295Y464138D01*
X430337Y464513D01*
X430295Y464846D01*
X430087Y465179D01*
X429837Y465388D01*
X429587Y465429D01*
X429295Y465346D01*
X429087Y465054D01*
X429004Y464763D01*
Y464388D01*
G01Y464763D02*
X428879Y465013D01*
X428670Y465221D01*
X428420Y465304D01*
X428170Y465221D01*
X427962Y465013D01*
X427837Y464638D01*
X427879Y464263D01*
X428045Y463888D01*
G01X430337Y468071D02*
X427837D01*
X429629Y466529D01*
Y468613D01*
G01X432600Y516700D02*
X434933D01*
Y514300D01*
X434233Y513500D01*
X433417Y512967D01*
X432250Y512700D01*
X431083Y512967D01*
X430267Y513500D01*
X429567Y514300D01*
X429100Y515233D01*
X428867Y516300D01*
Y517233D01*
X429100Y518033D01*
X429567Y518967D01*
X430267Y519767D01*
X430967Y520300D01*
X431900Y520700D01*
X432717D01*
X433650Y520433D01*
X434350Y519900D01*
G01X427650Y492317D02*
X425150D01*
Y493358D01*
X425275Y493692D01*
X425442Y493900D01*
X425775Y493983D01*
X426108Y493900D01*
X426317Y493650D01*
X426442Y493358D01*
Y492317D01*
G01Y493358D02*
X427650Y493983D01*
G01X427275Y495333D02*
X427483Y495583D01*
X427608Y495875D01*
X427650Y496250D01*
X427567Y496625D01*
X427400Y496917D01*
X427108Y497125D01*
X426775Y497167D01*
X426442Y497083D01*
X426233Y496875D01*
X426067Y496583D01*
X426025Y496292D01*
X426067Y496000D01*
X426233Y495625D01*
X425150Y495750D01*
Y496875D01*
G01X427358Y498642D02*
X427567Y498933D01*
X427650Y499267D01*
X427567Y499600D01*
X427317Y499892D01*
X426942Y500100D01*
X426567Y500183D01*
X426108D01*
X425733Y500100D01*
X425400Y499892D01*
X425233Y499642D01*
X425150Y499350D01*
X425233Y499017D01*
X425400Y498767D01*
X425650Y498600D01*
X425983Y498517D01*
X426275Y498600D01*
X426567Y498808D01*
X426733Y499058D01*
X426775Y499350D01*
X426692Y499683D01*
X426483Y499933D01*
X426108Y500183D01*
G01X427650Y502367D02*
X427108Y502450D01*
X426650Y502575D01*
X426233Y502742D01*
X425775Y502950D01*
X425150Y503283D01*
Y501617D01*
G01X431650Y492317D02*
X429150D01*
Y493358D01*
X429275Y493692D01*
X429442Y493900D01*
X429775Y493983D01*
X430108Y493900D01*
X430317Y493650D01*
X430442Y493358D01*
Y492317D01*
G01Y493358D02*
X431650Y493983D01*
G01X431275Y495333D02*
X431483Y495583D01*
X431608Y495875D01*
X431650Y496250D01*
X431567Y496625D01*
X431400Y496917D01*
X431108Y497125D01*
X430775Y497167D01*
X430442Y497083D01*
X430233Y496875D01*
X430067Y496583D01*
X430025Y496292D01*
X430067Y496000D01*
X430233Y495625D01*
X429150Y495750D01*
Y496875D01*
G01X431358Y498642D02*
X431567Y498933D01*
X431650Y499267D01*
X431567Y499600D01*
X431317Y499892D01*
X430942Y500100D01*
X430567Y500183D01*
X430108D01*
X429733Y500100D01*
X429400Y499892D01*
X429233Y499642D01*
X429150Y499350D01*
X429233Y499017D01*
X429400Y498767D01*
X429650Y498600D01*
X429983Y498517D01*
X430275Y498600D01*
X430567Y498808D01*
X430733Y499058D01*
X430775Y499350D01*
X430692Y499683D01*
X430483Y499933D01*
X430108Y500183D01*
G01X431275Y501533D02*
X431483Y501783D01*
X431608Y502075D01*
X431650Y502450D01*
X431567Y502825D01*
X431400Y503117D01*
X431108Y503325D01*
X430775Y503367D01*
X430442Y503283D01*
X430233Y503075D01*
X430067Y502783D01*
X430025Y502492D01*
X430067Y502200D01*
X430233Y501825D01*
X429150Y501950D01*
Y503075D01*
G01X419583Y488400D02*
Y490900D01*
X420417D01*
X420750Y490775D01*
X421000Y490608D01*
X421208Y490358D01*
X421375Y490067D01*
X421417Y489650D01*
X421375Y489233D01*
X421208Y488942D01*
X421000Y488692D01*
X420750Y488525D01*
X420417Y488400D01*
X419583D01*
G01X423600D02*
Y490900D01*
X423100Y490400D01*
G01Y488400D02*
X424100D01*
G01X426700D02*
Y490900D01*
X426200Y490400D01*
G01Y488400D02*
X427200D01*
G01X429783Y488100D02*
Y490600D01*
X430617D01*
X430950Y490475D01*
X431200Y490308D01*
X431408Y490058D01*
X431575Y489767D01*
X431617Y489350D01*
X431575Y488933D01*
X431408Y488642D01*
X431200Y488392D01*
X430950Y488225D01*
X430617Y488100D01*
X429783D01*
G01X433800D02*
Y490600D01*
X433300Y490100D01*
G01Y488100D02*
X434300D01*
G01X437400D02*
Y490600D01*
X435858Y488808D01*
X437942D01*
G01X401939Y844504D02*
X401814Y844254D01*
X401731Y843962D01*
Y843629D01*
X401856Y843254D01*
X402064Y842962D01*
X402314Y842754D01*
X402731Y842587D01*
X403106Y842545D01*
X403481Y842629D01*
X403731Y842754D01*
X403981Y843004D01*
X404148Y843295D01*
X404231Y843587D01*
Y843879D01*
X404148Y844170D01*
X404023Y844420D01*
X403856Y844629D01*
G01X404231Y846687D02*
X401731D01*
X402231Y846187D01*
G01X404231D02*
Y847187D01*
G01X403856Y848870D02*
X404064Y849120D01*
X404189Y849412D01*
X404231Y849787D01*
X404148Y850162D01*
X403981Y850454D01*
X403689Y850662D01*
X403356Y850704D01*
X403023Y850620D01*
X402814Y850412D01*
X402648Y850120D01*
X402606Y849829D01*
X402648Y849537D01*
X402814Y849162D01*
X401731Y849287D01*
Y850412D01*
G01Y852887D02*
X401814Y852554D01*
X402023Y852304D01*
X402273Y852137D01*
X402606Y852012D01*
X402981Y851970D01*
X403356Y852012D01*
X403689Y852137D01*
X403939Y852304D01*
X404148Y852554D01*
X404231Y852887D01*
X404148Y853220D01*
X403939Y853470D01*
X403689Y853637D01*
X403356Y853762D01*
X402981Y853804D01*
X402606Y853762D01*
X402273Y853637D01*
X402023Y853470D01*
X401814Y853220D01*
X401731Y852887D01*
G01X409208Y844367D02*
X409083Y844117D01*
X409000Y843825D01*
Y843492D01*
X409125Y843117D01*
X409333Y842825D01*
X409583Y842617D01*
X410000Y842450D01*
X410375Y842408D01*
X410750Y842492D01*
X411000Y842617D01*
X411250Y842867D01*
X411417Y843158D01*
X411500Y843450D01*
Y843742D01*
X411417Y844033D01*
X411292Y844283D01*
X411125Y844492D01*
G01X411500Y846550D02*
X409000D01*
X409500Y846050D01*
G01X411500D02*
Y847050D01*
G01Y850150D02*
X409000D01*
X410792Y848608D01*
Y850692D01*
G01X411208Y852042D02*
X411417Y852333D01*
X411500Y852667D01*
X411417Y853000D01*
X411167Y853292D01*
X410792Y853500D01*
X410417Y853583D01*
X409958D01*
X409583Y853500D01*
X409250Y853292D01*
X409083Y853042D01*
X409000Y852750D01*
X409083Y852417D01*
X409250Y852167D01*
X409500Y852000D01*
X409833Y851917D01*
X410125Y852000D01*
X410417Y852208D01*
X410583Y852458D01*
X410625Y852750D01*
X410542Y853083D01*
X410333Y853333D01*
X409958Y853583D01*
G01X414538Y844504D02*
X414413Y844254D01*
X414330Y843962D01*
Y843629D01*
X414455Y843254D01*
X414663Y842962D01*
X414913Y842754D01*
X415330Y842587D01*
X415705Y842545D01*
X416080Y842629D01*
X416330Y842754D01*
X416580Y843004D01*
X416747Y843295D01*
X416830Y843587D01*
Y843879D01*
X416747Y844170D01*
X416622Y844420D01*
X416455Y844629D01*
G01X416830Y846687D02*
X414330D01*
X414830Y846187D01*
G01X416830D02*
Y847187D01*
G01Y850287D02*
X414330D01*
X416122Y848745D01*
Y850829D01*
G01X416830Y852887D02*
X416788Y853179D01*
X416663Y853512D01*
X416455Y853720D01*
X416163Y853804D01*
X415872Y853720D01*
X415622Y853470D01*
X415497Y853095D01*
Y852679D01*
X415413Y852429D01*
X415205Y852220D01*
X414913Y852137D01*
X414622Y852262D01*
X414413Y852554D01*
X414330Y852887D01*
X414413Y853220D01*
X414622Y853512D01*
X414913Y853637D01*
X415205Y853554D01*
X415413Y853345D01*
X415497Y853095D01*
Y852679D01*
X415622Y852304D01*
X415872Y852054D01*
X416163Y851970D01*
X416455Y852054D01*
X416663Y852262D01*
X416788Y852595D01*
X416830Y852887D01*
G01X420908Y844667D02*
X420783Y844417D01*
X420700Y844125D01*
Y843792D01*
X420825Y843417D01*
X421033Y843125D01*
X421283Y842917D01*
X421700Y842750D01*
X422075Y842708D01*
X422450Y842792D01*
X422700Y842917D01*
X422950Y843167D01*
X423117Y843458D01*
X423200Y843750D01*
Y844042D01*
X423117Y844333D01*
X422992Y844583D01*
X422825Y844792D01*
G01X423200Y846850D02*
X420700D01*
X421200Y846350D01*
G01X423200D02*
Y847350D01*
G01Y850450D02*
X420700D01*
X422492Y848908D01*
Y850992D01*
G01X423200Y852967D02*
X422658Y853050D01*
X422200Y853175D01*
X421783Y853342D01*
X421325Y853550D01*
X420700Y853883D01*
Y852217D01*
G01X427136Y844504D02*
X427011Y844254D01*
X426928Y843962D01*
Y843629D01*
X427053Y843254D01*
X427261Y842962D01*
X427511Y842754D01*
X427928Y842587D01*
X428303Y842545D01*
X428678Y842629D01*
X428928Y842754D01*
X429178Y843004D01*
X429345Y843295D01*
X429428Y843587D01*
Y843879D01*
X429345Y844170D01*
X429220Y844420D01*
X429053Y844629D01*
G01X429428Y846687D02*
X426928D01*
X427428Y846187D01*
G01X429428D02*
Y847187D01*
G01Y850287D02*
X426928D01*
X428720Y848745D01*
Y850829D01*
G01X429428Y853387D02*
X426928D01*
X428720Y851845D01*
Y853929D01*
G01X464925Y25500D02*
X465258Y25292D01*
X465633Y25167D01*
X465967D01*
X466300Y25292D01*
X466550Y25500D01*
X466675Y25792D01*
X466592Y26084D01*
X466383Y26334D01*
X466008Y26500D01*
X465508Y26584D01*
X465217Y26750D01*
X465092Y27042D01*
X465175Y27334D01*
X465383Y27542D01*
X465675Y27667D01*
X465967D01*
X466258Y27584D01*
X466508Y27375D01*
G01X468067Y25167D02*
Y27667D01*
X469108D01*
X469442Y27542D01*
X469650Y27375D01*
X469733Y27042D01*
X469650Y26709D01*
X469400Y26500D01*
X469108Y26375D01*
X468067D01*
G01X469108D02*
X469733Y25167D01*
G01X471917D02*
X472000Y25709D01*
X472125Y26167D01*
X472292Y26584D01*
X472500Y27042D01*
X472833Y27667D01*
X471167D01*
G01X475100Y25167D02*
Y27667D01*
X474600Y27167D01*
G01Y25167D02*
X475600D01*
G01X478200Y27667D02*
X477867Y27584D01*
X477617Y27375D01*
X477450Y27125D01*
X477325Y26792D01*
X477283Y26417D01*
X477325Y26042D01*
X477450Y25709D01*
X477617Y25459D01*
X477867Y25250D01*
X478200Y25167D01*
X478533Y25250D01*
X478783Y25459D01*
X478950Y25709D01*
X479075Y26042D01*
X479117Y26417D01*
X479075Y26792D01*
X478950Y27125D01*
X478783Y27375D01*
X478533Y27584D01*
X478200Y27667D01*
G01X464925Y49000D02*
X465258Y48792D01*
X465633Y48667D01*
X465967D01*
X466300Y48792D01*
X466550Y49000D01*
X466675Y49292D01*
X466592Y49584D01*
X466383Y49834D01*
X466008Y50000D01*
X465508Y50084D01*
X465217Y50250D01*
X465092Y50542D01*
X465175Y50834D01*
X465383Y51042D01*
X465675Y51167D01*
X465967D01*
X466258Y51084D01*
X466508Y50875D01*
G01X468067Y48667D02*
Y51167D01*
X469108D01*
X469442Y51042D01*
X469650Y50875D01*
X469733Y50542D01*
X469650Y50209D01*
X469400Y50000D01*
X469108Y49875D01*
X468067D01*
G01X469108D02*
X469733Y48667D01*
G01X471917D02*
X472000Y49209D01*
X472125Y49667D01*
X472292Y50084D01*
X472500Y50542D01*
X472833Y51167D01*
X471167D01*
G01X475100D02*
X474767Y51084D01*
X474517Y50875D01*
X474350Y50625D01*
X474225Y50292D01*
X474183Y49917D01*
X474225Y49542D01*
X474350Y49209D01*
X474517Y48959D01*
X474767Y48750D01*
X475100Y48667D01*
X475433Y48750D01*
X475683Y48959D01*
X475850Y49209D01*
X475975Y49542D01*
X476017Y49917D01*
X475975Y50292D01*
X475850Y50625D01*
X475683Y50875D01*
X475433Y51084D01*
X475100Y51167D01*
G01X477492Y48959D02*
X477783Y48750D01*
X478117Y48667D01*
X478450Y48750D01*
X478742Y49000D01*
X478950Y49375D01*
X479033Y49750D01*
Y50209D01*
X478950Y50584D01*
X478742Y50917D01*
X478492Y51084D01*
X478200Y51167D01*
X477867Y51084D01*
X477617Y50917D01*
X477450Y50667D01*
X477367Y50334D01*
X477450Y50042D01*
X477658Y49750D01*
X477908Y49584D01*
X478200Y49542D01*
X478533Y49625D01*
X478783Y49834D01*
X479033Y50209D01*
G01X441500Y62717D02*
X439000D01*
Y63758D01*
X439125Y64092D01*
X439292Y64300D01*
X439625Y64383D01*
X439958Y64300D01*
X440167Y64050D01*
X440292Y63758D01*
Y62717D01*
G01Y63758D02*
X441500Y64383D01*
G01Y66567D02*
X440958Y66650D01*
X440500Y66775D01*
X440083Y66942D01*
X439625Y67150D01*
X439000Y67483D01*
Y65817D01*
G01X441500Y70250D02*
X439000D01*
X440792Y68708D01*
Y70792D01*
G01X441500Y72850D02*
X441458Y73142D01*
X441333Y73475D01*
X441125Y73683D01*
X440833Y73767D01*
X440542Y73683D01*
X440292Y73433D01*
X440167Y73058D01*
Y72642D01*
X440083Y72392D01*
X439875Y72183D01*
X439583Y72100D01*
X439292Y72225D01*
X439083Y72517D01*
X439000Y72850D01*
X439083Y73183D01*
X439292Y73475D01*
X439583Y73600D01*
X439875Y73517D01*
X440083Y73308D01*
X440167Y73058D01*
Y72642D01*
X440292Y72267D01*
X440542Y72017D01*
X440833Y71933D01*
X441125Y72017D01*
X441333Y72225D01*
X441458Y72558D01*
X441500Y72850D01*
G01X468000Y70900D02*
X464000D01*
Y63500D01*
G01X459900D02*
X463900D01*
Y70900D01*
G01X445700Y62717D02*
X443200D01*
Y63758D01*
X443325Y64092D01*
X443492Y64300D01*
X443825Y64383D01*
X444158Y64300D01*
X444367Y64050D01*
X444492Y63758D01*
Y62717D01*
G01Y63758D02*
X445700Y64383D01*
G01Y66567D02*
X445158Y66650D01*
X444700Y66775D01*
X444283Y66942D01*
X443825Y67150D01*
X443200Y67483D01*
Y65817D01*
G01X445325Y68833D02*
X445533Y69083D01*
X445658Y69375D01*
X445700Y69750D01*
X445617Y70125D01*
X445450Y70417D01*
X445158Y70625D01*
X444825Y70667D01*
X444492Y70583D01*
X444283Y70375D01*
X444117Y70083D01*
X444075Y69792D01*
X444117Y69500D01*
X444283Y69125D01*
X443200Y69250D01*
Y70375D01*
G01X443617Y72058D02*
X443367Y72308D01*
X443242Y72600D01*
X443200Y72933D01*
X443283Y73350D01*
X443492Y73642D01*
X443742Y73725D01*
X443992Y73683D01*
X444200Y73517D01*
X444617Y72683D01*
X444908Y72308D01*
X445325Y72058D01*
X445700Y71975D01*
Y73725D01*
G01X468200Y63500D02*
X472200D01*
Y70900D01*
G01X453900Y62717D02*
X451400D01*
Y63758D01*
X451525Y64092D01*
X451692Y64300D01*
X452025Y64383D01*
X452358Y64300D01*
X452567Y64050D01*
X452692Y63758D01*
Y62717D01*
G01Y63758D02*
X453900Y64383D01*
G01Y66567D02*
X453358Y66650D01*
X452900Y66775D01*
X452483Y66942D01*
X452025Y67150D01*
X451400Y67483D01*
Y65817D01*
G01X453525Y68833D02*
X453733Y69083D01*
X453858Y69375D01*
X453900Y69750D01*
X453817Y70125D01*
X453650Y70417D01*
X453358Y70625D01*
X453025Y70667D01*
X452692Y70583D01*
X452483Y70375D01*
X452317Y70083D01*
X452275Y69792D01*
X452317Y69500D01*
X452483Y69125D01*
X451400Y69250D01*
Y70375D01*
G01X453900Y72850D02*
X451400D01*
X451900Y72350D01*
G01X453900D02*
Y73350D01*
G01X459700Y70900D02*
X455700D01*
Y63500D01*
G01X449900Y62717D02*
X447400D01*
Y63758D01*
X447525Y64092D01*
X447692Y64300D01*
X448025Y64383D01*
X448358Y64300D01*
X448567Y64050D01*
X448692Y63758D01*
Y62717D01*
G01Y63758D02*
X449900Y64383D01*
G01Y66567D02*
X449358Y66650D01*
X448900Y66775D01*
X448483Y66942D01*
X448025Y67150D01*
X447400Y67483D01*
Y65817D01*
G01X449900Y70250D02*
X447400D01*
X449192Y68708D01*
Y70792D01*
G01X448858Y72058D02*
X448567Y72350D01*
X448400Y72600D01*
X448317Y72933D01*
X448400Y73225D01*
X448567Y73433D01*
X448817Y73600D01*
X449108Y73642D01*
X449358Y73600D01*
X449608Y73433D01*
X449817Y73183D01*
X449900Y72892D01*
X449817Y72558D01*
X449567Y72267D01*
X449192Y72100D01*
X448775Y72058D01*
X448233Y72142D01*
X447942Y72267D01*
X447650Y72475D01*
X447442Y72767D01*
X447400Y73058D01*
X447483Y73350D01*
X447692Y73558D01*
G01X451300Y90767D02*
X448800D01*
Y91808D01*
X448925Y92142D01*
X449092Y92350D01*
X449425Y92433D01*
X449758Y92350D01*
X449967Y92100D01*
X450092Y91808D01*
Y90767D01*
G01Y91808D02*
X451300Y92433D01*
G01X450925Y93783D02*
X451133Y94033D01*
X451258Y94325D01*
X451300Y94700D01*
X451217Y95075D01*
X451050Y95367D01*
X450758Y95575D01*
X450425Y95617D01*
X450092Y95533D01*
X449883Y95325D01*
X449717Y95033D01*
X449675Y94742D01*
X449717Y94450D01*
X449883Y94075D01*
X448800Y94200D01*
Y95325D01*
G01X450258Y97008D02*
X449967Y97300D01*
X449800Y97550D01*
X449717Y97883D01*
X449800Y98175D01*
X449967Y98383D01*
X450217Y98550D01*
X450508Y98592D01*
X450758Y98550D01*
X451008Y98383D01*
X451217Y98133D01*
X451300Y97842D01*
X451217Y97508D01*
X450967Y97217D01*
X450592Y97050D01*
X450175Y97008D01*
X449633Y97092D01*
X449342Y97217D01*
X449050Y97425D01*
X448842Y97717D01*
X448800Y98008D01*
X448883Y98300D01*
X449092Y98508D01*
G01X453800Y93500D02*
X457800D01*
Y100900D01*
G01X451334Y100517D02*
X448834D01*
Y101558D01*
X448959Y101892D01*
X449126Y102100D01*
X449459Y102183D01*
X449792Y102100D01*
X450001Y101850D01*
X450126Y101558D01*
Y100517D01*
G01Y101558D02*
X451334Y102183D01*
G01X450292Y103658D02*
X450001Y103950D01*
X449834Y104200D01*
X449751Y104533D01*
X449834Y104825D01*
X450001Y105033D01*
X450251Y105200D01*
X450542Y105242D01*
X450792Y105200D01*
X451042Y105033D01*
X451251Y104783D01*
X451334Y104492D01*
X451251Y104158D01*
X451001Y103867D01*
X450626Y103700D01*
X450209Y103658D01*
X449667Y103742D01*
X449376Y103867D01*
X449084Y104075D01*
X448876Y104367D01*
X448834Y104658D01*
X448917Y104950D01*
X449126Y105158D01*
G01X451334Y108050D02*
X448834D01*
X450626Y106508D01*
Y108592D01*
G01X451334Y111150D02*
X448834D01*
X450626Y109608D01*
Y111692D01*
G01X453800Y101000D02*
X457800D01*
Y108400D01*
G01X460400Y95700D02*
X458200Y93500D01*
G01X460400Y95700D02*
X458200Y97900D01*
G01Y102700D02*
Y88700D01*
G01X479700D02*
X458900D01*
G01X458200Y102700D02*
X479700D01*
G01X444517Y139167D02*
Y141667D01*
X445558D01*
X445892Y141542D01*
X446100Y141375D01*
X446183Y141042D01*
X446100Y140709D01*
X445850Y140500D01*
X445558Y140375D01*
X444517D01*
G01X445558D02*
X446183Y139167D01*
G01X447658Y140209D02*
X447950Y140500D01*
X448200Y140667D01*
X448533Y140750D01*
X448825Y140667D01*
X449033Y140500D01*
X449200Y140250D01*
X449242Y139959D01*
X449200Y139709D01*
X449033Y139459D01*
X448783Y139250D01*
X448492Y139167D01*
X448158Y139250D01*
X447867Y139500D01*
X447700Y139875D01*
X447658Y140292D01*
X447742Y140834D01*
X447867Y141125D01*
X448075Y141417D01*
X448367Y141625D01*
X448658Y141667D01*
X448950Y141584D01*
X449158Y141375D01*
G01X450758Y141250D02*
X451008Y141500D01*
X451300Y141625D01*
X451633Y141667D01*
X452050Y141584D01*
X452342Y141375D01*
X452425Y141125D01*
X452383Y140875D01*
X452217Y140667D01*
X451383Y140250D01*
X451008Y139959D01*
X450758Y139542D01*
X450675Y139167D01*
X452425D01*
G01X454650D02*
Y141667D01*
X454150Y141167D01*
G01Y139167D02*
X455150D01*
G01X467959Y145008D02*
X467960Y141008D01*
X475359D01*
G01X451405Y117095D02*
X448905D01*
Y118136D01*
X449030Y118470D01*
X449197Y118678D01*
X449530Y118761D01*
X449863Y118678D01*
X450072Y118428D01*
X450197Y118136D01*
Y117095D01*
G01Y118136D02*
X451405Y118761D01*
G01X449322Y120236D02*
X449072Y120486D01*
X448947Y120778D01*
X448905Y121111D01*
X448988Y121528D01*
X449197Y121820D01*
X449447Y121903D01*
X449697Y121861D01*
X449905Y121695D01*
X450322Y120861D01*
X450613Y120486D01*
X451030Y120236D01*
X451405Y120153D01*
Y121903D01*
G01X451113Y123420D02*
X451322Y123711D01*
X451405Y124045D01*
X451322Y124378D01*
X451072Y124670D01*
X450697Y124878D01*
X450322Y124961D01*
X449863D01*
X449488Y124878D01*
X449155Y124670D01*
X448988Y124420D01*
X448905Y124128D01*
X448988Y123795D01*
X449155Y123545D01*
X449405Y123378D01*
X449738Y123295D01*
X450030Y123378D01*
X450322Y123586D01*
X450488Y123836D01*
X450530Y124128D01*
X450447Y124461D01*
X450238Y124711D01*
X449863Y124961D01*
G01X450363Y126436D02*
X450072Y126728D01*
X449905Y126978D01*
X449822Y127311D01*
X449905Y127603D01*
X450072Y127811D01*
X450322Y127978D01*
X450613Y128020D01*
X450863Y127978D01*
X451113Y127811D01*
X451322Y127561D01*
X451405Y127270D01*
X451322Y126936D01*
X451072Y126645D01*
X450697Y126478D01*
X450280Y126436D01*
X449738Y126520D01*
X449447Y126645D01*
X449155Y126853D01*
X448947Y127145D01*
X448905Y127436D01*
X448988Y127728D01*
X449197Y127936D01*
G01X451405Y130328D02*
X448905D01*
X449405Y129828D01*
G01X451405D02*
Y130828D01*
G01X464905Y116928D02*
X468905D01*
Y124328D01*
G01X447368Y117091D02*
X444868D01*
Y118132D01*
X444993Y118466D01*
X445160Y118674D01*
X445493Y118757D01*
X445826Y118674D01*
X446035Y118424D01*
X446160Y118132D01*
Y117091D01*
G01Y118132D02*
X447368Y118757D01*
G01X445285Y120232D02*
X445035Y120482D01*
X444910Y120774D01*
X444868Y121107D01*
X444951Y121524D01*
X445160Y121816D01*
X445410Y121899D01*
X445660Y121857D01*
X445868Y121691D01*
X446285Y120857D01*
X446576Y120482D01*
X446993Y120232D01*
X447368Y120149D01*
Y121899D01*
G01X447076Y123416D02*
X447285Y123707D01*
X447368Y124041D01*
X447285Y124374D01*
X447035Y124666D01*
X446660Y124874D01*
X446285Y124957D01*
X445826D01*
X445451Y124874D01*
X445118Y124666D01*
X444951Y124416D01*
X444868Y124124D01*
X444951Y123791D01*
X445118Y123541D01*
X445368Y123374D01*
X445701Y123291D01*
X445993Y123374D01*
X446285Y123582D01*
X446451Y123832D01*
X446493Y124124D01*
X446410Y124457D01*
X446201Y124707D01*
X445826Y124957D01*
G01X446326Y126432D02*
X446035Y126724D01*
X445868Y126974D01*
X445785Y127307D01*
X445868Y127599D01*
X446035Y127807D01*
X446285Y127974D01*
X446576Y128016D01*
X446826Y127974D01*
X447076Y127807D01*
X447285Y127557D01*
X447368Y127266D01*
X447285Y126932D01*
X447035Y126641D01*
X446660Y126474D01*
X446243Y126432D01*
X445701Y126516D01*
X445410Y126641D01*
X445118Y126849D01*
X444910Y127141D01*
X444868Y127432D01*
X444951Y127724D01*
X445160Y127932D01*
G01X444868Y130324D02*
X444951Y129991D01*
X445160Y129741D01*
X445410Y129574D01*
X445743Y129449D01*
X446118Y129407D01*
X446493Y129449D01*
X446826Y129574D01*
X447076Y129741D01*
X447285Y129991D01*
X447368Y130324D01*
X447285Y130657D01*
X447076Y130907D01*
X446826Y131074D01*
X446493Y131199D01*
X446118Y131241D01*
X445743Y131199D01*
X445410Y131074D01*
X445160Y130907D01*
X444951Y130657D01*
X444868Y130324D01*
G01X460868Y116924D02*
X464868D01*
Y124324D01*
G01X441279Y120308D02*
X441154Y120058D01*
X441071Y119766D01*
Y119433D01*
X441196Y119058D01*
X441404Y118766D01*
X441654Y118558D01*
X442071Y118391D01*
X442446Y118349D01*
X442821Y118433D01*
X443071Y118558D01*
X443321Y118808D01*
X443488Y119099D01*
X443571Y119391D01*
Y119683D01*
X443488Y119974D01*
X443363Y120224D01*
X443196Y120433D01*
G01X443571Y122491D02*
X441071D01*
X441571Y121991D01*
G01X443571D02*
Y122991D01*
G01X443071Y124674D02*
X443363Y124924D01*
X443529Y125258D01*
X443571Y125633D01*
X443529Y125966D01*
X443321Y126299D01*
X443071Y126508D01*
X442821Y126549D01*
X442529Y126466D01*
X442321Y126174D01*
X442238Y125883D01*
Y125508D01*
G01Y125883D02*
X442113Y126133D01*
X441904Y126341D01*
X441654Y126424D01*
X441404Y126341D01*
X441196Y126133D01*
X441071Y125758D01*
X441113Y125383D01*
X441279Y125008D01*
G01X441488Y127899D02*
X441238Y128149D01*
X441113Y128441D01*
X441071Y128774D01*
X441154Y129191D01*
X441363Y129483D01*
X441613Y129566D01*
X441863Y129524D01*
X442071Y129358D01*
X442488Y128524D01*
X442779Y128149D01*
X443196Y127899D01*
X443571Y127816D01*
Y129566D01*
G01X439267Y115459D02*
X439017Y115584D01*
X438725Y115667D01*
X438392D01*
X438017Y115542D01*
X437725Y115334D01*
X437517Y115084D01*
X437350Y114667D01*
X437308Y114292D01*
X437392Y113917D01*
X437517Y113667D01*
X437767Y113417D01*
X438058Y113250D01*
X438350Y113167D01*
X438642D01*
X438933Y113250D01*
X439183Y113375D01*
X439392Y113542D01*
G01X441450Y113167D02*
Y115667D01*
X440950Y115167D01*
G01Y113167D02*
X441950D01*
G01X443633Y113667D02*
X443883Y113375D01*
X444217Y113209D01*
X444592Y113167D01*
X444925Y113209D01*
X445258Y113417D01*
X445467Y113667D01*
X445508Y113917D01*
X445425Y114209D01*
X445133Y114417D01*
X444842Y114500D01*
X444467D01*
G01X444842D02*
X445092Y114625D01*
X445300Y114834D01*
X445383Y115084D01*
X445300Y115334D01*
X445092Y115542D01*
X444717Y115667D01*
X444342Y115625D01*
X443967Y115459D01*
G01X446733Y113667D02*
X446983Y113375D01*
X447317Y113209D01*
X447692Y113167D01*
X448025Y113209D01*
X448358Y113417D01*
X448567Y113667D01*
X448608Y113917D01*
X448525Y114209D01*
X448233Y114417D01*
X447942Y114500D01*
X447567D01*
G01X447942D02*
X448192Y114625D01*
X448400Y114834D01*
X448483Y115084D01*
X448400Y115334D01*
X448192Y115542D01*
X447817Y115667D01*
X447442Y115625D01*
X447067Y115459D01*
G01X455834Y129900D02*
X455792Y129567D01*
X455626Y129275D01*
X455376Y129025D01*
X455084Y128858D01*
X454751Y128775D01*
X454417D01*
X454084Y128858D01*
X453792Y129025D01*
X453542Y129275D01*
X453376Y129567D01*
X453334Y129900D01*
X453376Y130233D01*
X453542Y130525D01*
X453792Y130775D01*
X454084Y130942D01*
X454417Y131025D01*
X454751D01*
X455084Y130942D01*
X455376Y130775D01*
X455626Y130525D01*
X455792Y130233D01*
X455834Y129900D01*
G01X455167Y130233D02*
X455834Y130733D01*
G01X453751Y132208D02*
X453501Y132458D01*
X453376Y132750D01*
X453334Y133083D01*
X453417Y133500D01*
X453626Y133792D01*
X453876Y133875D01*
X454126Y133833D01*
X454334Y133667D01*
X454751Y132833D01*
X455042Y132458D01*
X455459Y132208D01*
X455834Y132125D01*
Y133875D01*
G01Y136600D02*
X453334D01*
X455126Y135058D01*
Y137142D01*
G01X471770Y140582D02*
X458770D01*
G01D02*
Y126582D01*
G01D02*
X471770D01*
G01X451880Y146370D02*
X451838Y146037D01*
X451672Y145745D01*
X451422Y145495D01*
X451130Y145328D01*
X450797Y145245D01*
X450463D01*
X450130Y145328D01*
X449838Y145495D01*
X449588Y145745D01*
X449422Y146037D01*
X449380Y146370D01*
X449422Y146703D01*
X449588Y146995D01*
X449838Y147245D01*
X450130Y147412D01*
X450463Y147495D01*
X450797D01*
X451130Y147412D01*
X451422Y147245D01*
X451672Y146995D01*
X451838Y146703D01*
X451880Y146370D01*
G01X451213Y146703D02*
X451880Y147203D01*
G01X449797Y148678D02*
X449547Y148928D01*
X449422Y149220D01*
X449380Y149553D01*
X449463Y149970D01*
X449672Y150262D01*
X449922Y150345D01*
X450172Y150303D01*
X450380Y150137D01*
X450797Y149303D01*
X451088Y148928D01*
X451505Y148678D01*
X451880Y148595D01*
Y150345D01*
G01X451505Y151653D02*
X451713Y151903D01*
X451838Y152195D01*
X451880Y152570D01*
X451797Y152945D01*
X451630Y153237D01*
X451338Y153445D01*
X451005Y153487D01*
X450672Y153403D01*
X450463Y153195D01*
X450297Y152903D01*
X450255Y152612D01*
X450297Y152320D01*
X450463Y151945D01*
X449380Y152070D01*
Y153195D01*
G01X467285Y156509D02*
X454285D01*
G01D02*
Y142509D01*
G01D02*
X467285D01*
G01D02*
Y156509D01*
G01X460872Y171383D02*
X461080Y171133D01*
X461330Y170966D01*
X461622Y170883D01*
X461955Y170966D01*
X462205Y171133D01*
X462455Y171383D01*
X462538Y171716D01*
Y173383D01*
G01X463972Y170883D02*
Y173383D01*
X464972D01*
X465305Y173258D01*
X465555Y172966D01*
X465638Y172633D01*
X465555Y172300D01*
X465347Y172050D01*
X464972Y171925D01*
X463972D01*
G01X467113D02*
X467405Y172216D01*
X467655Y172383D01*
X467988Y172466D01*
X468280Y172383D01*
X468488Y172216D01*
X468655Y171966D01*
X468697Y171675D01*
X468655Y171425D01*
X468488Y171175D01*
X468238Y170966D01*
X467947Y170883D01*
X467613Y170966D01*
X467322Y171216D01*
X467155Y171591D01*
X467113Y172008D01*
X467197Y172550D01*
X467322Y172841D01*
X467530Y173133D01*
X467822Y173341D01*
X468113Y173383D01*
X468405Y173300D01*
X468613Y173091D01*
G01X471385Y175380D02*
Y205980D01*
X459585D01*
Y175380D01*
X471385D01*
G01X450400Y192350D02*
X447900D01*
X448400Y191850D01*
G01X450400D02*
Y192850D01*
G01X449567Y194908D02*
Y195992D01*
G01X448317Y197758D02*
X448067Y198008D01*
X447942Y198300D01*
X447900Y198633D01*
X447983Y199050D01*
X448192Y199342D01*
X448442Y199425D01*
X448692Y199383D01*
X448900Y199217D01*
X449317Y198383D01*
X449608Y198008D01*
X450025Y197758D01*
X450400Y197675D01*
Y199425D01*
G01X449900Y181017D02*
X450150Y181225D01*
X450317Y181475D01*
X450400Y181767D01*
X450317Y182100D01*
X450150Y182350D01*
X449900Y182600D01*
X449567Y182683D01*
X447900D01*
G01X450400Y184117D02*
X447900D01*
Y185117D01*
X448025Y185450D01*
X448317Y185700D01*
X448650Y185783D01*
X448983Y185700D01*
X449233Y185492D01*
X449358Y185117D01*
Y184117D01*
G01Y187258D02*
X449067Y187550D01*
X448900Y187800D01*
X448817Y188133D01*
X448900Y188425D01*
X449067Y188633D01*
X449317Y188800D01*
X449608Y188842D01*
X449858Y188800D01*
X450108Y188633D01*
X450317Y188383D01*
X450400Y188092D01*
X450317Y187758D01*
X450067Y187467D01*
X449692Y187300D01*
X449275Y187258D01*
X448733Y187342D01*
X448442Y187467D01*
X448150Y187675D01*
X447942Y187967D01*
X447900Y188258D01*
X447983Y188550D01*
X448192Y188758D01*
G01X441850Y178040D02*
X441725Y178207D01*
X441516Y178332D01*
X441225Y178415D01*
X440975Y178332D01*
X440808Y178165D01*
X440683Y177874D01*
Y176749D01*
X443183D01*
Y178124D01*
X443016Y178415D01*
X442766Y178582D01*
X442475Y178665D01*
X442183Y178582D01*
X441933Y178332D01*
X441850Y178040D01*
Y176749D01*
G01X443183Y179724D02*
X440683D01*
X442766Y180807D01*
X440683Y181890D01*
X443183D01*
G01X440891Y184824D02*
X440766Y184574D01*
X440683Y184282D01*
Y183949D01*
X440808Y183574D01*
X441016Y183282D01*
X441266Y183074D01*
X441683Y182907D01*
X442058Y182865D01*
X442433Y182949D01*
X442683Y183074D01*
X442933Y183324D01*
X443100Y183615D01*
X443183Y183907D01*
Y184199D01*
X443100Y184490D01*
X442975Y184740D01*
X442808Y184949D01*
G01X443183Y189065D02*
X440683Y190107D01*
X443183Y191149D01*
G01X442308Y190774D02*
Y189440D01*
G01X443183Y192290D02*
X440683D01*
Y193124D01*
X440808Y193457D01*
X440975Y193707D01*
X441225Y193915D01*
X441516Y194082D01*
X441933Y194124D01*
X442350Y194082D01*
X442641Y193915D01*
X442891Y193707D01*
X443058Y193457D01*
X443183Y193124D01*
Y192290D01*
G01Y195390D02*
X440683D01*
Y196224D01*
X440808Y196557D01*
X440975Y196807D01*
X441225Y197015D01*
X441516Y197182D01*
X441933Y197224D01*
X442350Y197182D01*
X442641Y197015D01*
X442891Y196807D01*
X443058Y196557D01*
X443183Y196224D01*
Y195390D01*
G01Y198574D02*
X440683D01*
Y199615D01*
X440808Y199949D01*
X440975Y200157D01*
X441308Y200240D01*
X441641Y200157D01*
X441850Y199907D01*
X441975Y199615D01*
Y198574D01*
G01Y199615D02*
X443183Y200240D01*
G01X441100Y201715D02*
X440850Y201965D01*
X440725Y202257D01*
X440683Y202590D01*
X440766Y203007D01*
X440975Y203299D01*
X441225Y203382D01*
X441475Y203340D01*
X441683Y203174D01*
X442100Y202340D01*
X442391Y201965D01*
X442808Y201715D01*
X443183Y201632D01*
Y203382D01*
G01X451900Y201100D02*
X446400D01*
Y190600D01*
X451900D01*
Y201100D01*
G01X465549Y208989D02*
Y212989D01*
X458149D01*
G01X456585Y177932D02*
X454085D01*
Y178973D01*
X454210Y179307D01*
X454377Y179515D01*
X454710Y179598D01*
X455043Y179515D01*
X455252Y179265D01*
X455377Y178973D01*
Y177932D01*
G01Y178973D02*
X456585Y179598D01*
G01X456293Y181157D02*
X456502Y181448D01*
X456585Y181782D01*
X456502Y182115D01*
X456252Y182407D01*
X455877Y182615D01*
X455502Y182698D01*
X455043D01*
X454668Y182615D01*
X454335Y182407D01*
X454168Y182157D01*
X454085Y181865D01*
X454168Y181532D01*
X454335Y181282D01*
X454585Y181115D01*
X454918Y181032D01*
X455210Y181115D01*
X455502Y181323D01*
X455668Y181573D01*
X455710Y181865D01*
X455627Y182198D01*
X455418Y182448D01*
X455043Y182698D01*
G01X456085Y184048D02*
X456377Y184298D01*
X456543Y184632D01*
X456585Y185007D01*
X456543Y185340D01*
X456335Y185673D01*
X456085Y185882D01*
X455835Y185923D01*
X455543Y185840D01*
X455335Y185548D01*
X455252Y185257D01*
Y184882D01*
G01Y185257D02*
X455127Y185507D01*
X454918Y185715D01*
X454668Y185798D01*
X454418Y185715D01*
X454210Y185507D01*
X454085Y185132D01*
X454127Y184757D01*
X454293Y184382D01*
G01X456085Y187148D02*
X456377Y187398D01*
X456543Y187732D01*
X456585Y188107D01*
X456543Y188440D01*
X456335Y188773D01*
X456085Y188982D01*
X455835Y189023D01*
X455543Y188940D01*
X455335Y188648D01*
X455252Y188357D01*
Y187982D01*
G01Y188357D02*
X455127Y188607D01*
X454918Y188815D01*
X454668Y188898D01*
X454418Y188815D01*
X454210Y188607D01*
X454085Y188232D01*
X454127Y187857D01*
X454293Y187482D01*
G01X467931Y302095D02*
X492731D01*
Y208395D01*
X467931D01*
Y302095D01*
G01X451460Y215505D02*
Y218005D01*
X452501D01*
X452835Y217880D01*
X453043Y217713D01*
X453126Y217380D01*
X453043Y217047D01*
X452793Y216838D01*
X452501Y216713D01*
X451460D01*
G01X452501D02*
X453126Y215505D01*
G01X454685Y215797D02*
X454976Y215588D01*
X455310Y215505D01*
X455643Y215588D01*
X455935Y215838D01*
X456143Y216213D01*
X456226Y216588D01*
Y217047D01*
X456143Y217422D01*
X455935Y217755D01*
X455685Y217922D01*
X455393Y218005D01*
X455060Y217922D01*
X454810Y217755D01*
X454643Y217505D01*
X454560Y217172D01*
X454643Y216880D01*
X454851Y216588D01*
X455101Y216422D01*
X455393Y216380D01*
X455726Y216463D01*
X455976Y216672D01*
X456226Y217047D01*
G01X457576Y216005D02*
X457826Y215713D01*
X458160Y215547D01*
X458535Y215505D01*
X458868Y215547D01*
X459201Y215755D01*
X459410Y216005D01*
X459451Y216255D01*
X459368Y216547D01*
X459076Y216755D01*
X458785Y216838D01*
X458410D01*
G01X458785D02*
X459035Y216963D01*
X459243Y217172D01*
X459326Y217422D01*
X459243Y217672D01*
X459035Y217880D01*
X458660Y218005D01*
X458285Y217963D01*
X457910Y217797D01*
G01X462093Y215505D02*
Y218005D01*
X460551Y216213D01*
X462635D01*
G01X466631Y235560D02*
X463631D01*
G01X465131Y237060D02*
Y234060D01*
G01X462001Y253683D02*
X461876Y253850D01*
X461667Y253975D01*
X461376Y254058D01*
X461126Y253975D01*
X460959Y253808D01*
X460834Y253517D01*
Y252392D01*
X463334D01*
Y253767D01*
X463167Y254058D01*
X462917Y254225D01*
X462626Y254308D01*
X462334Y254225D01*
X462084Y253975D01*
X462001Y253683D01*
Y252392D01*
G01X463334Y255408D02*
X460834Y256450D01*
X463334Y257492D01*
G01X462459Y257117D02*
Y255783D01*
G01X460834Y259550D02*
X463334D01*
G01X460834Y258592D02*
Y260508D01*
G01X463334Y262650D02*
X460834D01*
X461334Y262150D01*
G01X463334D02*
Y263150D01*
G01X465131Y276430D02*
Y273430D01*
G01X466631Y274930D02*
X463631D01*
G01X443667Y305712D02*
X438667Y309212D01*
G01Y305712D02*
X443667Y309212D01*
G01X439500Y311479D02*
X439000Y311979D01*
X438750Y312562D01*
X438667Y313229D01*
X438834Y314062D01*
X439250Y314645D01*
X439750Y314812D01*
X440250Y314729D01*
X440667Y314395D01*
X441500Y312729D01*
X442084Y311979D01*
X442917Y311479D01*
X443667Y311312D01*
Y314812D01*
G01X443834Y318662D02*
X443750Y318495D01*
X443584D01*
X443500Y318662D01*
X443584Y318829D01*
X443750D01*
X443834Y318662D01*
G01X441584D02*
X441500Y318495D01*
X441334D01*
X441250Y318662D01*
X441334Y318829D01*
X441500D01*
X441584Y318662D01*
G01X442667Y322429D02*
X443250Y322929D01*
X443584Y323595D01*
X443667Y324345D01*
X443584Y325012D01*
X443167Y325679D01*
X442667Y326095D01*
X442167Y326179D01*
X441584Y326012D01*
X441167Y325429D01*
X441000Y324845D01*
Y324095D01*
G01Y324845D02*
X440750Y325345D01*
X440334Y325762D01*
X439834Y325929D01*
X439334Y325762D01*
X438917Y325345D01*
X438667Y324595D01*
X438750Y323845D01*
X439084Y323095D01*
G01X439500Y328279D02*
X439000Y328779D01*
X438750Y329362D01*
X438667Y330029D01*
X438834Y330862D01*
X439250Y331445D01*
X439750Y331612D01*
X440250Y331529D01*
X440667Y331195D01*
X441500Y329529D01*
X442084Y328779D01*
X442917Y328279D01*
X443667Y328112D01*
Y331612D01*
G01X443834Y335462D02*
X443750Y335295D01*
X443584D01*
X443500Y335462D01*
X443584Y335629D01*
X443750D01*
X443834Y335462D01*
G01X443667Y340895D02*
X442584Y341062D01*
X441667Y341312D01*
X440834Y341645D01*
X439917Y342062D01*
X438667Y342729D01*
Y339395D01*
G01X441584Y345079D02*
X441000Y345662D01*
X440667Y346162D01*
X440500Y346829D01*
X440667Y347412D01*
X441000Y347829D01*
X441500Y348162D01*
X442084Y348245D01*
X442584Y348162D01*
X443084Y347829D01*
X443500Y347329D01*
X443667Y346745D01*
X443500Y346079D01*
X443000Y345495D01*
X442250Y345162D01*
X441417Y345079D01*
X440334Y345245D01*
X439750Y345495D01*
X439167Y345912D01*
X438750Y346495D01*
X438667Y347079D01*
X438834Y347662D01*
X439250Y348079D01*
G01X443667Y352262D02*
X443584Y352845D01*
X443334Y353512D01*
X442917Y353929D01*
X442334Y354095D01*
X441750Y353929D01*
X441250Y353429D01*
X441000Y352679D01*
Y351845D01*
X440834Y351345D01*
X440417Y350929D01*
X439834Y350762D01*
X439250Y351012D01*
X438834Y351595D01*
X438667Y352262D01*
X438834Y352929D01*
X439250Y353512D01*
X439834Y353762D01*
X440417Y353595D01*
X440834Y353179D01*
X441000Y352679D01*
Y351845D01*
X441250Y351095D01*
X441750Y350595D01*
X442334Y350429D01*
X442917Y350595D01*
X443334Y351012D01*
X443584Y351679D01*
X443667Y352262D01*
G01Y356029D02*
X438667D01*
G01Y359195D02*
X441750Y356029D01*
G01X443667Y359695D02*
X440334Y357445D01*
G01X443667Y361712D02*
X438667D01*
G01Y365212D02*
X443667D01*
G01X441167D02*
Y361712D01*
G01X438667Y367479D02*
Y370645D01*
X443667Y367479D01*
Y370645D01*
G01X464181Y302179D02*
X461681D01*
Y303220D01*
X461806Y303554D01*
X461973Y303762D01*
X462306Y303845D01*
X462639Y303762D01*
X462848Y303512D01*
X462973Y303220D01*
Y302179D01*
G01Y303220D02*
X464181Y303845D01*
G01X463806Y305195D02*
X464014Y305445D01*
X464139Y305737D01*
X464181Y306112D01*
X464098Y306487D01*
X463931Y306779D01*
X463639Y306987D01*
X463306Y307029D01*
X462973Y306945D01*
X462764Y306737D01*
X462598Y306445D01*
X462556Y306154D01*
X462598Y305862D01*
X462764Y305487D01*
X461681Y305612D01*
Y306737D01*
G01X462098Y308420D02*
X461848Y308670D01*
X461723Y308962D01*
X461681Y309295D01*
X461764Y309712D01*
X461973Y310004D01*
X462223Y310087D01*
X462473Y310045D01*
X462681Y309879D01*
X463098Y309045D01*
X463389Y308670D01*
X463806Y308420D01*
X464181Y308337D01*
Y310087D01*
G01X461681Y312312D02*
X461764Y311979D01*
X461973Y311729D01*
X462223Y311562D01*
X462556Y311437D01*
X462931Y311395D01*
X463306Y311437D01*
X463639Y311562D01*
X463889Y311729D01*
X464098Y311979D01*
X464181Y312312D01*
X464098Y312645D01*
X463889Y312895D01*
X463639Y313062D01*
X463306Y313187D01*
X462931Y313229D01*
X462556Y313187D01*
X462223Y313062D01*
X461973Y312895D01*
X461764Y312645D01*
X461681Y312312D01*
G01X462098Y314620D02*
X461848Y314870D01*
X461723Y315162D01*
X461681Y315495D01*
X461764Y315912D01*
X461973Y316204D01*
X462223Y316287D01*
X462473Y316245D01*
X462681Y316079D01*
X463098Y315245D01*
X463389Y314870D01*
X463806Y314620D01*
X464181Y314537D01*
Y316287D01*
G01X468334Y305983D02*
X465834D01*
Y306817D01*
X465959Y307150D01*
X466126Y307400D01*
X466376Y307608D01*
X466667Y307775D01*
X467084Y307817D01*
X467501Y307775D01*
X467792Y307608D01*
X468042Y307400D01*
X468209Y307150D01*
X468334Y306817D01*
Y305983D01*
G01Y310000D02*
X465834D01*
X466334Y309500D01*
G01X468334D02*
Y310500D01*
G01X467834Y312183D02*
X468126Y312433D01*
X468292Y312767D01*
X468334Y313142D01*
X468292Y313475D01*
X468084Y313808D01*
X467834Y314017D01*
X467584Y314058D01*
X467292Y313975D01*
X467084Y313683D01*
X467001Y313392D01*
Y313017D01*
G01Y313392D02*
X466876Y313642D01*
X466667Y313850D01*
X466417Y313933D01*
X466167Y313850D01*
X465959Y313642D01*
X465834Y313267D01*
X465876Y312892D01*
X466042Y312517D01*
G01X447217Y325459D02*
X446967Y325584D01*
X446675Y325667D01*
X446342D01*
X445967Y325542D01*
X445675Y325334D01*
X445467Y325084D01*
X445300Y324667D01*
X445258Y324292D01*
X445342Y323917D01*
X445467Y323667D01*
X445717Y323417D01*
X446008Y323250D01*
X446300Y323167D01*
X446592D01*
X446883Y323250D01*
X447133Y323375D01*
X447342Y323542D01*
G01X449400Y323167D02*
Y325667D01*
X448900Y325167D01*
G01Y323167D02*
X449900D01*
G01X451708Y324209D02*
X452000Y324500D01*
X452250Y324667D01*
X452583Y324750D01*
X452875Y324667D01*
X453083Y324500D01*
X453250Y324250D01*
X453292Y323959D01*
X453250Y323709D01*
X453083Y323459D01*
X452833Y323250D01*
X452542Y323167D01*
X452208Y323250D01*
X451917Y323500D01*
X451750Y323875D01*
X451708Y324292D01*
X451792Y324834D01*
X451917Y325125D01*
X452125Y325417D01*
X452417Y325625D01*
X452708Y325667D01*
X453000Y325584D01*
X453208Y325375D01*
G01X454892Y323459D02*
X455183Y323250D01*
X455517Y323167D01*
X455850Y323250D01*
X456142Y323500D01*
X456350Y323875D01*
X456433Y324250D01*
Y324709D01*
X456350Y325084D01*
X456142Y325417D01*
X455892Y325584D01*
X455600Y325667D01*
X455267Y325584D01*
X455017Y325417D01*
X454850Y325167D01*
X454767Y324834D01*
X454850Y324542D01*
X455058Y324250D01*
X455308Y324084D01*
X455600Y324042D01*
X455933Y324125D01*
X456183Y324334D01*
X456433Y324709D01*
G01X458700Y323167D02*
X458992Y323209D01*
X459325Y323334D01*
X459533Y323542D01*
X459617Y323834D01*
X459533Y324125D01*
X459283Y324375D01*
X458908Y324500D01*
X458492D01*
X458242Y324584D01*
X458033Y324792D01*
X457950Y325084D01*
X458075Y325375D01*
X458367Y325584D01*
X458700Y325667D01*
X459033Y325584D01*
X459325Y325375D01*
X459450Y325084D01*
X459367Y324792D01*
X459158Y324584D01*
X458908Y324500D01*
X458492D01*
X458117Y324375D01*
X457867Y324125D01*
X457783Y323834D01*
X457867Y323542D01*
X458075Y323334D01*
X458408Y323209D01*
X458700Y323167D01*
G01X466589Y320210D02*
X461089D01*
Y328210D01*
X466689D01*
G01X461300Y333666D02*
Y331166D01*
G01X460342Y333666D02*
X462258D01*
G01X463567Y331166D02*
Y333666D01*
X464567D01*
X464900Y333541D01*
X465150Y333249D01*
X465233Y332916D01*
X465150Y332583D01*
X464942Y332333D01*
X464567Y332208D01*
X463567D01*
G01X467500Y331166D02*
X467792Y331208D01*
X468125Y331333D01*
X468333Y331541D01*
X468417Y331833D01*
X468333Y332124D01*
X468083Y332374D01*
X467708Y332499D01*
X467292D01*
X467042Y332583D01*
X466833Y332791D01*
X466750Y333083D01*
X466875Y333374D01*
X467167Y333583D01*
X467500Y333666D01*
X467833Y333583D01*
X468125Y333374D01*
X468250Y333083D01*
X468167Y332791D01*
X467958Y332583D01*
X467708Y332499D01*
X467292D01*
X466917Y332374D01*
X466667Y332124D01*
X466583Y331833D01*
X466667Y331541D01*
X466875Y331333D01*
X467208Y331208D01*
X467500Y331166D01*
G01X470600Y333666D02*
X470267Y333583D01*
X470017Y333374D01*
X469850Y333124D01*
X469725Y332791D01*
X469683Y332416D01*
X469725Y332041D01*
X469850Y331708D01*
X470017Y331458D01*
X470267Y331249D01*
X470600Y331166D01*
X470933Y331249D01*
X471183Y331458D01*
X471350Y331708D01*
X471475Y332041D01*
X471517Y332416D01*
X471475Y332791D01*
X471350Y333124D01*
X471183Y333374D01*
X470933Y333583D01*
X470600Y333666D01*
G01X473700D02*
X473367Y333583D01*
X473117Y333374D01*
X472950Y333124D01*
X472825Y332791D01*
X472783Y332416D01*
X472825Y332041D01*
X472950Y331708D01*
X473117Y331458D01*
X473367Y331249D01*
X473700Y331166D01*
X474033Y331249D01*
X474283Y331458D01*
X474450Y331708D01*
X474575Y332041D01*
X474617Y332416D01*
X474575Y332791D01*
X474450Y333124D01*
X474283Y333374D01*
X474033Y333583D01*
X473700Y333666D01*
G01X460967Y338667D02*
Y341167D01*
X462008D01*
X462342Y341042D01*
X462550Y340875D01*
X462633Y340542D01*
X462550Y340209D01*
X462300Y340000D01*
X462008Y339875D01*
X460967D01*
G01X462008D02*
X462633Y338667D01*
G01X463983Y339042D02*
X464233Y338834D01*
X464525Y338709D01*
X464900Y338667D01*
X465275Y338750D01*
X465567Y338917D01*
X465775Y339209D01*
X465817Y339542D01*
X465733Y339875D01*
X465525Y340084D01*
X465233Y340250D01*
X464942Y340292D01*
X464650Y340250D01*
X464275Y340084D01*
X464400Y341167D01*
X465525D01*
G01X467208Y340750D02*
X467458Y341000D01*
X467750Y341125D01*
X468083Y341167D01*
X468500Y341084D01*
X468792Y340875D01*
X468875Y340625D01*
X468833Y340375D01*
X468667Y340167D01*
X467833Y339750D01*
X467458Y339459D01*
X467208Y339042D01*
X467125Y338667D01*
X468875D01*
G01X471100Y341167D02*
X470767Y341084D01*
X470517Y340875D01*
X470350Y340625D01*
X470225Y340292D01*
X470183Y339917D01*
X470225Y339542D01*
X470350Y339209D01*
X470517Y338959D01*
X470767Y338750D01*
X471100Y338667D01*
X471433Y338750D01*
X471683Y338959D01*
X471850Y339209D01*
X471975Y339542D01*
X472017Y339917D01*
X471975Y340292D01*
X471850Y340625D01*
X471683Y340875D01*
X471433Y341084D01*
X471100Y341167D01*
G01X474200Y338667D02*
Y341167D01*
X473700Y340667D01*
G01Y338667D02*
X474700D01*
G01X460476Y335041D02*
Y337541D01*
X461517D01*
X461851Y337416D01*
X462059Y337249D01*
X462142Y336916D01*
X462059Y336583D01*
X461809Y336374D01*
X461517Y336249D01*
X460476D01*
G01X461517D02*
X462142Y335041D01*
G01X463492Y335416D02*
X463742Y335208D01*
X464034Y335083D01*
X464409Y335041D01*
X464784Y335124D01*
X465076Y335291D01*
X465284Y335583D01*
X465326Y335916D01*
X465242Y336249D01*
X465034Y336458D01*
X464742Y336624D01*
X464451Y336666D01*
X464159Y336624D01*
X463784Y336458D01*
X463909Y337541D01*
X465034D01*
G01X466717Y337124D02*
X466967Y337374D01*
X467259Y337499D01*
X467592Y337541D01*
X468009Y337458D01*
X468301Y337249D01*
X468384Y336999D01*
X468342Y336749D01*
X468176Y336541D01*
X467342Y336124D01*
X466967Y335833D01*
X466717Y335416D01*
X466634Y335041D01*
X468384D01*
G01X470609Y337541D02*
X470276Y337458D01*
X470026Y337249D01*
X469859Y336999D01*
X469734Y336666D01*
X469692Y336291D01*
X469734Y335916D01*
X469859Y335583D01*
X470026Y335333D01*
X470276Y335124D01*
X470609Y335041D01*
X470942Y335124D01*
X471192Y335333D01*
X471359Y335583D01*
X471484Y335916D01*
X471526Y336291D01*
X471484Y336666D01*
X471359Y336999D01*
X471192Y337249D01*
X470942Y337458D01*
X470609Y337541D01*
G01X473709D02*
X473376Y337458D01*
X473126Y337249D01*
X472959Y336999D01*
X472834Y336666D01*
X472792Y336291D01*
X472834Y335916D01*
X472959Y335583D01*
X473126Y335333D01*
X473376Y335124D01*
X473709Y335041D01*
X474042Y335124D01*
X474292Y335333D01*
X474459Y335583D01*
X474584Y335916D01*
X474626Y336291D01*
X474584Y336666D01*
X474459Y336999D01*
X474292Y337249D01*
X474042Y337458D01*
X473709Y337541D01*
G01X464267Y355959D02*
X464017Y356084D01*
X463725Y356167D01*
X463392D01*
X463017Y356042D01*
X462725Y355834D01*
X462517Y355584D01*
X462350Y355167D01*
X462308Y354792D01*
X462392Y354417D01*
X462517Y354167D01*
X462767Y353917D01*
X463058Y353750D01*
X463350Y353667D01*
X463642D01*
X463933Y353750D01*
X464183Y353875D01*
X464392Y354042D01*
G01X465658Y355750D02*
X465908Y356000D01*
X466200Y356125D01*
X466533Y356167D01*
X466950Y356084D01*
X467242Y355875D01*
X467325Y355625D01*
X467283Y355375D01*
X467117Y355167D01*
X466283Y354750D01*
X465908Y354459D01*
X465658Y354042D01*
X465575Y353667D01*
X467325D01*
G01X470050D02*
Y356167D01*
X468508Y354375D01*
X470592D01*
G01X472567Y353667D02*
X472650Y354209D01*
X472775Y354667D01*
X472942Y355084D01*
X473150Y355542D01*
X473483Y356167D01*
X471817D01*
G01X454834Y374517D02*
X452334D01*
Y375558D01*
X452459Y375892D01*
X452626Y376100D01*
X452959Y376183D01*
X453292Y376100D01*
X453501Y375850D01*
X453626Y375558D01*
Y374517D01*
G01Y375558D02*
X454834Y376183D01*
G01Y378950D02*
X452334D01*
X454126Y377408D01*
Y379492D01*
G01X454334Y380633D02*
X454626Y380883D01*
X454792Y381217D01*
X454834Y381592D01*
X454792Y381925D01*
X454584Y382258D01*
X454334Y382467D01*
X454084Y382508D01*
X453792Y382425D01*
X453584Y382133D01*
X453501Y381842D01*
Y381467D01*
G01Y381842D02*
X453376Y382092D01*
X453167Y382300D01*
X452917Y382383D01*
X452667Y382300D01*
X452459Y382092D01*
X452334Y381717D01*
X452376Y381342D01*
X452542Y380967D01*
G01X452334Y384650D02*
X452417Y384317D01*
X452626Y384067D01*
X452876Y383900D01*
X453209Y383775D01*
X453584Y383733D01*
X453959Y383775D01*
X454292Y383900D01*
X454542Y384067D01*
X454751Y384317D01*
X454834Y384650D01*
X454751Y384983D01*
X454542Y385233D01*
X454292Y385400D01*
X453959Y385525D01*
X453584Y385567D01*
X453209Y385525D01*
X452876Y385400D01*
X452626Y385233D01*
X452417Y384983D01*
X452334Y384650D01*
G01X452408Y359067D02*
X452283Y358817D01*
X452200Y358525D01*
Y358192D01*
X452325Y357817D01*
X452533Y357525D01*
X452783Y357317D01*
X453200Y357150D01*
X453575Y357108D01*
X453950Y357192D01*
X454200Y357317D01*
X454450Y357567D01*
X454617Y357858D01*
X454700Y358150D01*
Y358442D01*
X454617Y358733D01*
X454492Y358983D01*
X454325Y359192D01*
G01X453658Y360458D02*
X453367Y360750D01*
X453200Y361000D01*
X453117Y361333D01*
X453200Y361625D01*
X453367Y361833D01*
X453617Y362000D01*
X453908Y362042D01*
X454158Y362000D01*
X454408Y361833D01*
X454617Y361583D01*
X454700Y361292D01*
X454617Y360958D01*
X454367Y360667D01*
X453992Y360500D01*
X453575Y360458D01*
X453033Y360542D01*
X452742Y360667D01*
X452450Y360875D01*
X452242Y361167D01*
X452200Y361458D01*
X452283Y361750D01*
X452492Y361958D01*
G01X454700Y364350D02*
X454658Y364642D01*
X454533Y364975D01*
X454325Y365183D01*
X454033Y365267D01*
X453742Y365183D01*
X453492Y364933D01*
X453367Y364558D01*
Y364142D01*
X453283Y363892D01*
X453075Y363683D01*
X452783Y363600D01*
X452492Y363725D01*
X452283Y364017D01*
X452200Y364350D01*
X452283Y364683D01*
X452492Y364975D01*
X452783Y365100D01*
X453075Y365017D01*
X453283Y364808D01*
X453367Y364558D01*
Y364142D01*
X453492Y363767D01*
X453742Y363517D01*
X454033Y363433D01*
X454325Y363517D01*
X454533Y363725D01*
X454658Y364058D01*
X454700Y364350D01*
G01Y367450D02*
X454658Y367742D01*
X454533Y368075D01*
X454325Y368283D01*
X454033Y368367D01*
X453742Y368283D01*
X453492Y368033D01*
X453367Y367658D01*
Y367242D01*
X453283Y366992D01*
X453075Y366783D01*
X452783Y366700D01*
X452492Y366825D01*
X452283Y367117D01*
X452200Y367450D01*
X452283Y367783D01*
X452492Y368075D01*
X452783Y368200D01*
X453075Y368117D01*
X453283Y367908D01*
X453367Y367658D01*
Y367242D01*
X453492Y366867D01*
X453742Y366617D01*
X454033Y366533D01*
X454325Y366617D01*
X454533Y366825D01*
X454658Y367158D01*
X454700Y367450D01*
G01X455908Y359067D02*
X455783Y358817D01*
X455700Y358525D01*
Y358192D01*
X455825Y357817D01*
X456033Y357525D01*
X456283Y357317D01*
X456700Y357150D01*
X457075Y357108D01*
X457450Y357192D01*
X457700Y357317D01*
X457950Y357567D01*
X458117Y357858D01*
X458200Y358150D01*
Y358442D01*
X458117Y358733D01*
X457992Y358983D01*
X457825Y359192D01*
G01X457158Y360458D02*
X456867Y360750D01*
X456700Y361000D01*
X456617Y361333D01*
X456700Y361625D01*
X456867Y361833D01*
X457117Y362000D01*
X457408Y362042D01*
X457658Y362000D01*
X457908Y361833D01*
X458117Y361583D01*
X458200Y361292D01*
X458117Y360958D01*
X457867Y360667D01*
X457492Y360500D01*
X457075Y360458D01*
X456533Y360542D01*
X456242Y360667D01*
X455950Y360875D01*
X455742Y361167D01*
X455700Y361458D01*
X455783Y361750D01*
X455992Y361958D01*
G01X457908Y363642D02*
X458117Y363933D01*
X458200Y364267D01*
X458117Y364600D01*
X457867Y364892D01*
X457492Y365100D01*
X457117Y365183D01*
X456658D01*
X456283Y365100D01*
X455950Y364892D01*
X455783Y364642D01*
X455700Y364350D01*
X455783Y364017D01*
X455950Y363767D01*
X456200Y363600D01*
X456533Y363517D01*
X456825Y363600D01*
X457117Y363808D01*
X457283Y364058D01*
X457325Y364350D01*
X457242Y364683D01*
X457033Y364933D01*
X456658Y365183D01*
G01X457700Y366533D02*
X457992Y366783D01*
X458158Y367117D01*
X458200Y367492D01*
X458158Y367825D01*
X457950Y368158D01*
X457700Y368367D01*
X457450Y368408D01*
X457158Y368325D01*
X456950Y368033D01*
X456867Y367742D01*
Y367367D01*
G01Y367742D02*
X456742Y367992D01*
X456533Y368200D01*
X456283Y368283D01*
X456033Y368200D01*
X455825Y367992D01*
X455700Y367617D01*
X455742Y367242D01*
X455908Y366867D01*
G01X455967Y391092D02*
X455717Y391217D01*
X455425Y391300D01*
X455092D01*
X454717Y391175D01*
X454425Y390967D01*
X454217Y390717D01*
X454050Y390300D01*
X454008Y389925D01*
X454092Y389550D01*
X454217Y389300D01*
X454467Y389050D01*
X454758Y388883D01*
X455050Y388800D01*
X455342D01*
X455633Y388883D01*
X455883Y389008D01*
X456092Y389175D01*
G01X457358Y390883D02*
X457608Y391133D01*
X457900Y391258D01*
X458233Y391300D01*
X458650Y391217D01*
X458942Y391008D01*
X459025Y390758D01*
X458983Y390508D01*
X458817Y390300D01*
X457983Y389883D01*
X457608Y389592D01*
X457358Y389175D01*
X457275Y388800D01*
X459025D01*
G01X461750D02*
Y391300D01*
X460208Y389508D01*
X462292D01*
G01X464350Y388800D02*
X464642Y388842D01*
X464975Y388967D01*
X465183Y389175D01*
X465267Y389467D01*
X465183Y389758D01*
X464933Y390008D01*
X464558Y390133D01*
X464142D01*
X463892Y390217D01*
X463683Y390425D01*
X463600Y390717D01*
X463725Y391008D01*
X464017Y391217D01*
X464350Y391300D01*
X464683Y391217D01*
X464975Y391008D01*
X465100Y390717D01*
X465017Y390425D01*
X464808Y390217D01*
X464558Y390133D01*
X464142D01*
X463767Y390008D01*
X463517Y389758D01*
X463433Y389467D01*
X463517Y389175D01*
X463725Y388967D01*
X464058Y388842D01*
X464350Y388800D01*
G01X455717Y393300D02*
Y395800D01*
X456758D01*
X457092Y395675D01*
X457300Y395508D01*
X457383Y395175D01*
X457300Y394842D01*
X457050Y394633D01*
X456758Y394508D01*
X455717D01*
G01X456758D02*
X457383Y393300D01*
G01X460150D02*
Y395800D01*
X458608Y394008D01*
X460692D01*
G01X461958Y395383D02*
X462208Y395633D01*
X462500Y395758D01*
X462833Y395800D01*
X463250Y395717D01*
X463542Y395508D01*
X463625Y395258D01*
X463583Y395008D01*
X463417Y394800D01*
X462583Y394383D01*
X462208Y394092D01*
X461958Y393675D01*
X461875Y393300D01*
X463625D01*
G01X465142Y393592D02*
X465433Y393383D01*
X465767Y393300D01*
X466100Y393383D01*
X466392Y393633D01*
X466600Y394008D01*
X466683Y394383D01*
Y394842D01*
X466600Y395217D01*
X466392Y395550D01*
X466142Y395717D01*
X465850Y395800D01*
X465517Y395717D01*
X465267Y395550D01*
X465100Y395300D01*
X465017Y394967D01*
X465100Y394675D01*
X465308Y394383D01*
X465558Y394217D01*
X465850Y394175D01*
X466183Y394258D01*
X466433Y394467D01*
X466683Y394842D01*
G01X460700Y378600D02*
X464700D01*
Y386000D01*
G01X435947Y469840D02*
Y472340D01*
X436988D01*
X437322Y472215D01*
X437530Y472048D01*
X437613Y471715D01*
X437530Y471382D01*
X437280Y471173D01*
X436988Y471048D01*
X435947D01*
G01X436988D02*
X437613Y469840D01*
G01X439088Y470882D02*
X439380Y471173D01*
X439630Y471340D01*
X439963Y471423D01*
X440255Y471340D01*
X440463Y471173D01*
X440630Y470923D01*
X440672Y470632D01*
X440630Y470382D01*
X440463Y470132D01*
X440213Y469923D01*
X439922Y469840D01*
X439588Y469923D01*
X439297Y470173D01*
X439130Y470548D01*
X439088Y470965D01*
X439172Y471507D01*
X439297Y471798D01*
X439505Y472090D01*
X439797Y472298D01*
X440088Y472340D01*
X440380Y472257D01*
X440588Y472048D01*
G01X442063Y470340D02*
X442313Y470048D01*
X442647Y469882D01*
X443022Y469840D01*
X443355Y469882D01*
X443688Y470090D01*
X443897Y470340D01*
X443938Y470590D01*
X443855Y470882D01*
X443563Y471090D01*
X443272Y471173D01*
X442897D01*
G01X443272D02*
X443522Y471298D01*
X443730Y471507D01*
X443813Y471757D01*
X443730Y472007D01*
X443522Y472215D01*
X443147Y472340D01*
X442772Y472298D01*
X442397Y472132D01*
G01X445163Y470340D02*
X445413Y470048D01*
X445747Y469882D01*
X446122Y469840D01*
X446455Y469882D01*
X446788Y470090D01*
X446997Y470340D01*
X447038Y470590D01*
X446955Y470882D01*
X446663Y471090D01*
X446372Y471173D01*
X445997D01*
G01X446372D02*
X446622Y471298D01*
X446830Y471507D01*
X446913Y471757D01*
X446830Y472007D01*
X446622Y472215D01*
X446247Y472340D01*
X445872Y472298D01*
X445497Y472132D01*
G01X437757Y456448D02*
X437632Y456198D01*
X437549Y455906D01*
Y455573D01*
X437674Y455198D01*
X437882Y454906D01*
X438132Y454698D01*
X438549Y454531D01*
X438924Y454489D01*
X439299Y454573D01*
X439549Y454698D01*
X439799Y454948D01*
X439966Y455239D01*
X440049Y455531D01*
Y455823D01*
X439966Y456114D01*
X439841Y456364D01*
X439674Y456573D01*
G01X439549Y457714D02*
X439841Y457964D01*
X440007Y458298D01*
X440049Y458673D01*
X440007Y459006D01*
X439799Y459339D01*
X439549Y459548D01*
X439299Y459589D01*
X439007Y459506D01*
X438799Y459214D01*
X438716Y458923D01*
Y458548D01*
G01Y458923D02*
X438591Y459173D01*
X438382Y459381D01*
X438132Y459464D01*
X437882Y459381D01*
X437674Y459173D01*
X437549Y458798D01*
X437591Y458423D01*
X437757Y458048D01*
G01X440049Y461731D02*
X440007Y462023D01*
X439882Y462356D01*
X439674Y462564D01*
X439382Y462648D01*
X439091Y462564D01*
X438841Y462314D01*
X438716Y461939D01*
Y461523D01*
X438632Y461273D01*
X438424Y461064D01*
X438132Y460981D01*
X437841Y461106D01*
X437632Y461398D01*
X437549Y461731D01*
X437632Y462064D01*
X437841Y462356D01*
X438132Y462481D01*
X438424Y462398D01*
X438632Y462189D01*
X438716Y461939D01*
Y461523D01*
X438841Y461148D01*
X439091Y460898D01*
X439382Y460814D01*
X439674Y460898D01*
X439882Y461106D01*
X440007Y461439D01*
X440049Y461731D01*
G01X439549Y463914D02*
X439841Y464164D01*
X440007Y464498D01*
X440049Y464873D01*
X440007Y465206D01*
X439799Y465539D01*
X439549Y465748D01*
X439299Y465789D01*
X439007Y465706D01*
X438799Y465414D01*
X438716Y465123D01*
Y464748D01*
G01Y465123D02*
X438591Y465373D01*
X438382Y465581D01*
X438132Y465664D01*
X437882Y465581D01*
X437674Y465373D01*
X437549Y464998D01*
X437591Y464623D01*
X437757Y464248D01*
G01X441257Y456448D02*
X441132Y456198D01*
X441049Y455906D01*
Y455573D01*
X441174Y455198D01*
X441382Y454906D01*
X441632Y454698D01*
X442049Y454531D01*
X442424Y454489D01*
X442799Y454573D01*
X443049Y454698D01*
X443299Y454948D01*
X443466Y455239D01*
X443549Y455531D01*
Y455823D01*
X443466Y456114D01*
X443341Y456364D01*
X443174Y456573D01*
G01X443049Y457714D02*
X443341Y457964D01*
X443507Y458298D01*
X443549Y458673D01*
X443507Y459006D01*
X443299Y459339D01*
X443049Y459548D01*
X442799Y459589D01*
X442507Y459506D01*
X442299Y459214D01*
X442216Y458923D01*
Y458548D01*
G01Y458923D02*
X442091Y459173D01*
X441882Y459381D01*
X441632Y459464D01*
X441382Y459381D01*
X441174Y459173D01*
X441049Y458798D01*
X441091Y458423D01*
X441257Y458048D01*
G01X443549Y461731D02*
X443507Y462023D01*
X443382Y462356D01*
X443174Y462564D01*
X442882Y462648D01*
X442591Y462564D01*
X442341Y462314D01*
X442216Y461939D01*
Y461523D01*
X442132Y461273D01*
X441924Y461064D01*
X441632Y460981D01*
X441341Y461106D01*
X441132Y461398D01*
X441049Y461731D01*
X441132Y462064D01*
X441341Y462356D01*
X441632Y462481D01*
X441924Y462398D01*
X442132Y462189D01*
X442216Y461939D01*
Y461523D01*
X442341Y461148D01*
X442591Y460898D01*
X442882Y460814D01*
X443174Y460898D01*
X443382Y461106D01*
X443507Y461439D01*
X443549Y461731D01*
G01X441466Y464039D02*
X441216Y464289D01*
X441091Y464581D01*
X441049Y464914D01*
X441132Y465331D01*
X441341Y465623D01*
X441591Y465706D01*
X441841Y465664D01*
X442049Y465498D01*
X442466Y464664D01*
X442757Y464289D01*
X443174Y464039D01*
X443549Y463956D01*
Y465706D01*
G01X463257Y456448D02*
X463132Y456198D01*
X463049Y455906D01*
Y455573D01*
X463174Y455198D01*
X463382Y454906D01*
X463632Y454698D01*
X464049Y454531D01*
X464424Y454489D01*
X464799Y454573D01*
X465049Y454698D01*
X465299Y454948D01*
X465466Y455239D01*
X465549Y455531D01*
Y455823D01*
X465466Y456114D01*
X465341Y456364D01*
X465174Y456573D01*
G01X465049Y457714D02*
X465341Y457964D01*
X465507Y458298D01*
X465549Y458673D01*
X465507Y459006D01*
X465299Y459339D01*
X465049Y459548D01*
X464799Y459589D01*
X464507Y459506D01*
X464299Y459214D01*
X464216Y458923D01*
Y458548D01*
G01Y458923D02*
X464091Y459173D01*
X463882Y459381D01*
X463632Y459464D01*
X463382Y459381D01*
X463174Y459173D01*
X463049Y458798D01*
X463091Y458423D01*
X463257Y458048D01*
G01X465549Y461731D02*
X465507Y462023D01*
X465382Y462356D01*
X465174Y462564D01*
X464882Y462648D01*
X464591Y462564D01*
X464341Y462314D01*
X464216Y461939D01*
Y461523D01*
X464132Y461273D01*
X463924Y461064D01*
X463632Y460981D01*
X463341Y461106D01*
X463132Y461398D01*
X463049Y461731D01*
X463132Y462064D01*
X463341Y462356D01*
X463632Y462481D01*
X463924Y462398D01*
X464132Y462189D01*
X464216Y461939D01*
Y461523D01*
X464341Y461148D01*
X464591Y460898D01*
X464882Y460814D01*
X465174Y460898D01*
X465382Y461106D01*
X465507Y461439D01*
X465549Y461731D01*
G01Y464748D02*
X465007Y464831D01*
X464549Y464956D01*
X464132Y465123D01*
X463674Y465331D01*
X463049Y465664D01*
Y463998D01*
G01X466757Y456448D02*
X466632Y456198D01*
X466549Y455906D01*
Y455573D01*
X466674Y455198D01*
X466882Y454906D01*
X467132Y454698D01*
X467549Y454531D01*
X467924Y454489D01*
X468299Y454573D01*
X468549Y454698D01*
X468799Y454948D01*
X468966Y455239D01*
X469049Y455531D01*
Y455823D01*
X468966Y456114D01*
X468841Y456364D01*
X468674Y456573D01*
G01X468549Y457714D02*
X468841Y457964D01*
X469007Y458298D01*
X469049Y458673D01*
X469007Y459006D01*
X468799Y459339D01*
X468549Y459548D01*
X468299Y459589D01*
X468007Y459506D01*
X467799Y459214D01*
X467716Y458923D01*
Y458548D01*
G01Y458923D02*
X467591Y459173D01*
X467382Y459381D01*
X467132Y459464D01*
X466882Y459381D01*
X466674Y459173D01*
X466549Y458798D01*
X466591Y458423D01*
X466757Y458048D01*
G01X469049Y461731D02*
X469007Y462023D01*
X468882Y462356D01*
X468674Y462564D01*
X468382Y462648D01*
X468091Y462564D01*
X467841Y462314D01*
X467716Y461939D01*
Y461523D01*
X467632Y461273D01*
X467424Y461064D01*
X467132Y460981D01*
X466841Y461106D01*
X466632Y461398D01*
X466549Y461731D01*
X466632Y462064D01*
X466841Y462356D01*
X467132Y462481D01*
X467424Y462398D01*
X467632Y462189D01*
X467716Y461939D01*
Y461523D01*
X467841Y461148D01*
X468091Y460898D01*
X468382Y460814D01*
X468674Y460898D01*
X468882Y461106D01*
X469007Y461439D01*
X469049Y461731D01*
G01X468007Y464039D02*
X467716Y464331D01*
X467549Y464581D01*
X467466Y464914D01*
X467549Y465206D01*
X467716Y465414D01*
X467966Y465581D01*
X468257Y465623D01*
X468507Y465581D01*
X468757Y465414D01*
X468966Y465164D01*
X469049Y464873D01*
X468966Y464539D01*
X468716Y464248D01*
X468341Y464081D01*
X467924Y464039D01*
X467382Y464123D01*
X467091Y464248D01*
X466799Y464456D01*
X466591Y464748D01*
X466549Y465039D01*
X466632Y465331D01*
X466841Y465539D01*
G01X446257Y456448D02*
X446132Y456198D01*
X446049Y455906D01*
Y455573D01*
X446174Y455198D01*
X446382Y454906D01*
X446632Y454698D01*
X447049Y454531D01*
X447424Y454489D01*
X447799Y454573D01*
X448049Y454698D01*
X448299Y454948D01*
X448466Y455239D01*
X448549Y455531D01*
Y455823D01*
X448466Y456114D01*
X448341Y456364D01*
X448174Y456573D01*
G01X448049Y457714D02*
X448341Y457964D01*
X448507Y458298D01*
X448549Y458673D01*
X448507Y459006D01*
X448299Y459339D01*
X448049Y459548D01*
X447799Y459589D01*
X447507Y459506D01*
X447299Y459214D01*
X447216Y458923D01*
Y458548D01*
G01Y458923D02*
X447091Y459173D01*
X446882Y459381D01*
X446632Y459464D01*
X446382Y459381D01*
X446174Y459173D01*
X446049Y458798D01*
X446091Y458423D01*
X446257Y458048D01*
G01X448549Y461731D02*
X448507Y462023D01*
X448382Y462356D01*
X448174Y462564D01*
X447882Y462648D01*
X447591Y462564D01*
X447341Y462314D01*
X447216Y461939D01*
Y461523D01*
X447132Y461273D01*
X446924Y461064D01*
X446632Y460981D01*
X446341Y461106D01*
X446132Y461398D01*
X446049Y461731D01*
X446132Y462064D01*
X446341Y462356D01*
X446632Y462481D01*
X446924Y462398D01*
X447132Y462189D01*
X447216Y461939D01*
Y461523D01*
X447341Y461148D01*
X447591Y460898D01*
X447882Y460814D01*
X448174Y460898D01*
X448382Y461106D01*
X448507Y461439D01*
X448549Y461731D01*
G01X448174Y463914D02*
X448382Y464164D01*
X448507Y464456D01*
X448549Y464831D01*
X448466Y465206D01*
X448299Y465498D01*
X448007Y465706D01*
X447674Y465748D01*
X447341Y465664D01*
X447132Y465456D01*
X446966Y465164D01*
X446924Y464873D01*
X446966Y464581D01*
X447132Y464206D01*
X446049Y464331D01*
Y465456D01*
G01X449757Y456448D02*
X449632Y456198D01*
X449549Y455906D01*
Y455573D01*
X449674Y455198D01*
X449882Y454906D01*
X450132Y454698D01*
X450549Y454531D01*
X450924Y454489D01*
X451299Y454573D01*
X451549Y454698D01*
X451799Y454948D01*
X451966Y455239D01*
X452049Y455531D01*
Y455823D01*
X451966Y456114D01*
X451841Y456364D01*
X451674Y456573D01*
G01X451549Y457714D02*
X451841Y457964D01*
X452007Y458298D01*
X452049Y458673D01*
X452007Y459006D01*
X451799Y459339D01*
X451549Y459548D01*
X451299Y459589D01*
X451007Y459506D01*
X450799Y459214D01*
X450716Y458923D01*
Y458548D01*
G01Y458923D02*
X450591Y459173D01*
X450382Y459381D01*
X450132Y459464D01*
X449882Y459381D01*
X449674Y459173D01*
X449549Y458798D01*
X449591Y458423D01*
X449757Y458048D01*
G01X452049Y461731D02*
X452007Y462023D01*
X451882Y462356D01*
X451674Y462564D01*
X451382Y462648D01*
X451091Y462564D01*
X450841Y462314D01*
X450716Y461939D01*
Y461523D01*
X450632Y461273D01*
X450424Y461064D01*
X450132Y460981D01*
X449841Y461106D01*
X449632Y461398D01*
X449549Y461731D01*
X449632Y462064D01*
X449841Y462356D01*
X450132Y462481D01*
X450424Y462398D01*
X450632Y462189D01*
X450716Y461939D01*
Y461523D01*
X450841Y461148D01*
X451091Y460898D01*
X451382Y460814D01*
X451674Y460898D01*
X451882Y461106D01*
X452007Y461439D01*
X452049Y461731D01*
G01Y465331D02*
X449549D01*
X451341Y463789D01*
Y465873D01*
G01X454757Y456448D02*
X454632Y456198D01*
X454549Y455906D01*
Y455573D01*
X454674Y455198D01*
X454882Y454906D01*
X455132Y454698D01*
X455549Y454531D01*
X455924Y454489D01*
X456299Y454573D01*
X456549Y454698D01*
X456799Y454948D01*
X456966Y455239D01*
X457049Y455531D01*
Y455823D01*
X456966Y456114D01*
X456841Y456364D01*
X456674Y456573D01*
G01X456549Y457714D02*
X456841Y457964D01*
X457007Y458298D01*
X457049Y458673D01*
X457007Y459006D01*
X456799Y459339D01*
X456549Y459548D01*
X456299Y459589D01*
X456007Y459506D01*
X455799Y459214D01*
X455716Y458923D01*
Y458548D01*
G01Y458923D02*
X455591Y459173D01*
X455382Y459381D01*
X455132Y459464D01*
X454882Y459381D01*
X454674Y459173D01*
X454549Y458798D01*
X454591Y458423D01*
X454757Y458048D01*
G01X457049Y461731D02*
X457007Y462023D01*
X456882Y462356D01*
X456674Y462564D01*
X456382Y462648D01*
X456091Y462564D01*
X455841Y462314D01*
X455716Y461939D01*
Y461523D01*
X455632Y461273D01*
X455424Y461064D01*
X455132Y460981D01*
X454841Y461106D01*
X454632Y461398D01*
X454549Y461731D01*
X454632Y462064D01*
X454841Y462356D01*
X455132Y462481D01*
X455424Y462398D01*
X455632Y462189D01*
X455716Y461939D01*
Y461523D01*
X455841Y461148D01*
X456091Y460898D01*
X456382Y460814D01*
X456674Y460898D01*
X456882Y461106D01*
X457007Y461439D01*
X457049Y461731D01*
G01Y464831D02*
X454549D01*
X455049Y464331D01*
G01X457049D02*
Y465331D01*
G01X458257Y456448D02*
X458132Y456198D01*
X458049Y455906D01*
Y455573D01*
X458174Y455198D01*
X458382Y454906D01*
X458632Y454698D01*
X459049Y454531D01*
X459424Y454489D01*
X459799Y454573D01*
X460049Y454698D01*
X460299Y454948D01*
X460466Y455239D01*
X460549Y455531D01*
Y455823D01*
X460466Y456114D01*
X460341Y456364D01*
X460174Y456573D01*
G01X460049Y457714D02*
X460341Y457964D01*
X460507Y458298D01*
X460549Y458673D01*
X460507Y459006D01*
X460299Y459339D01*
X460049Y459548D01*
X459799Y459589D01*
X459507Y459506D01*
X459299Y459214D01*
X459216Y458923D01*
Y458548D01*
G01Y458923D02*
X459091Y459173D01*
X458882Y459381D01*
X458632Y459464D01*
X458382Y459381D01*
X458174Y459173D01*
X458049Y458798D01*
X458091Y458423D01*
X458257Y458048D01*
G01X460549Y461731D02*
X460507Y462023D01*
X460382Y462356D01*
X460174Y462564D01*
X459882Y462648D01*
X459591Y462564D01*
X459341Y462314D01*
X459216Y461939D01*
Y461523D01*
X459132Y461273D01*
X458924Y461064D01*
X458632Y460981D01*
X458341Y461106D01*
X458132Y461398D01*
X458049Y461731D01*
X458132Y462064D01*
X458341Y462356D01*
X458632Y462481D01*
X458924Y462398D01*
X459132Y462189D01*
X459216Y461939D01*
Y461523D01*
X459341Y461148D01*
X459591Y460898D01*
X459882Y460814D01*
X460174Y460898D01*
X460382Y461106D01*
X460507Y461439D01*
X460549Y461731D01*
G01X458049Y464831D02*
X458132Y464498D01*
X458341Y464248D01*
X458591Y464081D01*
X458924Y463956D01*
X459299Y463914D01*
X459674Y463956D01*
X460007Y464081D01*
X460257Y464248D01*
X460466Y464498D01*
X460549Y464831D01*
X460466Y465164D01*
X460257Y465414D01*
X460007Y465581D01*
X459674Y465706D01*
X459299Y465748D01*
X458924Y465706D01*
X458591Y465581D01*
X458341Y465414D01*
X458132Y465164D01*
X458049Y464831D01*
G01X467500Y494217D02*
X465000D01*
Y495258D01*
X465125Y495592D01*
X465292Y495800D01*
X465625Y495883D01*
X465958Y495800D01*
X466167Y495550D01*
X466292Y495258D01*
Y494217D01*
G01Y495258D02*
X467500Y495883D01*
G01X467125Y497233D02*
X467333Y497483D01*
X467458Y497775D01*
X467500Y498150D01*
X467417Y498525D01*
X467250Y498817D01*
X466958Y499025D01*
X466625Y499067D01*
X466292Y498983D01*
X466083Y498775D01*
X465917Y498483D01*
X465875Y498192D01*
X465917Y497900D01*
X466083Y497525D01*
X465000Y497650D01*
Y498775D01*
G01X467500Y501250D02*
X465000D01*
X465500Y500750D01*
G01X467500D02*
Y501750D01*
G01X467125Y503433D02*
X467333Y503683D01*
X467458Y503975D01*
X467500Y504350D01*
X467417Y504725D01*
X467250Y505017D01*
X466958Y505225D01*
X466625Y505267D01*
X466292Y505183D01*
X466083Y504975D01*
X465917Y504683D01*
X465875Y504392D01*
X465917Y504100D01*
X466083Y503725D01*
X465000Y503850D01*
Y504975D01*
G01X463200Y507817D02*
X460700D01*
Y508858D01*
X460825Y509192D01*
X460992Y509400D01*
X461325Y509483D01*
X461658Y509400D01*
X461867Y509150D01*
X461992Y508858D01*
Y507817D01*
G01Y508858D02*
X463200Y509483D01*
G01X462158Y510958D02*
X461867Y511250D01*
X461700Y511500D01*
X461617Y511833D01*
X461700Y512125D01*
X461867Y512333D01*
X462117Y512500D01*
X462408Y512542D01*
X462658Y512500D01*
X462908Y512333D01*
X463117Y512083D01*
X463200Y511792D01*
X463117Y511458D01*
X462867Y511167D01*
X462492Y511000D01*
X462075Y510958D01*
X461533Y511042D01*
X461242Y511167D01*
X460950Y511375D01*
X460742Y511667D01*
X460700Y511958D01*
X460783Y512250D01*
X460992Y512458D01*
G01X463200Y514850D02*
X460700D01*
X461200Y514350D01*
G01X463200D02*
Y515350D01*
G01X462700Y517033D02*
X462992Y517283D01*
X463158Y517617D01*
X463200Y517992D01*
X463158Y518325D01*
X462950Y518658D01*
X462700Y518867D01*
X462450Y518908D01*
X462158Y518825D01*
X461950Y518533D01*
X461867Y518242D01*
Y517867D01*
G01Y518242D02*
X461742Y518492D01*
X461533Y518700D01*
X461283Y518783D01*
X461033Y518700D01*
X460825Y518492D01*
X460700Y518117D01*
X460742Y517742D01*
X460908Y517367D01*
G01X463500Y494217D02*
X461000D01*
Y495258D01*
X461125Y495592D01*
X461292Y495800D01*
X461625Y495883D01*
X461958Y495800D01*
X462167Y495550D01*
X462292Y495258D01*
Y494217D01*
G01Y495258D02*
X463500Y495883D01*
G01X463125Y497233D02*
X463333Y497483D01*
X463458Y497775D01*
X463500Y498150D01*
X463417Y498525D01*
X463250Y498817D01*
X462958Y499025D01*
X462625Y499067D01*
X462292Y498983D01*
X462083Y498775D01*
X461917Y498483D01*
X461875Y498192D01*
X461917Y497900D01*
X462083Y497525D01*
X461000Y497650D01*
Y498775D01*
G01X463500Y501250D02*
X463458Y501542D01*
X463333Y501875D01*
X463125Y502083D01*
X462833Y502167D01*
X462542Y502083D01*
X462292Y501833D01*
X462167Y501458D01*
Y501042D01*
X462083Y500792D01*
X461875Y500583D01*
X461583Y500500D01*
X461292Y500625D01*
X461083Y500917D01*
X461000Y501250D01*
X461083Y501583D01*
X461292Y501875D01*
X461583Y502000D01*
X461875Y501917D01*
X462083Y501708D01*
X462167Y501458D01*
Y501042D01*
X462292Y500667D01*
X462542Y500417D01*
X462833Y500333D01*
X463125Y500417D01*
X463333Y500625D01*
X463458Y500958D01*
X463500Y501250D01*
G01X461417Y503558D02*
X461167Y503808D01*
X461042Y504100D01*
X461000Y504433D01*
X461083Y504850D01*
X461292Y505142D01*
X461542Y505225D01*
X461792Y505183D01*
X462000Y505017D01*
X462417Y504183D01*
X462708Y503808D01*
X463125Y503558D01*
X463500Y503475D01*
Y505225D01*
G01X467200Y507817D02*
X464700D01*
Y508858D01*
X464825Y509192D01*
X464992Y509400D01*
X465325Y509483D01*
X465658Y509400D01*
X465867Y509150D01*
X465992Y508858D01*
Y507817D01*
G01Y508858D02*
X467200Y509483D01*
G01X466158Y510958D02*
X465867Y511250D01*
X465700Y511500D01*
X465617Y511833D01*
X465700Y512125D01*
X465867Y512333D01*
X466117Y512500D01*
X466408Y512542D01*
X466658Y512500D01*
X466908Y512333D01*
X467117Y512083D01*
X467200Y511792D01*
X467117Y511458D01*
X466867Y511167D01*
X466492Y511000D01*
X466075Y510958D01*
X465533Y511042D01*
X465242Y511167D01*
X464950Y511375D01*
X464742Y511667D01*
X464700Y511958D01*
X464783Y512250D01*
X464992Y512458D01*
G01X467200Y514850D02*
X464700D01*
X465200Y514350D01*
G01X467200D02*
Y515350D01*
G01Y517950D02*
X464700D01*
X465200Y517450D01*
G01X467200D02*
Y518450D01*
G01X445400Y487817D02*
X442900D01*
Y488858D01*
X443025Y489192D01*
X443192Y489400D01*
X443525Y489483D01*
X443858Y489400D01*
X444067Y489150D01*
X444192Y488858D01*
Y487817D01*
G01Y488858D02*
X445400Y489483D01*
G01X445025Y490833D02*
X445233Y491083D01*
X445358Y491375D01*
X445400Y491750D01*
X445317Y492125D01*
X445150Y492417D01*
X444858Y492625D01*
X444525Y492667D01*
X444192Y492583D01*
X443983Y492375D01*
X443817Y492083D01*
X443775Y491792D01*
X443817Y491500D01*
X443983Y491125D01*
X442900Y491250D01*
Y492375D01*
G01X445108Y494142D02*
X445317Y494433D01*
X445400Y494767D01*
X445317Y495100D01*
X445067Y495392D01*
X444692Y495600D01*
X444317Y495683D01*
X443858D01*
X443483Y495600D01*
X443150Y495392D01*
X442983Y495142D01*
X442900Y494850D01*
X442983Y494517D01*
X443150Y494267D01*
X443400Y494100D01*
X443733Y494017D01*
X444025Y494100D01*
X444317Y494308D01*
X444483Y494558D01*
X444525Y494850D01*
X444442Y495183D01*
X444233Y495433D01*
X443858Y495683D01*
G01X444358Y497158D02*
X444067Y497450D01*
X443900Y497700D01*
X443817Y498033D01*
X443900Y498325D01*
X444067Y498533D01*
X444317Y498700D01*
X444608Y498742D01*
X444858Y498700D01*
X445108Y498533D01*
X445317Y498283D01*
X445400Y497992D01*
X445317Y497658D01*
X445067Y497367D01*
X444692Y497200D01*
X444275Y497158D01*
X443733Y497242D01*
X443442Y497367D01*
X443150Y497575D01*
X442942Y497867D01*
X442900Y498158D01*
X442983Y498450D01*
X443192Y498658D01*
G01X449400Y487817D02*
X446900D01*
Y488858D01*
X447025Y489192D01*
X447192Y489400D01*
X447525Y489483D01*
X447858Y489400D01*
X448067Y489150D01*
X448192Y488858D01*
Y487817D01*
G01Y488858D02*
X449400Y489483D01*
G01X449025Y490833D02*
X449233Y491083D01*
X449358Y491375D01*
X449400Y491750D01*
X449317Y492125D01*
X449150Y492417D01*
X448858Y492625D01*
X448525Y492667D01*
X448192Y492583D01*
X447983Y492375D01*
X447817Y492083D01*
X447775Y491792D01*
X447817Y491500D01*
X447983Y491125D01*
X446900Y491250D01*
Y492375D01*
G01X449108Y494142D02*
X449317Y494433D01*
X449400Y494767D01*
X449317Y495100D01*
X449067Y495392D01*
X448692Y495600D01*
X448317Y495683D01*
X447858D01*
X447483Y495600D01*
X447150Y495392D01*
X446983Y495142D01*
X446900Y494850D01*
X446983Y494517D01*
X447150Y494267D01*
X447400Y494100D01*
X447733Y494017D01*
X448025Y494100D01*
X448317Y494308D01*
X448483Y494558D01*
X448525Y494850D01*
X448442Y495183D01*
X448233Y495433D01*
X447858Y495683D01*
G01X449400Y498450D02*
X446900D01*
X448692Y496908D01*
Y498992D01*
G01X465183Y490500D02*
Y493000D01*
X466017D01*
X466350Y492875D01*
X466600Y492708D01*
X466808Y492458D01*
X466975Y492167D01*
X467017Y491750D01*
X466975Y491333D01*
X466808Y491042D01*
X466600Y490792D01*
X466350Y490625D01*
X466017Y490500D01*
X465183D01*
G01X469200D02*
Y493000D01*
X468700Y492500D01*
G01Y490500D02*
X469700D01*
G01X472300D02*
X472592Y490542D01*
X472925Y490667D01*
X473133Y490875D01*
X473217Y491167D01*
X473133Y491458D01*
X472883Y491708D01*
X472508Y491833D01*
X472092D01*
X471842Y491917D01*
X471633Y492125D01*
X471550Y492417D01*
X471675Y492708D01*
X471967Y492917D01*
X472300Y493000D01*
X472633Y492917D01*
X472925Y492708D01*
X473050Y492417D01*
X472967Y492125D01*
X472758Y491917D01*
X472508Y491833D01*
X472092D01*
X471717Y491708D01*
X471467Y491458D01*
X471383Y491167D01*
X471467Y490875D01*
X471675Y490667D01*
X472008Y490542D01*
X472300Y490500D01*
G01X455283D02*
Y493000D01*
X456117D01*
X456450Y492875D01*
X456700Y492708D01*
X456908Y492458D01*
X457075Y492167D01*
X457117Y491750D01*
X457075Y491333D01*
X456908Y491042D01*
X456700Y490792D01*
X456450Y490625D01*
X456117Y490500D01*
X455283D01*
G01X459300D02*
Y493000D01*
X458800Y492500D01*
G01Y490500D02*
X459800D01*
G01X461608Y491542D02*
X461900Y491833D01*
X462150Y492000D01*
X462483Y492083D01*
X462775Y492000D01*
X462983Y491833D01*
X463150Y491583D01*
X463192Y491292D01*
X463150Y491042D01*
X462983Y490792D01*
X462733Y490583D01*
X462442Y490500D01*
X462108Y490583D01*
X461817Y490833D01*
X461650Y491208D01*
X461608Y491625D01*
X461692Y492167D01*
X461817Y492458D01*
X462025Y492750D01*
X462317Y492958D01*
X462608Y493000D01*
X462900Y492917D01*
X463108Y492708D01*
G01X437583Y483300D02*
Y485800D01*
X438417D01*
X438750Y485675D01*
X439000Y485508D01*
X439208Y485258D01*
X439375Y484967D01*
X439417Y484550D01*
X439375Y484133D01*
X439208Y483842D01*
X439000Y483592D01*
X438750Y483425D01*
X438417Y483300D01*
X437583D01*
G01X441600D02*
Y485800D01*
X441100Y485300D01*
G01Y483300D02*
X442100D01*
G01X443908Y485383D02*
X444158Y485633D01*
X444450Y485758D01*
X444783Y485800D01*
X445200Y485717D01*
X445492Y485508D01*
X445575Y485258D01*
X445533Y485008D01*
X445367Y484800D01*
X444533Y484383D01*
X444158Y484092D01*
X443908Y483675D01*
X443825Y483300D01*
X445575D01*
G01X447783D02*
Y485800D01*
X448617D01*
X448950Y485675D01*
X449200Y485508D01*
X449408Y485258D01*
X449575Y484967D01*
X449617Y484550D01*
X449575Y484133D01*
X449408Y483842D01*
X449200Y483592D01*
X448950Y483425D01*
X448617Y483300D01*
X447783D01*
G01X451800D02*
Y485800D01*
X451300Y485300D01*
G01Y483300D02*
X452300D01*
G01X453983Y483675D02*
X454233Y483467D01*
X454525Y483342D01*
X454900Y483300D01*
X455275Y483383D01*
X455567Y483550D01*
X455775Y483842D01*
X455817Y484175D01*
X455733Y484508D01*
X455525Y484717D01*
X455233Y484883D01*
X454942Y484925D01*
X454650Y484883D01*
X454275Y484717D01*
X454400Y485800D01*
X455525D01*
G01X471158Y803289D02*
X468658D01*
Y804330D01*
X468783Y804664D01*
X468950Y804872D01*
X469283Y804955D01*
X469616Y804872D01*
X469825Y804622D01*
X469950Y804330D01*
Y803289D01*
G01Y804330D02*
X471158Y804955D01*
G01Y807139D02*
X470616Y807222D01*
X470158Y807347D01*
X469741Y807514D01*
X469283Y807722D01*
X468658Y808055D01*
Y806389D01*
G01X470866Y809614D02*
X471075Y809905D01*
X471158Y810239D01*
X471075Y810572D01*
X470825Y810864D01*
X470450Y811072D01*
X470075Y811155D01*
X469616D01*
X469241Y811072D01*
X468908Y810864D01*
X468741Y810614D01*
X468658Y810322D01*
X468741Y809989D01*
X468908Y809739D01*
X469158Y809572D01*
X469491Y809489D01*
X469783Y809572D01*
X470075Y809780D01*
X470241Y810030D01*
X470283Y810322D01*
X470200Y810655D01*
X469991Y810905D01*
X469616Y811155D01*
G01X471158Y813422D02*
X468658D01*
X469158Y812922D01*
G01X471158D02*
Y813922D01*
G01X470116Y815730D02*
X469825Y816022D01*
X469658Y816272D01*
X469575Y816605D01*
X469658Y816897D01*
X469825Y817105D01*
X470075Y817272D01*
X470366Y817314D01*
X470616Y817272D01*
X470866Y817105D01*
X471075Y816855D01*
X471158Y816564D01*
X471075Y816230D01*
X470825Y815939D01*
X470450Y815772D01*
X470033Y815730D01*
X469491Y815814D01*
X469200Y815939D01*
X468908Y816147D01*
X468700Y816439D01*
X468658Y816730D01*
X468741Y817022D01*
X468950Y817230D01*
G01X467158Y803289D02*
X464658D01*
Y804330D01*
X464783Y804664D01*
X464950Y804872D01*
X465283Y804955D01*
X465616Y804872D01*
X465825Y804622D01*
X465950Y804330D01*
Y803289D01*
G01Y804330D02*
X467158Y804955D01*
G01Y807139D02*
X466616Y807222D01*
X466158Y807347D01*
X465741Y807514D01*
X465283Y807722D01*
X464658Y808055D01*
Y806389D01*
G01X466866Y809614D02*
X467075Y809905D01*
X467158Y810239D01*
X467075Y810572D01*
X466825Y810864D01*
X466450Y811072D01*
X466075Y811155D01*
X465616D01*
X465241Y811072D01*
X464908Y810864D01*
X464741Y810614D01*
X464658Y810322D01*
X464741Y809989D01*
X464908Y809739D01*
X465158Y809572D01*
X465491Y809489D01*
X465783Y809572D01*
X466075Y809780D01*
X466241Y810030D01*
X466283Y810322D01*
X466200Y810655D01*
X465991Y810905D01*
X465616Y811155D01*
G01X467158Y813422D02*
X464658D01*
X465158Y812922D01*
G01X467158D02*
Y813922D01*
G01X466783Y815605D02*
X466991Y815855D01*
X467116Y816147D01*
X467158Y816522D01*
X467075Y816897D01*
X466908Y817189D01*
X466616Y817397D01*
X466283Y817439D01*
X465950Y817355D01*
X465741Y817147D01*
X465575Y816855D01*
X465533Y816564D01*
X465575Y816272D01*
X465741Y815897D01*
X464658Y816022D01*
Y817147D01*
G01X460908Y805017D02*
X460783Y804767D01*
X460700Y804475D01*
Y804142D01*
X460825Y803767D01*
X461033Y803475D01*
X461283Y803267D01*
X461700Y803100D01*
X462075Y803058D01*
X462450Y803142D01*
X462700Y803267D01*
X462950Y803517D01*
X463117Y803808D01*
X463200Y804100D01*
Y804392D01*
X463117Y804683D01*
X462992Y804933D01*
X462825Y805142D01*
G01X462700Y806283D02*
X462992Y806533D01*
X463158Y806867D01*
X463200Y807242D01*
X463158Y807575D01*
X462950Y807908D01*
X462700Y808117D01*
X462450Y808158D01*
X462158Y808075D01*
X461950Y807783D01*
X461867Y807492D01*
Y807117D01*
G01Y807492D02*
X461742Y807742D01*
X461533Y807950D01*
X461283Y808033D01*
X461033Y807950D01*
X460825Y807742D01*
X460700Y807367D01*
X460742Y806992D01*
X460908Y806617D01*
G01X461117Y809508D02*
X460867Y809758D01*
X460742Y810050D01*
X460700Y810383D01*
X460783Y810800D01*
X460992Y811092D01*
X461242Y811175D01*
X461492Y811133D01*
X461700Y810967D01*
X462117Y810133D01*
X462408Y809758D01*
X462825Y809508D01*
X463200Y809425D01*
Y811175D01*
G01X460700Y813400D02*
X460783Y813067D01*
X460992Y812817D01*
X461242Y812650D01*
X461575Y812525D01*
X461950Y812483D01*
X462325Y812525D01*
X462658Y812650D01*
X462908Y812817D01*
X463117Y813067D01*
X463200Y813400D01*
X463117Y813733D01*
X462908Y813983D01*
X462658Y814150D01*
X462325Y814275D01*
X461950Y814317D01*
X461575Y814275D01*
X461242Y814150D01*
X460992Y813983D01*
X460783Y813733D01*
X460700Y813400D01*
G01X463200Y816500D02*
X463158Y816792D01*
X463033Y817125D01*
X462825Y817333D01*
X462533Y817417D01*
X462242Y817333D01*
X461992Y817083D01*
X461867Y816708D01*
Y816292D01*
X461783Y816042D01*
X461575Y815833D01*
X461283Y815750D01*
X460992Y815875D01*
X460783Y816167D01*
X460700Y816500D01*
X460783Y816833D01*
X460992Y817125D01*
X461283Y817250D01*
X461575Y817167D01*
X461783Y816958D01*
X461867Y816708D01*
Y816292D01*
X461992Y815917D01*
X462242Y815667D01*
X462533Y815583D01*
X462825Y815667D01*
X463033Y815875D01*
X463158Y816208D01*
X463200Y816500D01*
G01X499888Y5274D02*
X489088D01*
Y10474D01*
X499888D01*
Y5274D01*
G01X477925Y17000D02*
X478258Y16792D01*
X478633Y16667D01*
X478967D01*
X479300Y16792D01*
X479550Y17000D01*
X479675Y17292D01*
X479592Y17584D01*
X479383Y17834D01*
X479008Y18000D01*
X478508Y18084D01*
X478217Y18250D01*
X478092Y18542D01*
X478175Y18834D01*
X478383Y19042D01*
X478675Y19167D01*
X478967D01*
X479258Y19084D01*
X479508Y18875D01*
G01X481067Y16667D02*
Y19167D01*
X482108D01*
X482442Y19042D01*
X482650Y18875D01*
X482733Y18542D01*
X482650Y18209D01*
X482400Y18000D01*
X482108Y17875D01*
X481067D01*
G01X482108D02*
X482733Y16667D01*
G01X484917D02*
X485000Y17209D01*
X485125Y17667D01*
X485292Y18084D01*
X485500Y18542D01*
X485833Y19167D01*
X484167D01*
G01X488100Y16667D02*
Y19167D01*
X487600Y18667D01*
G01Y16667D02*
X488600D01*
G01X491200D02*
Y19167D01*
X490700Y18667D01*
G01Y16667D02*
X491700D01*
G01X481260Y15180D02*
Y11180D01*
X488660D01*
G01X481270Y28720D02*
Y24720D01*
X488670D01*
G01X489967Y15167D02*
Y12667D01*
X491633D01*
G01X494733D02*
X493067D01*
Y15167D01*
X494733D01*
G01X494067Y13959D02*
X493067D01*
G01X496083Y12667D02*
Y15167D01*
X496917D01*
X497250Y15042D01*
X497500Y14875D01*
X497708Y14625D01*
X497875Y14334D01*
X497917Y13917D01*
X497875Y13500D01*
X497708Y13209D01*
X497500Y12959D01*
X497250Y12792D01*
X496917Y12667D01*
X496083D01*
G01X500100D02*
Y15167D01*
X499600Y14667D01*
G01Y12667D02*
X500600D01*
G01X503200D02*
Y15167D01*
X502700Y14667D01*
G01Y12667D02*
X503700D01*
G01X488467Y39167D02*
Y36667D01*
X490133D01*
G01X493233D02*
X491567D01*
Y39167D01*
X493233D01*
G01X492567Y37959D02*
X491567D01*
G01X494583Y36667D02*
Y39167D01*
X495417D01*
X495750Y39042D01*
X496000Y38875D01*
X496208Y38625D01*
X496375Y38334D01*
X496417Y37917D01*
X496375Y37500D01*
X496208Y37209D01*
X496000Y36959D01*
X495750Y36792D01*
X495417Y36667D01*
X494583D01*
G01X498600D02*
Y39167D01*
X498100Y38667D01*
G01Y36667D02*
X499100D01*
G01X501700Y39167D02*
X501367Y39084D01*
X501117Y38875D01*
X500950Y38625D01*
X500825Y38292D01*
X500783Y37917D01*
X500825Y37542D01*
X500950Y37209D01*
X501117Y36959D01*
X501367Y36750D01*
X501700Y36667D01*
X502033Y36750D01*
X502283Y36959D01*
X502450Y37209D01*
X502575Y37542D01*
X502617Y37917D01*
X502575Y38292D01*
X502450Y38625D01*
X502283Y38875D01*
X502033Y39084D01*
X501700Y39167D01*
G01X499888Y28896D02*
X489088D01*
Y34096D01*
X499888D01*
Y28896D01*
G01X481300Y51880D02*
Y47880D01*
X488700D01*
G01X489925Y72000D02*
X490258Y71792D01*
X490633Y71667D01*
X490967D01*
X491300Y71792D01*
X491550Y72000D01*
X491675Y72292D01*
X491592Y72584D01*
X491383Y72834D01*
X491008Y73000D01*
X490508Y73084D01*
X490217Y73250D01*
X490092Y73542D01*
X490175Y73834D01*
X490383Y74042D01*
X490675Y74167D01*
X490967D01*
X491258Y74084D01*
X491508Y73875D01*
G01X493067Y71667D02*
Y74167D01*
X494108D01*
X494442Y74042D01*
X494650Y73875D01*
X494733Y73542D01*
X494650Y73209D01*
X494400Y73000D01*
X494108Y72875D01*
X493067D01*
G01X494108D02*
X494733Y71667D01*
G01X496917D02*
X497000Y72209D01*
X497125Y72667D01*
X497292Y73084D01*
X497500Y73542D01*
X497833Y74167D01*
X496167D01*
G01X500100D02*
X499767Y74084D01*
X499517Y73875D01*
X499350Y73625D01*
X499225Y73292D01*
X499183Y72917D01*
X499225Y72542D01*
X499350Y72209D01*
X499517Y71959D01*
X499767Y71750D01*
X500100Y71667D01*
X500433Y71750D01*
X500683Y71959D01*
X500850Y72209D01*
X500975Y72542D01*
X501017Y72917D01*
X500975Y73292D01*
X500850Y73625D01*
X500683Y73875D01*
X500433Y74084D01*
X500100Y74167D01*
G01X503200Y71667D02*
X503492Y71709D01*
X503825Y71834D01*
X504033Y72042D01*
X504117Y72334D01*
X504033Y72625D01*
X503783Y72875D01*
X503408Y73000D01*
X502992D01*
X502742Y73084D01*
X502533Y73292D01*
X502450Y73584D01*
X502575Y73875D01*
X502867Y74084D01*
X503200Y74167D01*
X503533Y74084D01*
X503825Y73875D01*
X503950Y73584D01*
X503867Y73292D01*
X503658Y73084D01*
X503408Y73000D01*
X502992D01*
X502617Y72875D01*
X502367Y72625D01*
X502283Y72334D01*
X502367Y72042D01*
X502575Y71834D01*
X502908Y71709D01*
X503200Y71667D01*
G01X481300Y75380D02*
Y71380D01*
X488700D01*
G01X476400Y63500D02*
X480400D01*
Y70900D01*
G01X476400D02*
X472400D01*
Y63500D01*
G01X488017Y62167D02*
Y59667D01*
X489683D01*
G01X492783D02*
X491117D01*
Y62167D01*
X492783D01*
G01X492117Y60959D02*
X491117D01*
G01X494133Y59667D02*
Y62167D01*
X494967D01*
X495300Y62042D01*
X495550Y61875D01*
X495758Y61625D01*
X495925Y61334D01*
X495967Y60917D01*
X495925Y60500D01*
X495758Y60209D01*
X495550Y59959D01*
X495300Y59792D01*
X494967Y59667D01*
X494133D01*
G01X497442Y59959D02*
X497733Y59750D01*
X498067Y59667D01*
X498400Y59750D01*
X498692Y60000D01*
X498900Y60375D01*
X498983Y60750D01*
Y61209D01*
X498900Y61584D01*
X498692Y61917D01*
X498442Y62084D01*
X498150Y62167D01*
X497817Y62084D01*
X497567Y61917D01*
X497400Y61667D01*
X497317Y61334D01*
X497400Y61042D01*
X497608Y60750D01*
X497858Y60584D01*
X498150Y60542D01*
X498483Y60625D01*
X498733Y60834D01*
X498983Y61209D01*
G01X499888Y52518D02*
X489088D01*
Y57718D01*
X499888D01*
Y52518D01*
G01X489517Y86167D02*
Y83667D01*
X491183D01*
G01X494283D02*
X492617D01*
Y86167D01*
X494283D01*
G01X493617Y84959D02*
X492617D01*
G01X495633Y83667D02*
Y86167D01*
X496467D01*
X496800Y86042D01*
X497050Y85875D01*
X497258Y85625D01*
X497425Y85334D01*
X497467Y84917D01*
X497425Y84500D01*
X497258Y84209D01*
X497050Y83959D01*
X496800Y83792D01*
X496467Y83667D01*
X495633D01*
G01X499650D02*
X499942Y83709D01*
X500275Y83834D01*
X500483Y84042D01*
X500567Y84334D01*
X500483Y84625D01*
X500233Y84875D01*
X499858Y85000D01*
X499442D01*
X499192Y85084D01*
X498983Y85292D01*
X498900Y85584D01*
X499025Y85875D01*
X499317Y86084D01*
X499650Y86167D01*
X499983Y86084D01*
X500275Y85875D01*
X500400Y85584D01*
X500317Y85292D01*
X500108Y85084D01*
X499858Y85000D01*
X499442D01*
X499067Y84875D01*
X498817Y84625D01*
X498733Y84334D01*
X498817Y84042D01*
X499025Y83834D01*
X499358Y83709D01*
X499650Y83667D01*
G01X499888Y76140D02*
X489088D01*
Y81340D01*
X499888D01*
Y76140D01*
G01X482334Y93983D02*
X484126D01*
X484501Y94150D01*
X484751Y94483D01*
X484834Y94900D01*
X484751Y95317D01*
X484501Y95650D01*
X484126Y95817D01*
X482334D01*
G01X484459Y97083D02*
X484667Y97333D01*
X484792Y97625D01*
X484834Y98000D01*
X484751Y98375D01*
X484584Y98667D01*
X484292Y98875D01*
X483959Y98917D01*
X483626Y98833D01*
X483417Y98625D01*
X483251Y98333D01*
X483209Y98042D01*
X483251Y97750D01*
X483417Y97375D01*
X482334Y97500D01*
Y98625D01*
G01X484834Y101600D02*
X482334D01*
X484126Y100058D01*
Y102142D01*
G01X479700Y102700D02*
Y88700D01*
G01X501100Y122800D02*
X493400D01*
Y137100D01*
X493900D01*
G01D02*
X501000D01*
G01X502232Y128548D02*
Y132548D01*
X494832D01*
G01X506248Y135950D02*
X502248D01*
Y128550D01*
G01X502238Y135950D02*
X498238D01*
Y128550D01*
G01X486834Y128517D02*
X484334D01*
Y129558D01*
X484459Y129892D01*
X484626Y130100D01*
X484959Y130183D01*
X485292Y130100D01*
X485501Y129850D01*
X485626Y129558D01*
Y128517D01*
G01Y129558D02*
X486834Y130183D01*
G01X485792Y131658D02*
X485501Y131950D01*
X485334Y132200D01*
X485251Y132533D01*
X485334Y132825D01*
X485501Y133033D01*
X485751Y133200D01*
X486042Y133242D01*
X486292Y133200D01*
X486542Y133033D01*
X486751Y132783D01*
X486834Y132492D01*
X486751Y132158D01*
X486501Y131867D01*
X486126Y131700D01*
X485709Y131658D01*
X485167Y131742D01*
X484876Y131867D01*
X484584Y132075D01*
X484376Y132367D01*
X484334Y132658D01*
X484417Y132950D01*
X484626Y133158D01*
G01X486834Y135550D02*
X484334D01*
X484834Y135050D01*
G01X486834D02*
Y136050D01*
G01X486542Y137942D02*
X486751Y138233D01*
X486834Y138567D01*
X486751Y138900D01*
X486501Y139192D01*
X486126Y139400D01*
X485751Y139483D01*
X485292D01*
X484917Y139400D01*
X484584Y139192D01*
X484417Y138942D01*
X484334Y138650D01*
X484417Y138317D01*
X484584Y138067D01*
X484834Y137900D01*
X485167Y137817D01*
X485459Y137900D01*
X485751Y138108D01*
X485917Y138358D01*
X485959Y138650D01*
X485876Y138983D01*
X485667Y139233D01*
X485292Y139483D01*
G01X478881Y134614D02*
X482881D01*
Y142014D01*
G01X502242Y132547D02*
Y128547D01*
X509642D01*
G01X484834Y116017D02*
X482334D01*
Y117058D01*
X482459Y117392D01*
X482626Y117600D01*
X482959Y117683D01*
X483292Y117600D01*
X483501Y117350D01*
X483626Y117058D01*
Y116017D01*
G01Y117058D02*
X484834Y117683D01*
G01Y119950D02*
X484792Y120242D01*
X484667Y120575D01*
X484459Y120783D01*
X484167Y120867D01*
X483876Y120783D01*
X483626Y120533D01*
X483501Y120158D01*
Y119742D01*
X483417Y119492D01*
X483209Y119283D01*
X482917Y119200D01*
X482626Y119325D01*
X482417Y119617D01*
X482334Y119950D01*
X482417Y120283D01*
X482626Y120575D01*
X482917Y120700D01*
X483209Y120617D01*
X483417Y120408D01*
X483501Y120158D01*
Y119742D01*
X483626Y119367D01*
X483876Y119117D01*
X484167Y119033D01*
X484459Y119117D01*
X484667Y119325D01*
X484792Y119658D01*
X484834Y119950D01*
G01X482334Y123050D02*
X482417Y122717D01*
X482626Y122467D01*
X482876Y122300D01*
X483209Y122175D01*
X483584Y122133D01*
X483959Y122175D01*
X484292Y122300D01*
X484542Y122467D01*
X484751Y122717D01*
X484834Y123050D01*
X484751Y123383D01*
X484542Y123633D01*
X484292Y123800D01*
X483959Y123925D01*
X483584Y123967D01*
X483209Y123925D01*
X482876Y123800D01*
X482626Y123633D01*
X482417Y123383D01*
X482334Y123050D01*
G01X484459Y125233D02*
X484667Y125483D01*
X484792Y125775D01*
X484834Y126150D01*
X484751Y126525D01*
X484584Y126817D01*
X484292Y127025D01*
X483959Y127067D01*
X483626Y126983D01*
X483417Y126775D01*
X483251Y126483D01*
X483209Y126192D01*
X483251Y125900D01*
X483417Y125525D01*
X482334Y125650D01*
Y126775D01*
G01X480800Y124700D02*
X476800D01*
Y117300D01*
G01X471770Y126582D02*
Y140582D01*
G01X491900Y140166D02*
X491567Y140208D01*
X491275Y140374D01*
X491025Y140624D01*
X490858Y140916D01*
X490775Y141249D01*
Y141583D01*
X490858Y141916D01*
X491025Y142208D01*
X491275Y142458D01*
X491567Y142624D01*
X491900Y142666D01*
X492233Y142624D01*
X492525Y142458D01*
X492775Y142208D01*
X492942Y141916D01*
X493025Y141583D01*
Y141249D01*
X492942Y140916D01*
X492775Y140624D01*
X492525Y140374D01*
X492233Y140208D01*
X491900Y140166D01*
G01X492233Y140833D02*
X492733Y140166D01*
G01X494208Y142249D02*
X494458Y142499D01*
X494750Y142624D01*
X495083Y142666D01*
X495500Y142583D01*
X495792Y142374D01*
X495875Y142124D01*
X495833Y141874D01*
X495667Y141666D01*
X494833Y141249D01*
X494458Y140958D01*
X494208Y140541D01*
X494125Y140166D01*
X495875D01*
G01X497308Y141208D02*
X497600Y141499D01*
X497850Y141666D01*
X498183Y141749D01*
X498475Y141666D01*
X498683Y141499D01*
X498850Y141249D01*
X498892Y140958D01*
X498850Y140708D01*
X498683Y140458D01*
X498433Y140249D01*
X498142Y140166D01*
X497808Y140249D01*
X497517Y140499D01*
X497350Y140874D01*
X497308Y141291D01*
X497392Y141833D01*
X497517Y142124D01*
X497725Y142416D01*
X498017Y142624D01*
X498308Y142666D01*
X498600Y142583D01*
X498808Y142374D01*
G01X504100Y171817D02*
X501600D01*
Y172858D01*
X501725Y173192D01*
X501892Y173400D01*
X502225Y173483D01*
X502558Y173400D01*
X502767Y173150D01*
X502892Y172858D01*
Y171817D01*
G01Y172858D02*
X504100Y173483D01*
G01X503058Y174958D02*
X502767Y175250D01*
X502600Y175500D01*
X502517Y175833D01*
X502600Y176125D01*
X502767Y176333D01*
X503017Y176500D01*
X503308Y176542D01*
X503558Y176500D01*
X503808Y176333D01*
X504017Y176083D01*
X504100Y175792D01*
X504017Y175458D01*
X503767Y175167D01*
X503392Y175000D01*
X502975Y174958D01*
X502433Y175042D01*
X502142Y175167D01*
X501850Y175375D01*
X501642Y175667D01*
X501600Y175958D01*
X501683Y176250D01*
X501892Y176458D01*
G01X502017Y178058D02*
X501767Y178308D01*
X501642Y178600D01*
X501600Y178933D01*
X501683Y179350D01*
X501892Y179642D01*
X502142Y179725D01*
X502392Y179683D01*
X502600Y179517D01*
X503017Y178683D01*
X503308Y178308D01*
X503725Y178058D01*
X504100Y177975D01*
Y179725D01*
G01X503600Y181033D02*
X503892Y181283D01*
X504058Y181617D01*
X504100Y181992D01*
X504058Y182325D01*
X503850Y182658D01*
X503600Y182867D01*
X503350Y182908D01*
X503058Y182825D01*
X502850Y182533D01*
X502767Y182242D01*
Y181867D01*
G01Y182242D02*
X502642Y182492D01*
X502433Y182700D01*
X502183Y182783D01*
X501933Y182700D01*
X501725Y182492D01*
X501600Y182117D01*
X501642Y181742D01*
X501808Y181367D01*
G01X496903Y163192D02*
X500903D01*
Y170592D01*
G01X485917Y168900D02*
Y171400D01*
X486958D01*
X487292Y171275D01*
X487500Y171108D01*
X487583Y170775D01*
X487500Y170442D01*
X487250Y170233D01*
X486958Y170108D01*
X485917D01*
G01X486958D02*
X487583Y168900D01*
G01X489142Y169192D02*
X489433Y168983D01*
X489767Y168900D01*
X490100Y168983D01*
X490392Y169233D01*
X490600Y169608D01*
X490683Y169983D01*
Y170442D01*
X490600Y170817D01*
X490392Y171150D01*
X490142Y171317D01*
X489850Y171400D01*
X489517Y171317D01*
X489267Y171150D01*
X489100Y170900D01*
X489017Y170567D01*
X489100Y170275D01*
X489308Y169983D01*
X489558Y169817D01*
X489850Y169775D01*
X490183Y169858D01*
X490433Y170067D01*
X490683Y170442D01*
G01X492033Y169400D02*
X492283Y169108D01*
X492617Y168942D01*
X492992Y168900D01*
X493325Y168942D01*
X493658Y169150D01*
X493867Y169400D01*
X493908Y169650D01*
X493825Y169942D01*
X493533Y170150D01*
X493242Y170233D01*
X492867D01*
G01X493242D02*
X493492Y170358D01*
X493700Y170567D01*
X493783Y170817D01*
X493700Y171067D01*
X493492Y171275D01*
X493117Y171400D01*
X492742Y171358D01*
X492367Y171192D01*
G01X495258Y170983D02*
X495508Y171233D01*
X495800Y171358D01*
X496133Y171400D01*
X496550Y171317D01*
X496842Y171108D01*
X496925Y170858D01*
X496883Y170608D01*
X496717Y170400D01*
X495883Y169983D01*
X495508Y169692D01*
X495258Y169275D01*
X495175Y168900D01*
X496925D01*
G01X488900Y168000D02*
Y164000D01*
X496300D01*
G01X501903Y162392D02*
X488903D01*
G01D02*
Y148392D01*
G01D02*
X501903D01*
G01D02*
Y162392D01*
G01X484767Y172700D02*
X484975Y172450D01*
X485225Y172283D01*
X485517Y172200D01*
X485850Y172283D01*
X486100Y172450D01*
X486350Y172700D01*
X486433Y173033D01*
Y174700D01*
G01X487867Y172200D02*
Y174700D01*
X488867D01*
X489200Y174575D01*
X489450Y174283D01*
X489533Y173950D01*
X489450Y173617D01*
X489242Y173367D01*
X488867Y173242D01*
X487867D01*
G01X492300Y172200D02*
Y174700D01*
X490758Y172908D01*
X492842D01*
G01X483415Y148115D02*
X483373Y147782D01*
X483207Y147490D01*
X482957Y147240D01*
X482665Y147073D01*
X482332Y146990D01*
X481998D01*
X481665Y147073D01*
X481373Y147240D01*
X481123Y147490D01*
X480957Y147782D01*
X480915Y148115D01*
X480957Y148448D01*
X481123Y148740D01*
X481373Y148990D01*
X481665Y149157D01*
X481998Y149240D01*
X482332D01*
X482665Y149157D01*
X482957Y148990D01*
X483207Y148740D01*
X483373Y148448D01*
X483415Y148115D01*
G01X482748Y148448D02*
X483415Y148948D01*
G01Y151715D02*
X480915D01*
X482707Y150173D01*
Y152257D01*
G01X477364Y172493D02*
G02Y152493I0J-10000D01*
G01X471564D01*
Y172493D01*
X477364D01*
G01X480230Y198887D02*
X477730D01*
X478230Y198387D01*
G01X480230D02*
Y199387D01*
G01X479397Y201445D02*
Y202529D01*
G01X478147Y204295D02*
X477897Y204545D01*
X477772Y204837D01*
X477730Y205170D01*
X477813Y205587D01*
X478022Y205879D01*
X478272Y205962D01*
X478522Y205920D01*
X478730Y205754D01*
X479147Y204920D01*
X479438Y204545D01*
X479855Y204295D01*
X480230Y204212D01*
Y205962D01*
G01X479830Y187654D02*
X480080Y187862D01*
X480247Y188112D01*
X480330Y188404D01*
X480247Y188737D01*
X480080Y188987D01*
X479830Y189237D01*
X479497Y189320D01*
X477830D01*
G01X480330Y190754D02*
X477830D01*
Y191754D01*
X477955Y192087D01*
X478247Y192337D01*
X478580Y192420D01*
X478913Y192337D01*
X479163Y192129D01*
X479288Y191754D01*
Y190754D01*
G01X480330Y195187D02*
X477830D01*
X479622Y193645D01*
Y195729D01*
G01X498937Y206521D02*
X499770D01*
Y205771D01*
X499520Y205521D01*
X499229Y205354D01*
X498812Y205271D01*
X498395Y205354D01*
X498104Y205521D01*
X497854Y205771D01*
X497687Y206063D01*
X497604Y206396D01*
Y206688D01*
X497687Y206938D01*
X497854Y207229D01*
X498104Y207479D01*
X498354Y207646D01*
X498687Y207771D01*
X498979D01*
X499312Y207688D01*
X499562Y207521D01*
G01X500829Y205271D02*
Y207771D01*
X502745Y205271D01*
Y207771D01*
G01X503970Y205271D02*
Y207771D01*
X504804D01*
X505137Y207646D01*
X505387Y207479D01*
X505595Y207229D01*
X505762Y206938D01*
X505804Y206521D01*
X505762Y206104D01*
X505595Y205813D01*
X505387Y205563D01*
X505137Y205396D01*
X504804Y205271D01*
X503970D01*
G01X473303Y178839D02*
X473178Y179006D01*
X472969Y179131D01*
X472678Y179214D01*
X472428Y179131D01*
X472261Y178964D01*
X472136Y178673D01*
Y177548D01*
X474636D01*
Y178923D01*
X474469Y179214D01*
X474219Y179381D01*
X473928Y179464D01*
X473636Y179381D01*
X473386Y179131D01*
X473303Y178839D01*
Y177548D01*
G01X474636Y180523D02*
X472136D01*
X474219Y181606D01*
X472136Y182689D01*
X474636D01*
G01X472344Y185623D02*
X472219Y185373D01*
X472136Y185081D01*
Y184748D01*
X472261Y184373D01*
X472469Y184081D01*
X472719Y183873D01*
X473136Y183706D01*
X473511Y183664D01*
X473886Y183748D01*
X474136Y183873D01*
X474386Y184123D01*
X474553Y184414D01*
X474636Y184706D01*
Y184998D01*
X474553Y185289D01*
X474428Y185539D01*
X474261Y185748D01*
G01X474636Y189864D02*
X472136Y190906D01*
X474636Y191948D01*
G01X473761Y191573D02*
Y190239D01*
G01X474636Y193089D02*
X472136D01*
Y193923D01*
X472261Y194256D01*
X472428Y194506D01*
X472678Y194714D01*
X472969Y194881D01*
X473386Y194923D01*
X473803Y194881D01*
X474094Y194714D01*
X474344Y194506D01*
X474511Y194256D01*
X474636Y193923D01*
Y193089D01*
G01Y196189D02*
X472136D01*
Y197023D01*
X472261Y197356D01*
X472428Y197606D01*
X472678Y197814D01*
X472969Y197981D01*
X473386Y198023D01*
X473803Y197981D01*
X474094Y197814D01*
X474344Y197606D01*
X474511Y197356D01*
X474636Y197023D01*
Y196189D01*
G01Y199373D02*
X472136D01*
Y200414D01*
X472261Y200748D01*
X472428Y200956D01*
X472761Y201039D01*
X473094Y200956D01*
X473303Y200706D01*
X473428Y200414D01*
Y199373D01*
G01Y200414D02*
X474636Y201039D01*
G01Y203306D02*
X472136D01*
X472636Y202806D01*
G01X474636D02*
Y203806D01*
G01X476230Y197147D02*
Y207637D01*
X481730D01*
Y197137D01*
X476240D01*
G02X476230Y197147I0J10D01*
G01X500017Y193100D02*
Y195600D01*
X501058D01*
X501392Y195475D01*
X501600Y195308D01*
X501683Y194975D01*
X501600Y194642D01*
X501350Y194433D01*
X501058Y194308D01*
X500017D01*
G01X501058D02*
X501683Y193100D01*
G01X503867D02*
X503950Y193642D01*
X504075Y194100D01*
X504242Y194517D01*
X504450Y194975D01*
X504783Y195600D01*
X503117D01*
G01X506967Y193100D02*
X507050Y193642D01*
X507175Y194100D01*
X507342Y194517D01*
X507550Y194975D01*
X507883Y195600D01*
X506217D01*
G01X509233Y193600D02*
X509483Y193308D01*
X509817Y193142D01*
X510192Y193100D01*
X510525Y193142D01*
X510858Y193350D01*
X511067Y193600D01*
X511108Y193850D01*
X511025Y194142D01*
X510733Y194350D01*
X510442Y194433D01*
X510067D01*
G01X510442D02*
X510692Y194558D01*
X510900Y194767D01*
X510983Y195017D01*
X510900Y195267D01*
X510692Y195475D01*
X510317Y195600D01*
X509942Y195558D01*
X509567Y195392D01*
G01X499800Y176617D02*
X497300D01*
Y177658D01*
X497425Y177992D01*
X497592Y178200D01*
X497925Y178283D01*
X498258Y178200D01*
X498467Y177950D01*
X498592Y177658D01*
Y176617D01*
G01Y177658D02*
X499800Y178283D01*
G01X498758Y179758D02*
X498467Y180050D01*
X498300Y180300D01*
X498217Y180633D01*
X498300Y180925D01*
X498467Y181133D01*
X498717Y181300D01*
X499008Y181342D01*
X499258Y181300D01*
X499508Y181133D01*
X499717Y180883D01*
X499800Y180592D01*
X499717Y180258D01*
X499467Y179967D01*
X499092Y179800D01*
X498675Y179758D01*
X498133Y179842D01*
X497842Y179967D01*
X497550Y180175D01*
X497342Y180467D01*
X497300Y180758D01*
X497383Y181050D01*
X497592Y181258D01*
G01X497717Y182858D02*
X497467Y183108D01*
X497342Y183400D01*
X497300Y183733D01*
X497383Y184150D01*
X497592Y184442D01*
X497842Y184525D01*
X498092Y184483D01*
X498300Y184317D01*
X498717Y183483D01*
X499008Y183108D01*
X499425Y182858D01*
X499800Y182775D01*
Y184525D01*
G01X497717Y185958D02*
X497467Y186208D01*
X497342Y186500D01*
X497300Y186833D01*
X497383Y187250D01*
X497592Y187542D01*
X497842Y187625D01*
X498092Y187583D01*
X498300Y187417D01*
X498717Y186583D01*
X499008Y186208D01*
X499425Y185958D01*
X499800Y185875D01*
Y187625D01*
G01X479466Y188220D02*
X475466D01*
Y180820D01*
G01X496400Y196500D02*
X500400D01*
Y203900D01*
G01X482562Y206061D02*
Y175461D01*
X494362D01*
Y206061D01*
X482562D01*
G01X493700Y224433D02*
X494233Y224100D01*
X494833Y223900D01*
X495367D01*
X495900Y224100D01*
X496300Y224433D01*
X496500Y224900D01*
X496367Y225367D01*
X496033Y225767D01*
X495433Y226033D01*
X494633Y226167D01*
X494167Y226433D01*
X493967Y226900D01*
X494100Y227367D01*
X494433Y227700D01*
X494900Y227900D01*
X495367D01*
X495833Y227767D01*
X496233Y227433D01*
G01X497700Y227900D02*
X498633Y223900D01*
X499700Y227900D01*
X500767Y223900D01*
X501700Y227900D01*
G01X503500D02*
X505100D01*
G01X504300D02*
Y223900D01*
G01X503500D02*
X505100D01*
G01X508900Y227900D02*
Y223900D01*
G01X507367Y227900D02*
X510433D01*
G01X514967Y227567D02*
X514567Y227767D01*
X514100Y227900D01*
X513567D01*
X512967Y227700D01*
X512500Y227367D01*
X512167Y226967D01*
X511900Y226300D01*
X511833Y225700D01*
X511967Y225100D01*
X512167Y224700D01*
X512567Y224300D01*
X513033Y224033D01*
X513500Y223900D01*
X513967D01*
X514433Y224033D01*
X514833Y224233D01*
X515167Y224500D01*
G01X516700Y223900D02*
Y227900D01*
G01X519500D02*
Y223900D01*
G01Y225900D02*
X516700D01*
G01X525833Y227900D02*
Y225033D01*
X526100Y224433D01*
X526633Y224033D01*
X527300Y223900D01*
X527967Y224033D01*
X528500Y224433D01*
X528767Y225033D01*
Y227900D01*
G01X530233Y223900D02*
X531900Y227900D01*
X533567Y223900D01*
G01X532967Y225300D02*
X530833D01*
G01X535167Y223900D02*
Y227900D01*
X536833D01*
X537367Y227700D01*
X537700Y227433D01*
X537833Y226900D01*
X537700Y226367D01*
X537300Y226033D01*
X536833Y225833D01*
X535167D01*
G01X536833D02*
X537833Y223900D01*
G01X541100Y227900D02*
Y223900D01*
G01X539567Y227900D02*
X542633D01*
G01X499971Y231101D02*
X500388Y231768D01*
X500638Y232518D01*
Y233184D01*
X500388Y233851D01*
X499971Y234351D01*
X499388Y234601D01*
X498805Y234434D01*
X498305Y234018D01*
X497971Y233268D01*
X497805Y232268D01*
X497471Y231684D01*
X496888Y231434D01*
X496305Y231601D01*
X495888Y232018D01*
X495638Y232601D01*
Y233184D01*
X495805Y233768D01*
X496221Y234268D01*
G01X495638Y235951D02*
X500638Y237118D01*
X495638Y238451D01*
X500638Y239784D01*
X495638Y240951D01*
G01Y243051D02*
Y245051D01*
G01Y244051D02*
X500638D01*
G01Y243051D02*
Y245051D01*
G01X495638Y249651D02*
X500638D01*
G01X495638Y247734D02*
Y251568D01*
G01X496055Y257084D02*
X495805Y256584D01*
X495638Y256001D01*
Y255334D01*
X495888Y254584D01*
X496305Y254001D01*
X496805Y253584D01*
X497638Y253251D01*
X498388Y253168D01*
X499138Y253334D01*
X499638Y253584D01*
X500138Y254084D01*
X500471Y254668D01*
X500638Y255251D01*
Y255834D01*
X500471Y256418D01*
X500221Y256918D01*
X499888Y257334D01*
G01X500638Y259101D02*
X495638D01*
G01Y262601D02*
X500638D01*
G01X498138D02*
Y259101D01*
G01X500638Y270468D02*
X495638D01*
Y273634D01*
G01X498055Y272468D02*
Y270468D01*
G01X495638Y275984D02*
X500638D01*
Y279318D01*
G01Y281168D02*
X495638Y283251D01*
X500638Y285334D01*
G01X498888Y284584D02*
Y281918D01*
G01X499971Y287101D02*
X500388Y287768D01*
X500638Y288518D01*
Y289184D01*
X500388Y289851D01*
X499971Y290351D01*
X499388Y290601D01*
X498805Y290434D01*
X498305Y290018D01*
X497971Y289268D01*
X497805Y288268D01*
X497471Y287684D01*
X496888Y287434D01*
X496305Y287601D01*
X495888Y288018D01*
X495638Y288601D01*
Y289184D01*
X495805Y289768D01*
X496221Y290268D01*
G01X500638Y292701D02*
X495638D01*
G01Y296201D02*
X500638D01*
G01X498138D02*
Y292701D01*
G01X495742Y209594D02*
X537742D01*
Y221594D01*
X495742D01*
Y209594D01*
G01X494102Y256745D02*
Y253745D01*
G01X473681Y311912D02*
X469681D01*
Y304512D01*
G01X475469Y318783D02*
X486019D01*
Y314583D01*
X489469D01*
Y309583D01*
X486019D01*
Y305383D01*
X475469D01*
Y318783D01*
G01X478689Y320210D02*
X473189D01*
G01X478689D02*
Y328210D01*
X473189D01*
G01X502380Y315445D02*
Y317945D01*
X503421D01*
X503755Y317820D01*
X503963Y317653D01*
X504046Y317320D01*
X503963Y316987D01*
X503713Y316778D01*
X503421Y316653D01*
X502380D01*
G01X503421D02*
X504046Y315445D01*
G01X506313D02*
Y317945D01*
X505813Y317445D01*
G01Y315445D02*
X506813D01*
G01X509413D02*
X509705Y315487D01*
X510038Y315612D01*
X510246Y315820D01*
X510330Y316112D01*
X510246Y316403D01*
X509996Y316653D01*
X509621Y316778D01*
X509205D01*
X508955Y316862D01*
X508746Y317070D01*
X508663Y317362D01*
X508788Y317653D01*
X509080Y317862D01*
X509413Y317945D01*
X509746Y317862D01*
X510038Y317653D01*
X510163Y317362D01*
X510080Y317070D01*
X509871Y316862D01*
X509621Y316778D01*
X509205D01*
X508830Y316653D01*
X508580Y316403D01*
X508496Y316112D01*
X508580Y315820D01*
X508788Y315612D01*
X509121Y315487D01*
X509413Y315445D01*
G01X513013D02*
Y317945D01*
X511471Y316153D01*
X513555D01*
G01X515613Y315445D02*
X515905Y315487D01*
X516238Y315612D01*
X516446Y315820D01*
X516530Y316112D01*
X516446Y316403D01*
X516196Y316653D01*
X515821Y316778D01*
X515405D01*
X515155Y316862D01*
X514946Y317070D01*
X514863Y317362D01*
X514988Y317653D01*
X515280Y317862D01*
X515613Y317945D01*
X515946Y317862D01*
X516238Y317653D01*
X516363Y317362D01*
X516280Y317070D01*
X516071Y316862D01*
X515821Y316778D01*
X515405D01*
X515030Y316653D01*
X514780Y316403D01*
X514696Y316112D01*
X514780Y315820D01*
X514988Y315612D01*
X515321Y315487D01*
X515613Y315445D01*
G01X477200Y342817D02*
X474700D01*
Y343858D01*
X474825Y344192D01*
X474992Y344400D01*
X475325Y344483D01*
X475658Y344400D01*
X475867Y344150D01*
X475992Y343858D01*
Y342817D01*
G01Y343858D02*
X477200Y344483D01*
G01Y346750D02*
X477158Y347042D01*
X477033Y347375D01*
X476825Y347583D01*
X476533Y347667D01*
X476242Y347583D01*
X475992Y347333D01*
X475867Y346958D01*
Y346542D01*
X475783Y346292D01*
X475575Y346083D01*
X475283Y346000D01*
X474992Y346125D01*
X474783Y346417D01*
X474700Y346750D01*
X474783Y347083D01*
X474992Y347375D01*
X475283Y347500D01*
X475575Y347417D01*
X475783Y347208D01*
X475867Y346958D01*
Y346542D01*
X475992Y346167D01*
X476242Y345917D01*
X476533Y345833D01*
X476825Y345917D01*
X477033Y346125D01*
X477158Y346458D01*
X477200Y346750D01*
G01X476158Y349058D02*
X475867Y349350D01*
X475700Y349600D01*
X475617Y349933D01*
X475700Y350225D01*
X475867Y350433D01*
X476117Y350600D01*
X476408Y350642D01*
X476658Y350600D01*
X476908Y350433D01*
X477117Y350183D01*
X477200Y349892D01*
X477117Y349558D01*
X476867Y349267D01*
X476492Y349100D01*
X476075Y349058D01*
X475533Y349142D01*
X475242Y349267D01*
X474950Y349475D01*
X474742Y349767D01*
X474700Y350058D01*
X474783Y350350D01*
X474992Y350558D01*
G01X476700Y352033D02*
X476992Y352283D01*
X477158Y352617D01*
X477200Y352992D01*
X477158Y353325D01*
X476950Y353658D01*
X476700Y353867D01*
X476450Y353908D01*
X476158Y353825D01*
X475950Y353533D01*
X475867Y353242D01*
Y352867D01*
G01Y353242D02*
X475742Y353492D01*
X475533Y353700D01*
X475283Y353783D01*
X475033Y353700D01*
X474825Y353492D01*
X474700Y353117D01*
X474742Y352742D01*
X474908Y352367D01*
G01X481700Y342817D02*
X479200D01*
Y343858D01*
X479325Y344192D01*
X479492Y344400D01*
X479825Y344483D01*
X480158Y344400D01*
X480367Y344150D01*
X480492Y343858D01*
Y342817D01*
G01Y343858D02*
X481700Y344483D01*
G01Y346750D02*
X481658Y347042D01*
X481533Y347375D01*
X481325Y347583D01*
X481033Y347667D01*
X480742Y347583D01*
X480492Y347333D01*
X480367Y346958D01*
Y346542D01*
X480283Y346292D01*
X480075Y346083D01*
X479783Y346000D01*
X479492Y346125D01*
X479283Y346417D01*
X479200Y346750D01*
X479283Y347083D01*
X479492Y347375D01*
X479783Y347500D01*
X480075Y347417D01*
X480283Y347208D01*
X480367Y346958D01*
Y346542D01*
X480492Y346167D01*
X480742Y345917D01*
X481033Y345833D01*
X481325Y345917D01*
X481533Y346125D01*
X481658Y346458D01*
X481700Y346750D01*
G01X480658Y349058D02*
X480367Y349350D01*
X480200Y349600D01*
X480117Y349933D01*
X480200Y350225D01*
X480367Y350433D01*
X480617Y350600D01*
X480908Y350642D01*
X481158Y350600D01*
X481408Y350433D01*
X481617Y350183D01*
X481700Y349892D01*
X481617Y349558D01*
X481367Y349267D01*
X480992Y349100D01*
X480575Y349058D01*
X480033Y349142D01*
X479742Y349267D01*
X479450Y349475D01*
X479242Y349767D01*
X479200Y350058D01*
X479283Y350350D01*
X479492Y350558D01*
G01X481700Y352950D02*
X479200D01*
X479700Y352450D01*
G01X481700D02*
Y353450D01*
G01X486209Y337041D02*
Y341041D01*
X478809D01*
G01X486209Y332041D02*
Y336041D01*
X478809D01*
G01X500483Y345666D02*
Y343874D01*
X500650Y343499D01*
X500983Y343249D01*
X501400Y343166D01*
X501817Y343249D01*
X502150Y343499D01*
X502317Y343874D01*
Y345666D01*
G01X505000Y343166D02*
Y345666D01*
X503458Y343874D01*
X505542D01*
G01X506683Y343666D02*
X506933Y343374D01*
X507267Y343208D01*
X507642Y343166D01*
X507975Y343208D01*
X508308Y343416D01*
X508517Y343666D01*
X508558Y343916D01*
X508475Y344208D01*
X508183Y344416D01*
X507892Y344499D01*
X507517D01*
G01X507892D02*
X508142Y344624D01*
X508350Y344833D01*
X508433Y345083D01*
X508350Y345333D01*
X508142Y345541D01*
X507767Y345666D01*
X507392Y345624D01*
X507017Y345458D01*
G01X501909Y320841D02*
X503709Y322941D01*
X505909Y320841D01*
G01X509509Y320741D02*
Y339941D01*
X498309D01*
Y320741D01*
X509509D01*
Y321141D01*
G01X490483Y366166D02*
Y364374D01*
X490650Y363999D01*
X490983Y363749D01*
X491400Y363666D01*
X491817Y363749D01*
X492150Y363999D01*
X492317Y364374D01*
Y366166D01*
G01X493708Y365749D02*
X493958Y365999D01*
X494250Y366124D01*
X494583Y366166D01*
X495000Y366083D01*
X495292Y365874D01*
X495375Y365624D01*
X495333Y365374D01*
X495167Y365166D01*
X494333Y364749D01*
X493958Y364458D01*
X493708Y364041D01*
X493625Y363666D01*
X495375D01*
G01X498100D02*
Y366166D01*
X496558Y364374D01*
X498642D01*
G01X478200Y372300D02*
X479800Y370700D01*
G01X478200Y372300D02*
X476600Y370700D01*
G01X482200D02*
X474200D01*
G01D02*
Y382600D01*
G01X482200D02*
Y370700D01*
G01X484767Y355459D02*
X484517Y355584D01*
X484225Y355667D01*
X483892D01*
X483517Y355542D01*
X483225Y355334D01*
X483017Y355084D01*
X482850Y354667D01*
X482808Y354292D01*
X482892Y353917D01*
X483017Y353667D01*
X483267Y353417D01*
X483558Y353250D01*
X483850Y353167D01*
X484142D01*
X484433Y353250D01*
X484683Y353375D01*
X484892Y353542D01*
G01X486158Y355250D02*
X486408Y355500D01*
X486700Y355625D01*
X487033Y355667D01*
X487450Y355584D01*
X487742Y355375D01*
X487825Y355125D01*
X487783Y354875D01*
X487617Y354667D01*
X486783Y354250D01*
X486408Y353959D01*
X486158Y353542D01*
X486075Y353167D01*
X487825D01*
G01X490550D02*
Y355667D01*
X489008Y353875D01*
X491092D01*
G01X492358Y354209D02*
X492650Y354500D01*
X492900Y354667D01*
X493233Y354750D01*
X493525Y354667D01*
X493733Y354500D01*
X493900Y354250D01*
X493942Y353959D01*
X493900Y353709D01*
X493733Y353459D01*
X493483Y353250D01*
X493192Y353167D01*
X492858Y353250D01*
X492567Y353500D01*
X492400Y353875D01*
X492358Y354292D01*
X492442Y354834D01*
X492567Y355125D01*
X492775Y355417D01*
X493067Y355625D01*
X493358Y355667D01*
X493650Y355584D01*
X493858Y355375D01*
G01X478200Y365000D02*
X474200D01*
Y357600D01*
G01X478700D02*
X482700D01*
Y365000D01*
G01X499334Y369517D02*
X496834D01*
Y370558D01*
X496959Y370892D01*
X497126Y371100D01*
X497459Y371183D01*
X497792Y371100D01*
X498001Y370850D01*
X498126Y370558D01*
Y369517D01*
G01Y370558D02*
X499334Y371183D01*
G01Y373950D02*
X496834D01*
X498626Y372408D01*
Y374492D01*
G01X497251Y375758D02*
X497001Y376008D01*
X496876Y376300D01*
X496834Y376633D01*
X496917Y377050D01*
X497126Y377342D01*
X497376Y377425D01*
X497626Y377383D01*
X497834Y377217D01*
X498251Y376383D01*
X498542Y376008D01*
X498959Y375758D01*
X499334Y375675D01*
Y377425D01*
G01Y379650D02*
X499292Y379942D01*
X499167Y380275D01*
X498959Y380483D01*
X498667Y380567D01*
X498376Y380483D01*
X498126Y380233D01*
X498001Y379858D01*
Y379442D01*
X497917Y379192D01*
X497709Y378983D01*
X497417Y378900D01*
X497126Y379025D01*
X496917Y379317D01*
X496834Y379650D01*
X496917Y379983D01*
X497126Y380275D01*
X497417Y380400D01*
X497709Y380317D01*
X497917Y380108D01*
X498001Y379858D01*
Y379442D01*
X498126Y379067D01*
X498376Y378817D01*
X498667Y378733D01*
X498959Y378817D01*
X499167Y379025D01*
X499292Y379358D01*
X499334Y379650D01*
G01X491700Y370600D02*
X495700D01*
Y378000D01*
G01X474200Y382600D02*
X482200D01*
G01X494467Y390092D02*
X494217Y390217D01*
X493925Y390300D01*
X493592D01*
X493217Y390175D01*
X492925Y389967D01*
X492717Y389717D01*
X492550Y389300D01*
X492508Y388925D01*
X492592Y388550D01*
X492717Y388300D01*
X492967Y388050D01*
X493258Y387883D01*
X493550Y387800D01*
X493842D01*
X494133Y387883D01*
X494383Y388008D01*
X494592Y388175D01*
G01X495858Y389883D02*
X496108Y390133D01*
X496400Y390258D01*
X496733Y390300D01*
X497150Y390217D01*
X497442Y390008D01*
X497525Y389758D01*
X497483Y389508D01*
X497317Y389300D01*
X496483Y388883D01*
X496108Y388592D01*
X495858Y388175D01*
X495775Y387800D01*
X497525D01*
G01X500250D02*
Y390300D01*
X498708Y388508D01*
X500792D01*
G01X501933Y388175D02*
X502183Y387967D01*
X502475Y387842D01*
X502850Y387800D01*
X503225Y387883D01*
X503517Y388050D01*
X503725Y388342D01*
X503767Y388675D01*
X503683Y389008D01*
X503475Y389217D01*
X503183Y389383D01*
X502892Y389425D01*
X502600Y389383D01*
X502225Y389217D01*
X502350Y390300D01*
X503475D01*
G01X471000Y395300D02*
Y391300D01*
X478400D01*
G01X491217Y392300D02*
Y394800D01*
X492258D01*
X492592Y394675D01*
X492800Y394508D01*
X492883Y394175D01*
X492800Y393842D01*
X492550Y393633D01*
X492258Y393508D01*
X491217D01*
G01X492258D02*
X492883Y392300D01*
G01X495650D02*
Y394800D01*
X494108Y393008D01*
X496192D01*
G01X497458Y394383D02*
X497708Y394633D01*
X498000Y394758D01*
X498333Y394800D01*
X498750Y394717D01*
X499042Y394508D01*
X499125Y394258D01*
X499083Y394008D01*
X498917Y393800D01*
X498083Y393383D01*
X497708Y393092D01*
X497458Y392675D01*
X497375Y392300D01*
X499125D01*
G01X501267D02*
X501350Y392842D01*
X501475Y393300D01*
X501642Y393717D01*
X501850Y394175D01*
X502183Y394800D01*
X500517D01*
G01X485900Y391300D02*
Y395300D01*
X478500D01*
G01X477200Y407817D02*
X474700D01*
Y408858D01*
X474825Y409192D01*
X474992Y409400D01*
X475325Y409483D01*
X475658Y409400D01*
X475867Y409150D01*
X475992Y408858D01*
Y407817D01*
G01Y408858D02*
X477200Y409483D01*
G01Y411750D02*
X477158Y412042D01*
X477033Y412375D01*
X476825Y412583D01*
X476533Y412667D01*
X476242Y412583D01*
X475992Y412333D01*
X475867Y411958D01*
Y411542D01*
X475783Y411292D01*
X475575Y411083D01*
X475283Y411000D01*
X474992Y411125D01*
X474783Y411417D01*
X474700Y411750D01*
X474783Y412083D01*
X474992Y412375D01*
X475283Y412500D01*
X475575Y412417D01*
X475783Y412208D01*
X475867Y411958D01*
Y411542D01*
X475992Y411167D01*
X476242Y410917D01*
X476533Y410833D01*
X476825Y410917D01*
X477033Y411125D01*
X477158Y411458D01*
X477200Y411750D01*
G01X476158Y414058D02*
X475867Y414350D01*
X475700Y414600D01*
X475617Y414933D01*
X475700Y415225D01*
X475867Y415433D01*
X476117Y415600D01*
X476408Y415642D01*
X476658Y415600D01*
X476908Y415433D01*
X477117Y415183D01*
X477200Y414892D01*
X477117Y414558D01*
X476867Y414267D01*
X476492Y414100D01*
X476075Y414058D01*
X475533Y414142D01*
X475242Y414267D01*
X474950Y414475D01*
X474742Y414767D01*
X474700Y415058D01*
X474783Y415350D01*
X474992Y415558D01*
G01X477200Y418450D02*
X474700D01*
X476492Y416908D01*
Y418992D01*
G01X474200Y395600D02*
X478200D01*
Y403000D01*
G01X481700Y407817D02*
X479200D01*
Y408858D01*
X479325Y409192D01*
X479492Y409400D01*
X479825Y409483D01*
X480158Y409400D01*
X480367Y409150D01*
X480492Y408858D01*
Y407817D01*
G01Y408858D02*
X481700Y409483D01*
G01Y411750D02*
X481658Y412042D01*
X481533Y412375D01*
X481325Y412583D01*
X481033Y412667D01*
X480742Y412583D01*
X480492Y412333D01*
X480367Y411958D01*
Y411542D01*
X480283Y411292D01*
X480075Y411083D01*
X479783Y411000D01*
X479492Y411125D01*
X479283Y411417D01*
X479200Y411750D01*
X479283Y412083D01*
X479492Y412375D01*
X479783Y412500D01*
X480075Y412417D01*
X480283Y412208D01*
X480367Y411958D01*
Y411542D01*
X480492Y411167D01*
X480742Y410917D01*
X481033Y410833D01*
X481325Y410917D01*
X481533Y411125D01*
X481658Y411458D01*
X481700Y411750D01*
G01X480658Y414058D02*
X480367Y414350D01*
X480200Y414600D01*
X480117Y414933D01*
X480200Y415225D01*
X480367Y415433D01*
X480617Y415600D01*
X480908Y415642D01*
X481158Y415600D01*
X481408Y415433D01*
X481617Y415183D01*
X481700Y414892D01*
X481617Y414558D01*
X481367Y414267D01*
X480992Y414100D01*
X480575Y414058D01*
X480033Y414142D01*
X479742Y414267D01*
X479450Y414475D01*
X479242Y414767D01*
X479200Y415058D01*
X479283Y415350D01*
X479492Y415558D01*
G01X479617Y417158D02*
X479367Y417408D01*
X479242Y417700D01*
X479200Y418033D01*
X479283Y418450D01*
X479492Y418742D01*
X479742Y418825D01*
X479992Y418783D01*
X480200Y418617D01*
X480617Y417783D01*
X480908Y417408D01*
X481325Y417158D01*
X481700Y417075D01*
Y418825D01*
G01X482700Y403000D02*
X478700D01*
Y395600D01*
G01X486789Y454368D02*
X484289D01*
Y455409D01*
X484414Y455743D01*
X484581Y455951D01*
X484914Y456034D01*
X485247Y455951D01*
X485456Y455701D01*
X485581Y455409D01*
Y454368D01*
G01Y455409D02*
X486789Y456034D01*
G01X485747Y457509D02*
X485456Y457801D01*
X485289Y458051D01*
X485206Y458384D01*
X485289Y458676D01*
X485456Y458884D01*
X485706Y459051D01*
X485997Y459093D01*
X486247Y459051D01*
X486497Y458884D01*
X486706Y458634D01*
X486789Y458343D01*
X486706Y458009D01*
X486456Y457718D01*
X486081Y457551D01*
X485664Y457509D01*
X485122Y457593D01*
X484831Y457718D01*
X484539Y457926D01*
X484331Y458218D01*
X484289Y458509D01*
X484372Y458801D01*
X484581Y459009D01*
G01X485747Y460609D02*
X485456Y460901D01*
X485289Y461151D01*
X485206Y461484D01*
X485289Y461776D01*
X485456Y461984D01*
X485706Y462151D01*
X485997Y462193D01*
X486247Y462151D01*
X486497Y461984D01*
X486706Y461734D01*
X486789Y461443D01*
X486706Y461109D01*
X486456Y460818D01*
X486081Y460651D01*
X485664Y460609D01*
X485122Y460693D01*
X484831Y460818D01*
X484539Y461026D01*
X484331Y461318D01*
X484289Y461609D01*
X484372Y461901D01*
X484581Y462109D01*
G01X486789Y464501D02*
X486747Y464793D01*
X486622Y465126D01*
X486414Y465334D01*
X486122Y465418D01*
X485831Y465334D01*
X485581Y465084D01*
X485456Y464709D01*
Y464293D01*
X485372Y464043D01*
X485164Y463834D01*
X484872Y463751D01*
X484581Y463876D01*
X484372Y464168D01*
X484289Y464501D01*
X484372Y464834D01*
X484581Y465126D01*
X484872Y465251D01*
X485164Y465168D01*
X485372Y464959D01*
X485456Y464709D01*
Y464293D01*
X485581Y463918D01*
X485831Y463668D01*
X486122Y463584D01*
X486414Y463668D01*
X486622Y463876D01*
X486747Y464209D01*
X486789Y464501D01*
G01X475616Y467387D02*
Y469887D01*
X476657D01*
X476991Y469762D01*
X477199Y469595D01*
X477282Y469262D01*
X477199Y468929D01*
X476949Y468720D01*
X476657Y468595D01*
X475616D01*
G01X476657D02*
X477282Y467387D01*
G01X478757Y469470D02*
X479007Y469720D01*
X479299Y469845D01*
X479632Y469887D01*
X480049Y469804D01*
X480341Y469595D01*
X480424Y469345D01*
X480382Y469095D01*
X480216Y468887D01*
X479382Y468470D01*
X479007Y468179D01*
X478757Y467762D01*
X478674Y467387D01*
X480424D01*
G01X482649D02*
Y469887D01*
X482149Y469387D01*
G01Y467387D02*
X483149D01*
G01X486249D02*
Y469887D01*
X484707Y468095D01*
X486791D01*
G01X490799Y454368D02*
X488299D01*
Y455409D01*
X488424Y455743D01*
X488591Y455951D01*
X488924Y456034D01*
X489257Y455951D01*
X489466Y455701D01*
X489591Y455409D01*
Y454368D01*
G01Y455409D02*
X490799Y456034D01*
G01X489757Y457509D02*
X489466Y457801D01*
X489299Y458051D01*
X489216Y458384D01*
X489299Y458676D01*
X489466Y458884D01*
X489716Y459051D01*
X490007Y459093D01*
X490257Y459051D01*
X490507Y458884D01*
X490716Y458634D01*
X490799Y458343D01*
X490716Y458009D01*
X490466Y457718D01*
X490091Y457551D01*
X489674Y457509D01*
X489132Y457593D01*
X488841Y457718D01*
X488549Y457926D01*
X488341Y458218D01*
X488299Y458509D01*
X488382Y458801D01*
X488591Y459009D01*
G01X490299Y460484D02*
X490591Y460734D01*
X490757Y461068D01*
X490799Y461443D01*
X490757Y461776D01*
X490549Y462109D01*
X490299Y462318D01*
X490049Y462359D01*
X489757Y462276D01*
X489549Y461984D01*
X489466Y461693D01*
Y461318D01*
G01Y461693D02*
X489341Y461943D01*
X489132Y462151D01*
X488882Y462234D01*
X488632Y462151D01*
X488424Y461943D01*
X488299Y461568D01*
X488341Y461193D01*
X488507Y460818D01*
G01X490799Y465001D02*
X488299D01*
X490091Y463459D01*
Y465543D01*
G01X471096Y459171D02*
Y461671D01*
X472137D01*
X472471Y461546D01*
X472679Y461379D01*
X472762Y461046D01*
X472679Y460713D01*
X472429Y460504D01*
X472137Y460379D01*
X471096D01*
G01X472137D02*
X472762Y459171D01*
G01X474237Y461254D02*
X474487Y461504D01*
X474779Y461629D01*
X475112Y461671D01*
X475529Y461588D01*
X475821Y461379D01*
X475904Y461129D01*
X475862Y460879D01*
X475696Y460671D01*
X474862Y460254D01*
X474487Y459963D01*
X474237Y459546D01*
X474154Y459171D01*
X475904D01*
G01X478046D02*
X478129Y459713D01*
X478254Y460171D01*
X478421Y460588D01*
X478629Y461046D01*
X478962Y461671D01*
X477296D01*
G01X481729Y459171D02*
Y461671D01*
X480187Y459879D01*
X482271D01*
G01X471116Y463218D02*
Y465718D01*
X472157D01*
X472491Y465593D01*
X472699Y465426D01*
X472782Y465093D01*
X472699Y464760D01*
X472449Y464551D01*
X472157Y464426D01*
X471116D01*
G01X472157D02*
X472782Y463218D01*
G01X474257Y465301D02*
X474507Y465551D01*
X474799Y465676D01*
X475132Y465718D01*
X475549Y465635D01*
X475841Y465426D01*
X475924Y465176D01*
X475882Y464926D01*
X475716Y464718D01*
X474882Y464301D01*
X474507Y464010D01*
X474257Y463593D01*
X474174Y463218D01*
X475924D01*
G01X478149Y465718D02*
X477816Y465635D01*
X477566Y465426D01*
X477399Y465176D01*
X477274Y464843D01*
X477232Y464468D01*
X477274Y464093D01*
X477399Y463760D01*
X477566Y463510D01*
X477816Y463301D01*
X478149Y463218D01*
X478482Y463301D01*
X478732Y463510D01*
X478899Y463760D01*
X479024Y464093D01*
X479066Y464468D01*
X479024Y464843D01*
X478899Y465176D01*
X478732Y465426D01*
X478482Y465635D01*
X478149Y465718D01*
G01X480457Y464260D02*
X480749Y464551D01*
X480999Y464718D01*
X481332Y464801D01*
X481624Y464718D01*
X481832Y464551D01*
X481999Y464301D01*
X482041Y464010D01*
X481999Y463760D01*
X481832Y463510D01*
X481582Y463301D01*
X481291Y463218D01*
X480957Y463301D01*
X480666Y463551D01*
X480499Y463926D01*
X480457Y464343D01*
X480541Y464885D01*
X480666Y465176D01*
X480874Y465468D01*
X481166Y465676D01*
X481457Y465718D01*
X481749Y465635D01*
X481957Y465426D01*
G01X481933Y446238D02*
X479433D01*
Y447279D01*
X479558Y447613D01*
X479725Y447821D01*
X480058Y447904D01*
X480391Y447821D01*
X480600Y447571D01*
X480725Y447279D01*
Y446238D01*
G01Y447279D02*
X481933Y447904D01*
G01X481433Y449254D02*
X481725Y449504D01*
X481891Y449838D01*
X481933Y450213D01*
X481891Y450546D01*
X481683Y450879D01*
X481433Y451088D01*
X481183Y451129D01*
X480891Y451046D01*
X480683Y450754D01*
X480600Y450463D01*
Y450088D01*
G01Y450463D02*
X480475Y450713D01*
X480266Y450921D01*
X480016Y451004D01*
X479766Y450921D01*
X479558Y450713D01*
X479433Y450338D01*
X479475Y449963D01*
X479641Y449588D01*
G01X479433Y453271D02*
X479516Y452938D01*
X479725Y452688D01*
X479975Y452521D01*
X480308Y452396D01*
X480683Y452354D01*
X481058Y452396D01*
X481391Y452521D01*
X481641Y452688D01*
X481850Y452938D01*
X481933Y453271D01*
X481850Y453604D01*
X481641Y453854D01*
X481391Y454021D01*
X481058Y454146D01*
X480683Y454188D01*
X480308Y454146D01*
X479975Y454021D01*
X479725Y453854D01*
X479516Y453604D01*
X479433Y453271D01*
G01X479850Y455579D02*
X479600Y455829D01*
X479475Y456121D01*
X479433Y456454D01*
X479516Y456871D01*
X479725Y457163D01*
X479975Y457246D01*
X480225Y457204D01*
X480433Y457038D01*
X480850Y456204D01*
X481141Y455829D01*
X481558Y455579D01*
X481933Y455496D01*
Y457246D01*
G01X500307Y455388D02*
X500182Y455138D01*
X500099Y454846D01*
Y454513D01*
X500224Y454138D01*
X500432Y453846D01*
X500682Y453638D01*
X501099Y453471D01*
X501474Y453429D01*
X501849Y453513D01*
X502099Y453638D01*
X502349Y453888D01*
X502516Y454179D01*
X502599Y454471D01*
Y454763D01*
X502516Y455054D01*
X502391Y455304D01*
X502224Y455513D01*
G01X502099Y456654D02*
X502391Y456904D01*
X502557Y457238D01*
X502599Y457613D01*
X502557Y457946D01*
X502349Y458279D01*
X502099Y458488D01*
X501849Y458529D01*
X501557Y458446D01*
X501349Y458154D01*
X501266Y457863D01*
Y457488D01*
G01Y457863D02*
X501141Y458113D01*
X500932Y458321D01*
X500682Y458404D01*
X500432Y458321D01*
X500224Y458113D01*
X500099Y457738D01*
X500141Y457363D01*
X500307Y456988D01*
G01X502307Y459963D02*
X502516Y460254D01*
X502599Y460588D01*
X502516Y460921D01*
X502266Y461213D01*
X501891Y461421D01*
X501516Y461504D01*
X501057D01*
X500682Y461421D01*
X500349Y461213D01*
X500182Y460963D01*
X500099Y460671D01*
X500182Y460338D01*
X500349Y460088D01*
X500599Y459921D01*
X500932Y459838D01*
X501224Y459921D01*
X501516Y460129D01*
X501682Y460379D01*
X501724Y460671D01*
X501641Y461004D01*
X501432Y461254D01*
X501057Y461504D01*
G01X500516Y462979D02*
X500266Y463229D01*
X500141Y463521D01*
X500099Y463854D01*
X500182Y464271D01*
X500391Y464563D01*
X500641Y464646D01*
X500891Y464604D01*
X501099Y464438D01*
X501516Y463604D01*
X501807Y463229D01*
X502224Y462979D01*
X502599Y462896D01*
Y464646D01*
G01X496141Y455888D02*
X496016Y455638D01*
X495933Y455346D01*
Y455013D01*
X496058Y454638D01*
X496266Y454346D01*
X496516Y454138D01*
X496933Y453971D01*
X497308Y453929D01*
X497683Y454013D01*
X497933Y454138D01*
X498183Y454388D01*
X498350Y454679D01*
X498433Y454971D01*
Y455263D01*
X498350Y455554D01*
X498225Y455804D01*
X498058Y456013D01*
G01X497933Y457154D02*
X498225Y457404D01*
X498391Y457738D01*
X498433Y458113D01*
X498391Y458446D01*
X498183Y458779D01*
X497933Y458988D01*
X497683Y459029D01*
X497391Y458946D01*
X497183Y458654D01*
X497100Y458363D01*
Y457988D01*
G01Y458363D02*
X496975Y458613D01*
X496766Y458821D01*
X496516Y458904D01*
X496266Y458821D01*
X496058Y458613D01*
X495933Y458238D01*
X495975Y457863D01*
X496141Y457488D01*
G01X498141Y460463D02*
X498350Y460754D01*
X498433Y461088D01*
X498350Y461421D01*
X498100Y461713D01*
X497725Y461921D01*
X497350Y462004D01*
X496891D01*
X496516Y461921D01*
X496183Y461713D01*
X496016Y461463D01*
X495933Y461171D01*
X496016Y460838D01*
X496183Y460588D01*
X496433Y460421D01*
X496766Y460338D01*
X497058Y460421D01*
X497350Y460629D01*
X497516Y460879D01*
X497558Y461171D01*
X497475Y461504D01*
X497266Y461754D01*
X496891Y462004D01*
G01X498433Y464271D02*
X495933D01*
X496433Y463771D01*
G01X498433D02*
Y464771D01*
G01X492107Y455868D02*
X491982Y455618D01*
X491899Y455326D01*
Y454993D01*
X492024Y454618D01*
X492232Y454326D01*
X492482Y454118D01*
X492899Y453951D01*
X493274Y453909D01*
X493649Y453993D01*
X493899Y454118D01*
X494149Y454368D01*
X494316Y454659D01*
X494399Y454951D01*
Y455243D01*
X494316Y455534D01*
X494191Y455784D01*
X494024Y455993D01*
G01X493899Y457134D02*
X494191Y457384D01*
X494357Y457718D01*
X494399Y458093D01*
X494357Y458426D01*
X494149Y458759D01*
X493899Y458968D01*
X493649Y459009D01*
X493357Y458926D01*
X493149Y458634D01*
X493066Y458343D01*
Y457968D01*
G01Y458343D02*
X492941Y458593D01*
X492732Y458801D01*
X492482Y458884D01*
X492232Y458801D01*
X492024Y458593D01*
X491899Y458218D01*
X491941Y457843D01*
X492107Y457468D01*
G01X494107Y460443D02*
X494316Y460734D01*
X494399Y461068D01*
X494316Y461401D01*
X494066Y461693D01*
X493691Y461901D01*
X493316Y461984D01*
X492857D01*
X492482Y461901D01*
X492149Y461693D01*
X491982Y461443D01*
X491899Y461151D01*
X491982Y460818D01*
X492149Y460568D01*
X492399Y460401D01*
X492732Y460318D01*
X493024Y460401D01*
X493316Y460609D01*
X493482Y460859D01*
X493524Y461151D01*
X493441Y461484D01*
X493232Y461734D01*
X492857Y461984D01*
G01X491899Y464251D02*
X491982Y463918D01*
X492191Y463668D01*
X492441Y463501D01*
X492774Y463376D01*
X493149Y463334D01*
X493524Y463376D01*
X493857Y463501D01*
X494107Y463668D01*
X494316Y463918D01*
X494399Y464251D01*
X494316Y464584D01*
X494107Y464834D01*
X493857Y465001D01*
X493524Y465126D01*
X493149Y465168D01*
X492774Y465126D01*
X492441Y465001D01*
X492191Y464834D01*
X491982Y464584D01*
X491899Y464251D01*
G01X484200Y488117D02*
X481700D01*
Y489158D01*
X481825Y489492D01*
X481992Y489700D01*
X482325Y489783D01*
X482658Y489700D01*
X482867Y489450D01*
X482992Y489158D01*
Y488117D01*
G01Y489158D02*
X484200Y489783D01*
G01X483825Y491133D02*
X484033Y491383D01*
X484158Y491675D01*
X484200Y492050D01*
X484117Y492425D01*
X483950Y492717D01*
X483658Y492925D01*
X483325Y492967D01*
X482992Y492883D01*
X482783Y492675D01*
X482617Y492383D01*
X482575Y492092D01*
X482617Y491800D01*
X482783Y491425D01*
X481700Y491550D01*
Y492675D01*
G01X484200Y495150D02*
X481700D01*
X482200Y494650D01*
G01X484200D02*
Y495650D01*
G01X482117Y497458D02*
X481867Y497708D01*
X481742Y498000D01*
X481700Y498333D01*
X481783Y498750D01*
X481992Y499042D01*
X482242Y499125D01*
X482492Y499083D01*
X482700Y498917D01*
X483117Y498083D01*
X483408Y497708D01*
X483825Y497458D01*
X484200Y497375D01*
Y499125D01*
G01Y501617D02*
X481700D01*
Y502658D01*
X481825Y502992D01*
X481992Y503200D01*
X482325Y503283D01*
X482658Y503200D01*
X482867Y502950D01*
X482992Y502658D01*
Y501617D01*
G01Y502658D02*
X484200Y503283D01*
G01X483158Y504758D02*
X482867Y505050D01*
X482700Y505300D01*
X482617Y505633D01*
X482700Y505925D01*
X482867Y506133D01*
X483117Y506300D01*
X483408Y506342D01*
X483658Y506300D01*
X483908Y506133D01*
X484117Y505883D01*
X484200Y505592D01*
X484117Y505258D01*
X483867Y504967D01*
X483492Y504800D01*
X483075Y504758D01*
X482533Y504842D01*
X482242Y504967D01*
X481950Y505175D01*
X481742Y505467D01*
X481700Y505758D01*
X481783Y506050D01*
X481992Y506258D01*
G01X481700Y508650D02*
X481783Y508317D01*
X481992Y508067D01*
X482242Y507900D01*
X482575Y507775D01*
X482950Y507733D01*
X483325Y507775D01*
X483658Y507900D01*
X483908Y508067D01*
X484117Y508317D01*
X484200Y508650D01*
X484117Y508983D01*
X483908Y509233D01*
X483658Y509400D01*
X483325Y509525D01*
X482950Y509567D01*
X482575Y509525D01*
X482242Y509400D01*
X481992Y509233D01*
X481783Y508983D01*
X481700Y508650D01*
G01X483700Y510833D02*
X483992Y511083D01*
X484158Y511417D01*
X484200Y511792D01*
X484158Y512125D01*
X483950Y512458D01*
X483700Y512667D01*
X483450Y512708D01*
X483158Y512625D01*
X482950Y512333D01*
X482867Y512042D01*
Y511667D01*
G01Y512042D02*
X482742Y512292D01*
X482533Y512500D01*
X482283Y512583D01*
X482033Y512500D01*
X481825Y512292D01*
X481700Y511917D01*
X481742Y511542D01*
X481908Y511167D01*
G01X480200Y488117D02*
X477700D01*
Y489158D01*
X477825Y489492D01*
X477992Y489700D01*
X478325Y489783D01*
X478658Y489700D01*
X478867Y489450D01*
X478992Y489158D01*
Y488117D01*
G01Y489158D02*
X480200Y489783D01*
G01X479825Y491133D02*
X480033Y491383D01*
X480158Y491675D01*
X480200Y492050D01*
X480117Y492425D01*
X479950Y492717D01*
X479658Y492925D01*
X479325Y492967D01*
X478992Y492883D01*
X478783Y492675D01*
X478617Y492383D01*
X478575Y492092D01*
X478617Y491800D01*
X478783Y491425D01*
X477700Y491550D01*
Y492675D01*
G01X479158Y494358D02*
X478867Y494650D01*
X478700Y494900D01*
X478617Y495233D01*
X478700Y495525D01*
X478867Y495733D01*
X479117Y495900D01*
X479408Y495942D01*
X479658Y495900D01*
X479908Y495733D01*
X480117Y495483D01*
X480200Y495192D01*
X480117Y494858D01*
X479867Y494567D01*
X479492Y494400D01*
X479075Y494358D01*
X478533Y494442D01*
X478242Y494567D01*
X477950Y494775D01*
X477742Y495067D01*
X477700Y495358D01*
X477783Y495650D01*
X477992Y495858D01*
G01X477700Y498250D02*
X477783Y497917D01*
X477992Y497667D01*
X478242Y497500D01*
X478575Y497375D01*
X478950Y497333D01*
X479325Y497375D01*
X479658Y497500D01*
X479908Y497667D01*
X480117Y497917D01*
X480200Y498250D01*
X480117Y498583D01*
X479908Y498833D01*
X479658Y499000D01*
X479325Y499125D01*
X478950Y499167D01*
X478575Y499125D01*
X478242Y499000D01*
X477992Y498833D01*
X477783Y498583D01*
X477700Y498250D01*
G01X480200Y501617D02*
X477700D01*
Y502658D01*
X477825Y502992D01*
X477992Y503200D01*
X478325Y503283D01*
X478658Y503200D01*
X478867Y502950D01*
X478992Y502658D01*
Y501617D01*
G01Y502658D02*
X480200Y503283D01*
G01X479158Y504758D02*
X478867Y505050D01*
X478700Y505300D01*
X478617Y505633D01*
X478700Y505925D01*
X478867Y506133D01*
X479117Y506300D01*
X479408Y506342D01*
X479658Y506300D01*
X479908Y506133D01*
X480117Y505883D01*
X480200Y505592D01*
X480117Y505258D01*
X479867Y504967D01*
X479492Y504800D01*
X479075Y504758D01*
X478533Y504842D01*
X478242Y504967D01*
X477950Y505175D01*
X477742Y505467D01*
X477700Y505758D01*
X477783Y506050D01*
X477992Y506258D01*
G01X480200Y508650D02*
X477700D01*
X478200Y508150D01*
G01X480200D02*
Y509150D01*
G01X478117Y510958D02*
X477867Y511208D01*
X477742Y511500D01*
X477700Y511833D01*
X477783Y512250D01*
X477992Y512542D01*
X478242Y512625D01*
X478492Y512583D01*
X478700Y512417D01*
X479117Y511583D01*
X479408Y511208D01*
X479825Y510958D01*
X480200Y510875D01*
Y512625D01*
G01X482583Y482400D02*
Y484900D01*
X483417D01*
X483750Y484775D01*
X484000Y484608D01*
X484208Y484358D01*
X484375Y484067D01*
X484417Y483650D01*
X484375Y483233D01*
X484208Y482942D01*
X484000Y482692D01*
X483750Y482525D01*
X483417Y482400D01*
X482583D01*
G01X486600D02*
Y484900D01*
X486100Y484400D01*
G01Y482400D02*
X487100D01*
G01X488992Y482692D02*
X489283Y482483D01*
X489617Y482400D01*
X489950Y482483D01*
X490242Y482733D01*
X490450Y483108D01*
X490533Y483483D01*
Y483942D01*
X490450Y484317D01*
X490242Y484650D01*
X489992Y484817D01*
X489700Y484900D01*
X489367Y484817D01*
X489117Y484650D01*
X488950Y484400D01*
X488867Y484067D01*
X488950Y483775D01*
X489158Y483483D01*
X489408Y483317D01*
X489700Y483275D01*
X490033Y483358D01*
X490283Y483567D01*
X490533Y483942D01*
G01X472683Y482100D02*
Y484600D01*
X473517D01*
X473850Y484475D01*
X474100Y484308D01*
X474308Y484058D01*
X474475Y483767D01*
X474517Y483350D01*
X474475Y482933D01*
X474308Y482642D01*
X474100Y482392D01*
X473850Y482225D01*
X473517Y482100D01*
X472683D01*
G01X476700D02*
Y484600D01*
X476200Y484100D01*
G01Y482100D02*
X477200D01*
G01X479717D02*
X479800Y482642D01*
X479925Y483100D01*
X480092Y483517D01*
X480300Y483975D01*
X480633Y484600D01*
X478967D01*
G01X505906Y777098D02*
X501906D01*
Y769698D01*
G01Y777098D02*
X497906D01*
Y769698D01*
G01Y777098D02*
X493906D01*
Y769698D01*
G01X485906D02*
X489906D01*
Y777098D01*
G01Y769698D02*
X493906D01*
Y777098D01*
G01X474833Y798800D02*
Y797008D01*
X475000Y796633D01*
X475333Y796383D01*
X475750Y796300D01*
X476167Y796383D01*
X476500Y796633D01*
X476667Y797008D01*
Y798800D01*
G01X478850Y796300D02*
Y798800D01*
X478350Y798300D01*
G01Y796300D02*
X479350D01*
G01X481242Y796592D02*
X481533Y796383D01*
X481867Y796300D01*
X482200Y796383D01*
X482492Y796633D01*
X482700Y797008D01*
X482783Y797383D01*
Y797842D01*
X482700Y798217D01*
X482492Y798550D01*
X482242Y798717D01*
X481950Y798800D01*
X481617Y798717D01*
X481367Y798550D01*
X481200Y798300D01*
X481117Y797967D01*
X481200Y797675D01*
X481408Y797383D01*
X481658Y797217D01*
X481950Y797175D01*
X482283Y797258D01*
X482533Y797467D01*
X482783Y797842D01*
G01X484342Y796592D02*
X484633Y796383D01*
X484967Y796300D01*
X485300Y796383D01*
X485592Y796633D01*
X485800Y797008D01*
X485883Y797383D01*
Y797842D01*
X485800Y798217D01*
X485592Y798550D01*
X485342Y798717D01*
X485050Y798800D01*
X484717Y798717D01*
X484467Y798550D01*
X484300Y798300D01*
X484217Y797967D01*
X484300Y797675D01*
X484508Y797383D01*
X484758Y797217D01*
X485050Y797175D01*
X485383Y797258D01*
X485633Y797467D01*
X485883Y797842D01*
G01X519906Y791398D02*
X489206D01*
G01Y805398D02*
X519906D01*
G01X489206D02*
Y791398D01*
G01X490306Y798398D02*
X489206Y799498D01*
G01X490306Y798398D02*
X489206Y797298D01*
G01X483254Y802941D02*
X480754D01*
Y803982D01*
X480879Y804316D01*
X481046Y804524D01*
X481379Y804607D01*
X481712Y804524D01*
X481921Y804274D01*
X482046Y803982D01*
Y802941D01*
G01Y803982D02*
X483254Y804607D01*
G01Y806791D02*
X482712Y806874D01*
X482254Y806999D01*
X481837Y807166D01*
X481379Y807374D01*
X480754Y807707D01*
Y806041D01*
G01X482962Y809266D02*
X483171Y809557D01*
X483254Y809891D01*
X483171Y810224D01*
X482921Y810516D01*
X482546Y810724D01*
X482171Y810807D01*
X481712D01*
X481337Y810724D01*
X481004Y810516D01*
X480837Y810266D01*
X480754Y809974D01*
X480837Y809641D01*
X481004Y809391D01*
X481254Y809224D01*
X481587Y809141D01*
X481879Y809224D01*
X482171Y809432D01*
X482337Y809682D01*
X482379Y809974D01*
X482296Y810307D01*
X482087Y810557D01*
X481712Y810807D01*
G01X483254Y812991D02*
X482712Y813074D01*
X482254Y813199D01*
X481837Y813366D01*
X481379Y813574D01*
X480754Y813907D01*
Y812241D01*
G01Y816174D02*
X480837Y815841D01*
X481046Y815591D01*
X481296Y815424D01*
X481629Y815299D01*
X482004Y815257D01*
X482379Y815299D01*
X482712Y815424D01*
X482962Y815591D01*
X483171Y815841D01*
X483254Y816174D01*
X483171Y816507D01*
X482962Y816757D01*
X482712Y816924D01*
X482379Y817049D01*
X482004Y817091D01*
X481629Y817049D01*
X481296Y816924D01*
X481046Y816757D01*
X480837Y816507D01*
X480754Y816174D01*
G01X475100Y803417D02*
X472600D01*
Y804458D01*
X472725Y804792D01*
X472892Y805000D01*
X473225Y805083D01*
X473558Y805000D01*
X473767Y804750D01*
X473892Y804458D01*
Y803417D01*
G01Y804458D02*
X475100Y805083D01*
G01X474725Y806433D02*
X474933Y806683D01*
X475058Y806975D01*
X475100Y807350D01*
X475017Y807725D01*
X474850Y808017D01*
X474558Y808225D01*
X474225Y808267D01*
X473892Y808183D01*
X473683Y807975D01*
X473517Y807683D01*
X473475Y807392D01*
X473517Y807100D01*
X473683Y806725D01*
X472600Y806850D01*
Y807975D01*
G01X475100Y810950D02*
X472600D01*
X474392Y809408D01*
Y811492D01*
G01X474808Y812842D02*
X475017Y813133D01*
X475100Y813467D01*
X475017Y813800D01*
X474767Y814092D01*
X474392Y814300D01*
X474017Y814383D01*
X473558D01*
X473183Y814300D01*
X472850Y814092D01*
X472683Y813842D01*
X472600Y813550D01*
X472683Y813217D01*
X472850Y812967D01*
X473100Y812800D01*
X473433Y812717D01*
X473725Y812800D01*
X474017Y813008D01*
X474183Y813258D01*
X474225Y813550D01*
X474142Y813883D01*
X473933Y814133D01*
X473558Y814383D01*
G01X479141Y803116D02*
X476641D01*
Y804157D01*
X476766Y804491D01*
X476933Y804699D01*
X477266Y804782D01*
X477599Y804699D01*
X477808Y804449D01*
X477933Y804157D01*
Y803116D01*
G01Y804157D02*
X479141Y804782D01*
G01X478849Y806341D02*
X479058Y806632D01*
X479141Y806966D01*
X479058Y807299D01*
X478808Y807591D01*
X478433Y807799D01*
X478058Y807882D01*
X477599D01*
X477224Y807799D01*
X476891Y807591D01*
X476724Y807341D01*
X476641Y807049D01*
X476724Y806716D01*
X476891Y806466D01*
X477141Y806299D01*
X477474Y806216D01*
X477766Y806299D01*
X478058Y806507D01*
X478224Y806757D01*
X478266Y807049D01*
X478183Y807382D01*
X477974Y807632D01*
X477599Y807882D01*
G01X476641Y810149D02*
X476724Y809816D01*
X476933Y809566D01*
X477183Y809399D01*
X477516Y809274D01*
X477891Y809232D01*
X478266Y809274D01*
X478599Y809399D01*
X478849Y809566D01*
X479058Y809816D01*
X479141Y810149D01*
X479058Y810482D01*
X478849Y810732D01*
X478599Y810899D01*
X478266Y811024D01*
X477891Y811066D01*
X477516Y811024D01*
X477183Y810899D01*
X476933Y810732D01*
X476724Y810482D01*
X476641Y810149D01*
G01X478641Y812332D02*
X478933Y812582D01*
X479099Y812916D01*
X479141Y813291D01*
X479099Y813624D01*
X478891Y813957D01*
X478641Y814166D01*
X478391Y814207D01*
X478099Y814124D01*
X477891Y813832D01*
X477808Y813541D01*
Y813166D01*
G01Y813541D02*
X477683Y813791D01*
X477474Y813999D01*
X477224Y814082D01*
X476974Y813999D01*
X476766Y813791D01*
X476641Y813416D01*
X476683Y813041D01*
X476849Y812666D01*
G01X478099Y815557D02*
X477808Y815849D01*
X477641Y816099D01*
X477558Y816432D01*
X477641Y816724D01*
X477808Y816932D01*
X478058Y817099D01*
X478349Y817141D01*
X478599Y817099D01*
X478849Y816932D01*
X479058Y816682D01*
X479141Y816391D01*
X479058Y816057D01*
X478808Y815766D01*
X478433Y815599D01*
X478016Y815557D01*
X477474Y815641D01*
X477183Y815766D01*
X476891Y815974D01*
X476683Y816266D01*
X476641Y816557D01*
X476724Y816849D01*
X476933Y817057D01*
G01X502406Y818698D02*
X506406D01*
Y826098D01*
G01X493906D02*
X489906D01*
Y818698D01*
G01Y826098D02*
X485906D01*
Y818698D01*
G01X497978Y826131D02*
X493978D01*
Y818731D01*
G01X498100Y818700D02*
X502100D01*
Y826100D01*
G01X509673Y-43680D02*
Y109220D01*
X692173D01*
Y-43680D01*
X509673D01*
G01X692173Y-19527D02*
X509673D01*
G01X525475Y142000D02*
X527225Y144500D01*
G01X525475D02*
X527225Y142000D01*
G01X529950D02*
Y144500D01*
X528408Y142708D01*
X530492D01*
G01X521100Y110900D02*
X523600Y115900D01*
X526100Y110900D01*
G01X525200Y112650D02*
X522000D01*
G01X519400Y137100D02*
X525000D01*
G01X529200D02*
X533500D01*
G01X536100D02*
X539800D01*
G01X534200Y122800D02*
X528100D01*
G01X524900D02*
X520900D01*
G01X503700Y137100D02*
X516200D01*
G01X517200Y122800D02*
X504000D01*
G01X508100Y142400D02*
X507767Y142442D01*
X507475Y142608D01*
X507225Y142858D01*
X507058Y143150D01*
X506975Y143483D01*
Y143817D01*
X507058Y144150D01*
X507225Y144442D01*
X507475Y144692D01*
X507767Y144858D01*
X508100Y144900D01*
X508433Y144858D01*
X508725Y144692D01*
X508975Y144442D01*
X509142Y144150D01*
X509225Y143817D01*
Y143483D01*
X509142Y143150D01*
X508975Y142858D01*
X508725Y142608D01*
X508433Y142442D01*
X508100Y142400D01*
G01X508433Y143067D02*
X508933Y142400D01*
G01X510408Y144483D02*
X510658Y144733D01*
X510950Y144858D01*
X511283Y144900D01*
X511700Y144817D01*
X511992Y144608D01*
X512075Y144358D01*
X512033Y144108D01*
X511867Y143900D01*
X511033Y143483D01*
X510658Y143192D01*
X510408Y142775D01*
X510325Y142400D01*
X512075D01*
G01X514217D02*
X514300Y142942D01*
X514425Y143400D01*
X514592Y143817D01*
X514800Y144275D01*
X515133Y144900D01*
X513467D01*
G01X525275Y149600D02*
X527025Y152100D01*
G01X525275D02*
X527025Y149600D01*
G01X529250D02*
Y152100D01*
X528750Y151600D01*
G01Y149600D02*
X529750D01*
G01X531558Y150642D02*
X531850Y150933D01*
X532100Y151100D01*
X532433Y151183D01*
X532725Y151100D01*
X532933Y150933D01*
X533100Y150683D01*
X533142Y150392D01*
X533100Y150142D01*
X532933Y149892D01*
X532683Y149683D01*
X532392Y149600D01*
X532058Y149683D01*
X531767Y149933D01*
X531600Y150308D01*
X531558Y150725D01*
X531642Y151267D01*
X531767Y151558D01*
X531975Y151850D01*
X532267Y152058D01*
X532558Y152100D01*
X532850Y152017D01*
X533058Y151808D01*
G01X523267Y153700D02*
Y156200D01*
X524350Y154117D01*
X525433Y156200D01*
Y153700D01*
G01X527450D02*
X527117Y153742D01*
X526825Y153908D01*
X526575Y154158D01*
X526408Y154450D01*
X526325Y154783D01*
Y155117D01*
X526408Y155450D01*
X526575Y155742D01*
X526825Y155992D01*
X527117Y156158D01*
X527450Y156200D01*
X527783Y156158D01*
X528075Y155992D01*
X528325Y155742D01*
X528492Y155450D01*
X528575Y155117D01*
Y154783D01*
X528492Y154450D01*
X528325Y154158D01*
X528075Y153908D01*
X527783Y153742D01*
X527450Y153700D01*
G01X529633D02*
Y156200D01*
X530467D01*
X530800Y156075D01*
X531050Y155908D01*
X531258Y155658D01*
X531425Y155367D01*
X531467Y154950D01*
X531425Y154533D01*
X531258Y154242D01*
X531050Y153992D01*
X530800Y153825D01*
X530467Y153700D01*
X529633D01*
G01X534483D02*
X532817D01*
Y156200D01*
X534483D01*
G01X533817Y154992D02*
X532817D01*
G01X525375Y145800D02*
X527125Y148300D01*
G01X525375D02*
X527125Y145800D01*
G01X529350D02*
X529642Y145842D01*
X529975Y145967D01*
X530183Y146175D01*
X530267Y146467D01*
X530183Y146758D01*
X529933Y147008D01*
X529558Y147133D01*
X529142D01*
X528892Y147217D01*
X528683Y147425D01*
X528600Y147717D01*
X528725Y148008D01*
X529017Y148217D01*
X529350Y148300D01*
X529683Y148217D01*
X529975Y148008D01*
X530100Y147717D01*
X530017Y147425D01*
X529808Y147217D01*
X529558Y147133D01*
X529142D01*
X528767Y147008D01*
X528517Y146758D01*
X528433Y146467D01*
X528517Y146175D01*
X528725Y145967D01*
X529058Y145842D01*
X529350Y145800D01*
G01X532000Y163815D02*
Y167815D01*
X524600D01*
G01X520000Y150817D02*
X517500D01*
Y151858D01*
X517625Y152192D01*
X517792Y152400D01*
X518125Y152483D01*
X518458Y152400D01*
X518667Y152150D01*
X518792Y151858D01*
Y150817D01*
G01Y151858D02*
X520000Y152483D01*
G01Y154667D02*
X519458Y154750D01*
X519000Y154875D01*
X518583Y155042D01*
X518125Y155250D01*
X517500Y155583D01*
Y153917D01*
G01X518958Y157058D02*
X518667Y157350D01*
X518500Y157600D01*
X518417Y157933D01*
X518500Y158225D01*
X518667Y158433D01*
X518917Y158600D01*
X519208Y158642D01*
X519458Y158600D01*
X519708Y158433D01*
X519917Y158183D01*
X520000Y157892D01*
X519917Y157558D01*
X519667Y157267D01*
X519292Y157100D01*
X518875Y157058D01*
X518333Y157142D01*
X518042Y157267D01*
X517750Y157475D01*
X517542Y157767D01*
X517500Y158058D01*
X517583Y158350D01*
X517792Y158558D01*
G01X517917Y160158D02*
X517667Y160408D01*
X517542Y160700D01*
X517500Y161033D01*
X517583Y161450D01*
X517792Y161742D01*
X518042Y161825D01*
X518292Y161783D01*
X518500Y161617D01*
X518917Y160783D01*
X519208Y160408D01*
X519625Y160158D01*
X520000Y160075D01*
Y161825D01*
G01X532000Y155715D02*
Y159715D01*
X524600D01*
G01X532000Y159815D02*
Y163815D01*
X524600D01*
G01X505700Y166100D02*
X509700D01*
Y173500D01*
G01X533012Y161035D02*
Y157035D01*
X540412D01*
G01X532925Y165463D02*
Y161463D01*
X540325D01*
G01X515903Y162392D02*
X502903D01*
G01D02*
Y148392D01*
G01D02*
X515903D01*
G01D02*
Y162392D01*
G01X512100Y169250D02*
X579700D01*
Y198750D01*
X512100D01*
Y169250D01*
G01X510688Y205271D02*
Y207771D01*
X511729D01*
X512063Y207646D01*
X512271Y207479D01*
X512354Y207146D01*
X512271Y206813D01*
X512021Y206604D01*
X511729Y206479D01*
X510688D01*
G01X511729D02*
X512354Y205271D01*
G01X513746D02*
X515496Y207771D01*
G01X513746D02*
X515496Y205271D01*
G01X520383Y207538D02*
Y205038D01*
G01X519425Y207538D02*
X521341D01*
G01X522608Y205038D02*
X524358Y207538D01*
G01X522608D02*
X524358Y205038D01*
G01X527088Y207398D02*
X528130Y204898D01*
X529172Y207398D01*
G01X532147Y207190D02*
X531897Y207315D01*
X531605Y207398D01*
X531272D01*
X530897Y207273D01*
X530605Y207065D01*
X530397Y206815D01*
X530230Y206398D01*
X530188Y206023D01*
X530272Y205648D01*
X530397Y205398D01*
X530647Y205148D01*
X530938Y204981D01*
X531230Y204898D01*
X531522D01*
X531813Y204981D01*
X532063Y205106D01*
X532272Y205273D01*
G01X535247Y207190D02*
X534997Y207315D01*
X534705Y207398D01*
X534372D01*
X533997Y207273D01*
X533705Y207065D01*
X533497Y206815D01*
X533330Y206398D01*
X533288Y206023D01*
X533372Y205648D01*
X533497Y205398D01*
X533747Y205148D01*
X534038Y204981D01*
X534330Y204898D01*
X534622D01*
X534913Y204981D01*
X535163Y205106D01*
X535372Y205273D01*
G01X503100Y188500D02*
Y184500D01*
X510500D01*
G01X505300Y177000D02*
X509300D01*
Y184400D01*
G01X536126Y201072D02*
Y203572D01*
X537167D01*
X537501Y203447D01*
X537709Y203280D01*
X537792Y202947D01*
X537709Y202614D01*
X537459Y202405D01*
X537167Y202280D01*
X536126D01*
G01X537167D02*
X537792Y201072D01*
G01X539351Y201364D02*
X539642Y201155D01*
X539976Y201072D01*
X540309Y201155D01*
X540601Y201405D01*
X540809Y201780D01*
X540892Y202155D01*
Y202614D01*
X540809Y202989D01*
X540601Y203322D01*
X540351Y203489D01*
X540059Y203572D01*
X539726Y203489D01*
X539476Y203322D01*
X539309Y203072D01*
X539226Y202739D01*
X539309Y202447D01*
X539517Y202155D01*
X539767Y201989D01*
X540059Y201947D01*
X540392Y202030D01*
X540642Y202239D01*
X540892Y202614D01*
G01X543659Y201072D02*
Y203572D01*
X542117Y201780D01*
X544201D01*
G01X545342Y201447D02*
X545592Y201239D01*
X545884Y201114D01*
X546259Y201072D01*
X546634Y201155D01*
X546926Y201322D01*
X547134Y201614D01*
X547176Y201947D01*
X547092Y202280D01*
X546884Y202489D01*
X546592Y202655D01*
X546301Y202697D01*
X546009Y202655D01*
X545634Y202489D01*
X545759Y203572D01*
X546884D01*
G01X521109Y200072D02*
Y204072D01*
X513709D01*
G01X522626Y201072D02*
Y203572D01*
X523667D01*
X524001Y203447D01*
X524209Y203280D01*
X524292Y202947D01*
X524209Y202614D01*
X523959Y202405D01*
X523667Y202280D01*
X522626D01*
G01X523667D02*
X524292Y201072D01*
G01X525851Y201364D02*
X526142Y201155D01*
X526476Y201072D01*
X526809Y201155D01*
X527101Y201405D01*
X527309Y201780D01*
X527392Y202155D01*
Y202614D01*
X527309Y202989D01*
X527101Y203322D01*
X526851Y203489D01*
X526559Y203572D01*
X526226Y203489D01*
X525976Y203322D01*
X525809Y203072D01*
X525726Y202739D01*
X525809Y202447D01*
X526017Y202155D01*
X526267Y201989D01*
X526559Y201947D01*
X526892Y202030D01*
X527142Y202239D01*
X527392Y202614D01*
G01X530159Y201072D02*
Y203572D01*
X528617Y201780D01*
X530701D01*
G01X531967Y202114D02*
X532259Y202405D01*
X532509Y202572D01*
X532842Y202655D01*
X533134Y202572D01*
X533342Y202405D01*
X533509Y202155D01*
X533551Y201864D01*
X533509Y201614D01*
X533342Y201364D01*
X533092Y201155D01*
X532801Y201072D01*
X532467Y201155D01*
X532176Y201405D01*
X532009Y201780D01*
X531967Y202197D01*
X532051Y202739D01*
X532176Y203030D01*
X532384Y203322D01*
X532676Y203530D01*
X532967Y203572D01*
X533259Y203489D01*
X533467Y203280D01*
G01X513409Y200172D02*
Y204172D01*
X506009D01*
G01X529232Y231524D02*
X533232D01*
Y238924D01*
G01X511789Y229799D02*
X509289D01*
Y230840D01*
X509414Y231174D01*
X509581Y231382D01*
X509914Y231465D01*
X510247Y231382D01*
X510456Y231132D01*
X510581Y230840D01*
Y229799D01*
G01Y230840D02*
X511789Y231465D01*
G01Y234232D02*
X509289D01*
X511081Y232690D01*
Y234774D01*
G01X511414Y235915D02*
X511622Y236165D01*
X511747Y236457D01*
X511789Y236832D01*
X511706Y237207D01*
X511539Y237499D01*
X511247Y237707D01*
X510914Y237749D01*
X510581Y237665D01*
X510372Y237457D01*
X510206Y237165D01*
X510164Y236874D01*
X510206Y236582D01*
X510372Y236207D01*
X509289Y236332D01*
Y237457D01*
G01X511789Y239932D02*
X511747Y240224D01*
X511622Y240557D01*
X511414Y240765D01*
X511122Y240849D01*
X510831Y240765D01*
X510581Y240515D01*
X510456Y240140D01*
Y239724D01*
X510372Y239474D01*
X510164Y239265D01*
X509872Y239182D01*
X509581Y239307D01*
X509372Y239599D01*
X509289Y239932D01*
X509372Y240265D01*
X509581Y240557D01*
X509872Y240682D01*
X510164Y240599D01*
X510372Y240390D01*
X510456Y240140D01*
Y239724D01*
X510581Y239349D01*
X510831Y239099D01*
X511122Y239015D01*
X511414Y239099D01*
X511622Y239307D01*
X511747Y239640D01*
X511789Y239932D01*
G01X520899Y231537D02*
X524899D01*
Y238937D01*
G01X507889Y229799D02*
X505389D01*
Y230840D01*
X505514Y231174D01*
X505681Y231382D01*
X506014Y231465D01*
X506347Y231382D01*
X506556Y231132D01*
X506681Y230840D01*
Y229799D01*
G01Y230840D02*
X507889Y231465D01*
G01X506847Y232940D02*
X506556Y233232D01*
X506389Y233482D01*
X506306Y233815D01*
X506389Y234107D01*
X506556Y234315D01*
X506806Y234482D01*
X507097Y234524D01*
X507347Y234482D01*
X507597Y234315D01*
X507806Y234065D01*
X507889Y233774D01*
X507806Y233440D01*
X507556Y233149D01*
X507181Y232982D01*
X506764Y232940D01*
X506222Y233024D01*
X505931Y233149D01*
X505639Y233357D01*
X505431Y233649D01*
X505389Y233940D01*
X505472Y234232D01*
X505681Y234440D01*
G01X507889Y236832D02*
X505389D01*
X505889Y236332D01*
G01X507889D02*
Y237332D01*
G01X506847Y239140D02*
X506556Y239432D01*
X506389Y239682D01*
X506306Y240015D01*
X506389Y240307D01*
X506556Y240515D01*
X506806Y240682D01*
X507097Y240724D01*
X507347Y240682D01*
X507597Y240515D01*
X507806Y240265D01*
X507889Y239974D01*
X507806Y239640D01*
X507556Y239349D01*
X507181Y239182D01*
X506764Y239140D01*
X506222Y239224D01*
X505931Y239349D01*
X505639Y239557D01*
X505431Y239849D01*
X505389Y240140D01*
X505472Y240432D01*
X505681Y240640D01*
G01X515599Y231537D02*
X519599D01*
Y238937D01*
G01X525131Y231480D02*
X529131D01*
Y238880D01*
G01X533295Y231558D02*
X537295D01*
Y238958D01*
G01X542976Y287611D02*
Y277787D01*
X548476Y270237D01*
Y259085D01*
X542976Y251535D01*
Y241711D01*
X511076D01*
Y251535D01*
X505576Y259085D01*
Y270237D01*
X511076Y277787D01*
Y287611D01*
X542976D01*
G01X535426Y255361D02*
X515026D01*
G01X535426Y274161D02*
Y255361D01*
G01X517926Y264761D02*
X514326Y261161D01*
G01X517926Y264761D02*
X514326Y268361D01*
G01Y274161D02*
Y246761D01*
G01X535426Y274161D02*
X514326D01*
G01X505626Y267661D02*
X508626Y264661D01*
X505626Y261661D01*
G01X505348Y300535D02*
X505098Y300660D01*
X504806Y300743D01*
X504473D01*
X504098Y300618D01*
X503806Y300410D01*
X503598Y300160D01*
X503431Y299743D01*
X503389Y299368D01*
X503473Y298993D01*
X503598Y298743D01*
X503848Y298493D01*
X504139Y298326D01*
X504431Y298243D01*
X504723D01*
X505014Y298326D01*
X505264Y298451D01*
X505473Y298618D01*
G01X507448Y298243D02*
X507531Y298785D01*
X507656Y299243D01*
X507823Y299660D01*
X508031Y300118D01*
X508364Y300743D01*
X506698D01*
G01X509839Y300326D02*
X510089Y300576D01*
X510381Y300701D01*
X510714Y300743D01*
X511131Y300660D01*
X511423Y300451D01*
X511506Y300201D01*
X511464Y299951D01*
X511298Y299743D01*
X510464Y299326D01*
X510089Y299035D01*
X509839Y298618D01*
X509756Y298243D01*
X511506D01*
G01X512814Y298743D02*
X513064Y298451D01*
X513398Y298285D01*
X513773Y298243D01*
X514106Y298285D01*
X514439Y298493D01*
X514648Y298743D01*
X514689Y298993D01*
X514606Y299285D01*
X514314Y299493D01*
X514023Y299576D01*
X513648D01*
G01X514023D02*
X514273Y299701D01*
X514481Y299910D01*
X514564Y300160D01*
X514481Y300410D01*
X514273Y300618D01*
X513898Y300743D01*
X513523Y300701D01*
X513148Y300535D01*
G01X516698Y298142D02*
Y300642D01*
X517739D01*
X518073Y300517D01*
X518281Y300350D01*
X518364Y300017D01*
X518281Y299684D01*
X518031Y299475D01*
X517739Y299350D01*
X516698D01*
G01X517739D02*
X518364Y298142D01*
G01X519839Y299184D02*
X520131Y299475D01*
X520381Y299642D01*
X520714Y299725D01*
X521006Y299642D01*
X521214Y299475D01*
X521381Y299225D01*
X521423Y298934D01*
X521381Y298684D01*
X521214Y298434D01*
X520964Y298225D01*
X520673Y298142D01*
X520339Y298225D01*
X520048Y298475D01*
X519881Y298850D01*
X519839Y299267D01*
X519923Y299809D01*
X520048Y300100D01*
X520256Y300392D01*
X520548Y300600D01*
X520839Y300642D01*
X521131Y300559D01*
X521339Y300350D01*
G01X522814Y298517D02*
X523064Y298309D01*
X523356Y298184D01*
X523731Y298142D01*
X524106Y298225D01*
X524398Y298392D01*
X524606Y298684D01*
X524648Y299017D01*
X524564Y299350D01*
X524356Y299559D01*
X524064Y299725D01*
X523773Y299767D01*
X523481Y299725D01*
X523106Y299559D01*
X523231Y300642D01*
X524356D01*
G01X526831D02*
X526498Y300559D01*
X526248Y300350D01*
X526081Y300100D01*
X525956Y299767D01*
X525914Y299392D01*
X525956Y299017D01*
X526081Y298684D01*
X526248Y298434D01*
X526498Y298225D01*
X526831Y298142D01*
X527164Y298225D01*
X527414Y298434D01*
X527581Y298684D01*
X527706Y299017D01*
X527748Y299392D01*
X527706Y299767D01*
X527581Y300100D01*
X527414Y300350D01*
X527164Y300559D01*
X526831Y300642D01*
G01X522177Y289240D02*
X526177D01*
Y296640D01*
G01X533397Y302581D02*
X530897D01*
Y303622D01*
X531022Y303956D01*
X531189Y304164D01*
X531522Y304247D01*
X531855Y304164D01*
X532064Y303914D01*
X532189Y303622D01*
Y302581D01*
G01Y303622D02*
X533397Y304247D01*
G01Y307014D02*
X530897D01*
X532689Y305472D01*
Y307556D01*
G01X533397Y310114D02*
X530897D01*
X532689Y308572D01*
Y310656D01*
G01X533397Y312631D02*
X532855Y312714D01*
X532397Y312839D01*
X531980Y313006D01*
X531522Y313214D01*
X530897Y313547D01*
Y311881D01*
G01X530921Y289117D02*
X534921D01*
Y296517D01*
G01X529916Y302505D02*
X527416D01*
Y303546D01*
X527541Y303880D01*
X527708Y304088D01*
X528041Y304171D01*
X528374Y304088D01*
X528583Y303838D01*
X528708Y303546D01*
Y302505D01*
G01Y303546D02*
X529916Y304171D01*
G01X529624Y305730D02*
X529833Y306021D01*
X529916Y306355D01*
X529833Y306688D01*
X529583Y306980D01*
X529208Y307188D01*
X528833Y307271D01*
X528374D01*
X527999Y307188D01*
X527666Y306980D01*
X527499Y306730D01*
X527416Y306438D01*
X527499Y306105D01*
X527666Y305855D01*
X527916Y305688D01*
X528249Y305605D01*
X528541Y305688D01*
X528833Y305896D01*
X528999Y306146D01*
X529041Y306438D01*
X528958Y306771D01*
X528749Y307021D01*
X528374Y307271D01*
G01X529541Y308621D02*
X529749Y308871D01*
X529874Y309163D01*
X529916Y309538D01*
X529833Y309913D01*
X529666Y310205D01*
X529374Y310413D01*
X529041Y310455D01*
X528708Y310371D01*
X528499Y310163D01*
X528333Y309871D01*
X528291Y309580D01*
X528333Y309288D01*
X528499Y308913D01*
X527416Y309038D01*
Y310163D01*
G01X529916Y312555D02*
X529374Y312638D01*
X528916Y312763D01*
X528499Y312930D01*
X528041Y313138D01*
X527416Y313471D01*
Y311805D01*
G01X530709Y296883D02*
X526709D01*
Y289483D01*
G01X534953Y289360D02*
X538953D01*
Y296760D01*
G01X504423Y279943D02*
X504298Y279693D01*
X504215Y279401D01*
Y279068D01*
X504340Y278693D01*
X504548Y278401D01*
X504798Y278193D01*
X505215Y278026D01*
X505590Y277984D01*
X505965Y278068D01*
X506215Y278193D01*
X506465Y278443D01*
X506632Y278734D01*
X506715Y279026D01*
Y279318D01*
X506632Y279609D01*
X506507Y279859D01*
X506340Y280068D01*
G01X506715Y282043D02*
X506173Y282126D01*
X505715Y282251D01*
X505298Y282418D01*
X504840Y282626D01*
X504215Y282959D01*
Y281293D01*
G01X504632Y284434D02*
X504382Y284684D01*
X504257Y284976D01*
X504215Y285309D01*
X504298Y285726D01*
X504507Y286018D01*
X504757Y286101D01*
X505007Y286059D01*
X505215Y285893D01*
X505632Y285059D01*
X505923Y284684D01*
X506340Y284434D01*
X506715Y284351D01*
Y286101D01*
G01Y288826D02*
X504215D01*
X506007Y287284D01*
Y289368D01*
G01X527800Y338500D02*
Y342500D01*
X520400D01*
G01X537359Y335391D02*
Y317691D01*
X528459D01*
Y335391D01*
X537359D01*
G01X518670Y356160D02*
Y358660D01*
X519711D01*
X520045Y358535D01*
X520253Y358368D01*
X520336Y358035D01*
X520253Y357702D01*
X520003Y357493D01*
X519711Y357368D01*
X518670D01*
G01X519711D02*
X520336Y356160D01*
G01X521811Y357202D02*
X522103Y357493D01*
X522353Y357660D01*
X522686Y357743D01*
X522978Y357660D01*
X523186Y357493D01*
X523353Y357243D01*
X523395Y356952D01*
X523353Y356702D01*
X523186Y356452D01*
X522936Y356243D01*
X522645Y356160D01*
X522311Y356243D01*
X522020Y356493D01*
X521853Y356868D01*
X521811Y357285D01*
X521895Y357827D01*
X522020Y358118D01*
X522228Y358410D01*
X522520Y358618D01*
X522811Y358660D01*
X523103Y358577D01*
X523311Y358368D01*
G01X524786Y356535D02*
X525036Y356327D01*
X525328Y356202D01*
X525703Y356160D01*
X526078Y356243D01*
X526370Y356410D01*
X526578Y356702D01*
X526620Y357035D01*
X526536Y357368D01*
X526328Y357577D01*
X526036Y357743D01*
X525745Y357785D01*
X525453Y357743D01*
X525078Y357577D01*
X525203Y358660D01*
X526328D01*
G01X527886Y356535D02*
X528136Y356327D01*
X528428Y356202D01*
X528803Y356160D01*
X529178Y356243D01*
X529470Y356410D01*
X529678Y356702D01*
X529720Y357035D01*
X529636Y357368D01*
X529428Y357577D01*
X529136Y357743D01*
X528845Y357785D01*
X528553Y357743D01*
X528178Y357577D01*
X528303Y358660D01*
X529428D01*
G01X520106Y354558D02*
X519856Y354683D01*
X519564Y354766D01*
X519231D01*
X518856Y354641D01*
X518564Y354433D01*
X518356Y354183D01*
X518189Y353766D01*
X518147Y353391D01*
X518231Y353016D01*
X518356Y352766D01*
X518606Y352516D01*
X518897Y352349D01*
X519189Y352266D01*
X519481D01*
X519772Y352349D01*
X520022Y352474D01*
X520231Y352641D01*
G01X521372Y352766D02*
X521622Y352474D01*
X521956Y352308D01*
X522331Y352266D01*
X522664Y352308D01*
X522997Y352516D01*
X523206Y352766D01*
X523247Y353016D01*
X523164Y353308D01*
X522872Y353516D01*
X522581Y353599D01*
X522206D01*
G01X522581D02*
X522831Y353724D01*
X523039Y353933D01*
X523122Y354183D01*
X523039Y354433D01*
X522831Y354641D01*
X522456Y354766D01*
X522081Y354724D01*
X521706Y354558D01*
G01X525389Y354766D02*
X525056Y354683D01*
X524806Y354474D01*
X524639Y354224D01*
X524514Y353891D01*
X524472Y353516D01*
X524514Y353141D01*
X524639Y352808D01*
X524806Y352558D01*
X525056Y352349D01*
X525389Y352266D01*
X525722Y352349D01*
X525972Y352558D01*
X526139Y352808D01*
X526264Y353141D01*
X526306Y353516D01*
X526264Y353891D01*
X526139Y354224D01*
X525972Y354474D01*
X525722Y354683D01*
X525389Y354766D01*
G01X528406Y352266D02*
X528489Y352808D01*
X528614Y353266D01*
X528781Y353683D01*
X528989Y354141D01*
X529322Y354766D01*
X527656D01*
G01X520483Y350601D02*
X520233Y350726D01*
X519941Y350809D01*
X519608D01*
X519233Y350684D01*
X518941Y350476D01*
X518733Y350226D01*
X518566Y349809D01*
X518524Y349434D01*
X518608Y349059D01*
X518733Y348809D01*
X518983Y348559D01*
X519274Y348392D01*
X519566Y348309D01*
X519858D01*
X520149Y348392D01*
X520399Y348517D01*
X520608Y348684D01*
G01X521749Y348809D02*
X521999Y348517D01*
X522333Y348351D01*
X522708Y348309D01*
X523041Y348351D01*
X523374Y348559D01*
X523583Y348809D01*
X523624Y349059D01*
X523541Y349351D01*
X523249Y349559D01*
X522958Y349642D01*
X522583D01*
G01X522958D02*
X523208Y349767D01*
X523416Y349976D01*
X523499Y350226D01*
X523416Y350476D01*
X523208Y350684D01*
X522833Y350809D01*
X522458Y350767D01*
X522083Y350601D01*
G01X525766Y350809D02*
X525433Y350726D01*
X525183Y350517D01*
X525016Y350267D01*
X524891Y349934D01*
X524849Y349559D01*
X524891Y349184D01*
X525016Y348851D01*
X525183Y348601D01*
X525433Y348392D01*
X525766Y348309D01*
X526099Y348392D01*
X526349Y348601D01*
X526516Y348851D01*
X526641Y349184D01*
X526683Y349559D01*
X526641Y349934D01*
X526516Y350267D01*
X526349Y350517D01*
X526099Y350726D01*
X525766Y350809D01*
G01X528074Y349351D02*
X528366Y349642D01*
X528616Y349809D01*
X528949Y349892D01*
X529241Y349809D01*
X529449Y349642D01*
X529616Y349392D01*
X529658Y349101D01*
X529616Y348851D01*
X529449Y348601D01*
X529199Y348392D01*
X528908Y348309D01*
X528574Y348392D01*
X528283Y348642D01*
X528116Y349017D01*
X528074Y349434D01*
X528158Y349976D01*
X528283Y350267D01*
X528491Y350559D01*
X528783Y350767D01*
X529074Y350809D01*
X529366Y350726D01*
X529574Y350517D01*
G01X525308Y453719D02*
X522808D01*
Y454760D01*
X522933Y455094D01*
X523100Y455302D01*
X523433Y455385D01*
X523766Y455302D01*
X523975Y455052D01*
X524100Y454760D01*
Y453719D01*
G01Y454760D02*
X525308Y455385D01*
G01X524266Y456860D02*
X523975Y457152D01*
X523808Y457402D01*
X523725Y457735D01*
X523808Y458027D01*
X523975Y458235D01*
X524225Y458402D01*
X524516Y458444D01*
X524766Y458402D01*
X525016Y458235D01*
X525225Y457985D01*
X525308Y457694D01*
X525225Y457360D01*
X524975Y457069D01*
X524600Y456902D01*
X524183Y456860D01*
X523641Y456944D01*
X523350Y457069D01*
X523058Y457277D01*
X522850Y457569D01*
X522808Y457860D01*
X522891Y458152D01*
X523100Y458360D01*
G01X524266Y459960D02*
X523975Y460252D01*
X523808Y460502D01*
X523725Y460835D01*
X523808Y461127D01*
X523975Y461335D01*
X524225Y461502D01*
X524516Y461544D01*
X524766Y461502D01*
X525016Y461335D01*
X525225Y461085D01*
X525308Y460794D01*
X525225Y460460D01*
X524975Y460169D01*
X524600Y460002D01*
X524183Y459960D01*
X523641Y460044D01*
X523350Y460169D01*
X523058Y460377D01*
X522850Y460669D01*
X522808Y460960D01*
X522891Y461252D01*
X523100Y461460D01*
G01X525016Y463144D02*
X525225Y463435D01*
X525308Y463769D01*
X525225Y464102D01*
X524975Y464394D01*
X524600Y464602D01*
X524225Y464685D01*
X523766D01*
X523391Y464602D01*
X523058Y464394D01*
X522891Y464144D01*
X522808Y463852D01*
X522891Y463519D01*
X523058Y463269D01*
X523308Y463102D01*
X523641Y463019D01*
X523933Y463102D01*
X524225Y463310D01*
X524391Y463560D01*
X524433Y463852D01*
X524350Y464185D01*
X524141Y464435D01*
X523766Y464685D01*
G01X529310Y453719D02*
X526810D01*
Y454760D01*
X526935Y455094D01*
X527102Y455302D01*
X527435Y455385D01*
X527768Y455302D01*
X527977Y455052D01*
X528102Y454760D01*
Y453719D01*
G01Y454760D02*
X529310Y455385D01*
G01X528268Y456860D02*
X527977Y457152D01*
X527810Y457402D01*
X527727Y457735D01*
X527810Y458027D01*
X527977Y458235D01*
X528227Y458402D01*
X528518Y458444D01*
X528768Y458402D01*
X529018Y458235D01*
X529227Y457985D01*
X529310Y457694D01*
X529227Y457360D01*
X528977Y457069D01*
X528602Y456902D01*
X528185Y456860D01*
X527643Y456944D01*
X527352Y457069D01*
X527060Y457277D01*
X526852Y457569D01*
X526810Y457860D01*
X526893Y458152D01*
X527102Y458360D01*
G01X528810Y459835D02*
X529102Y460085D01*
X529268Y460419D01*
X529310Y460794D01*
X529268Y461127D01*
X529060Y461460D01*
X528810Y461669D01*
X528560Y461710D01*
X528268Y461627D01*
X528060Y461335D01*
X527977Y461044D01*
Y460669D01*
G01Y461044D02*
X527852Y461294D01*
X527643Y461502D01*
X527393Y461585D01*
X527143Y461502D01*
X526935Y461294D01*
X526810Y460919D01*
X526852Y460544D01*
X527018Y460169D01*
G01X529310Y463769D02*
X528768Y463852D01*
X528310Y463977D01*
X527893Y464144D01*
X527435Y464352D01*
X526810Y464685D01*
Y463019D01*
G01X515607Y455288D02*
X515482Y455038D01*
X515399Y454746D01*
Y454413D01*
X515524Y454038D01*
X515732Y453746D01*
X515982Y453538D01*
X516399Y453371D01*
X516774Y453329D01*
X517149Y453413D01*
X517399Y453538D01*
X517649Y453788D01*
X517816Y454079D01*
X517899Y454371D01*
Y454663D01*
X517816Y454954D01*
X517691Y455204D01*
X517524Y455413D01*
G01X517399Y456554D02*
X517691Y456804D01*
X517857Y457138D01*
X517899Y457513D01*
X517857Y457846D01*
X517649Y458179D01*
X517399Y458388D01*
X517149Y458429D01*
X516857Y458346D01*
X516649Y458054D01*
X516566Y457763D01*
Y457388D01*
G01Y457763D02*
X516441Y458013D01*
X516232Y458221D01*
X515982Y458304D01*
X515732Y458221D01*
X515524Y458013D01*
X515399Y457638D01*
X515441Y457263D01*
X515607Y456888D01*
G01X517607Y459863D02*
X517816Y460154D01*
X517899Y460488D01*
X517816Y460821D01*
X517566Y461113D01*
X517191Y461321D01*
X516816Y461404D01*
X516357D01*
X515982Y461321D01*
X515649Y461113D01*
X515482Y460863D01*
X515399Y460571D01*
X515482Y460238D01*
X515649Y459988D01*
X515899Y459821D01*
X516232Y459738D01*
X516524Y459821D01*
X516816Y460029D01*
X516982Y460279D01*
X517024Y460571D01*
X516941Y460904D01*
X516732Y461154D01*
X516357Y461404D01*
G01X517899Y464171D02*
X515399D01*
X517191Y462629D01*
Y464713D01*
G01X503807Y455388D02*
X503682Y455138D01*
X503599Y454846D01*
Y454513D01*
X503724Y454138D01*
X503932Y453846D01*
X504182Y453638D01*
X504599Y453471D01*
X504974Y453429D01*
X505349Y453513D01*
X505599Y453638D01*
X505849Y453888D01*
X506016Y454179D01*
X506099Y454471D01*
Y454763D01*
X506016Y455054D01*
X505891Y455304D01*
X505724Y455513D01*
G01X505599Y456654D02*
X505891Y456904D01*
X506057Y457238D01*
X506099Y457613D01*
X506057Y457946D01*
X505849Y458279D01*
X505599Y458488D01*
X505349Y458529D01*
X505057Y458446D01*
X504849Y458154D01*
X504766Y457863D01*
Y457488D01*
G01Y457863D02*
X504641Y458113D01*
X504432Y458321D01*
X504182Y458404D01*
X503932Y458321D01*
X503724Y458113D01*
X503599Y457738D01*
X503641Y457363D01*
X503807Y456988D01*
G01X505807Y459963D02*
X506016Y460254D01*
X506099Y460588D01*
X506016Y460921D01*
X505766Y461213D01*
X505391Y461421D01*
X505016Y461504D01*
X504557D01*
X504182Y461421D01*
X503849Y461213D01*
X503682Y460963D01*
X503599Y460671D01*
X503682Y460338D01*
X503849Y460088D01*
X504099Y459921D01*
X504432Y459838D01*
X504724Y459921D01*
X505016Y460129D01*
X505182Y460379D01*
X505224Y460671D01*
X505141Y461004D01*
X504932Y461254D01*
X504557Y461504D01*
G01X505599Y462854D02*
X505891Y463104D01*
X506057Y463438D01*
X506099Y463813D01*
X506057Y464146D01*
X505849Y464479D01*
X505599Y464688D01*
X505349Y464729D01*
X505057Y464646D01*
X504849Y464354D01*
X504766Y464063D01*
Y463688D01*
G01Y464063D02*
X504641Y464313D01*
X504432Y464521D01*
X504182Y464604D01*
X503932Y464521D01*
X503724Y464313D01*
X503599Y463938D01*
X503641Y463563D01*
X503807Y463188D01*
G01X507807Y455388D02*
X507682Y455138D01*
X507599Y454846D01*
Y454513D01*
X507724Y454138D01*
X507932Y453846D01*
X508182Y453638D01*
X508599Y453471D01*
X508974Y453429D01*
X509349Y453513D01*
X509599Y453638D01*
X509849Y453888D01*
X510016Y454179D01*
X510099Y454471D01*
Y454763D01*
X510016Y455054D01*
X509891Y455304D01*
X509724Y455513D01*
G01X509599Y456654D02*
X509891Y456904D01*
X510057Y457238D01*
X510099Y457613D01*
X510057Y457946D01*
X509849Y458279D01*
X509599Y458488D01*
X509349Y458529D01*
X509057Y458446D01*
X508849Y458154D01*
X508766Y457863D01*
Y457488D01*
G01Y457863D02*
X508641Y458113D01*
X508432Y458321D01*
X508182Y458404D01*
X507932Y458321D01*
X507724Y458113D01*
X507599Y457738D01*
X507641Y457363D01*
X507807Y456988D01*
G01X510099Y460671D02*
X510057Y460963D01*
X509932Y461296D01*
X509724Y461504D01*
X509432Y461588D01*
X509141Y461504D01*
X508891Y461254D01*
X508766Y460879D01*
Y460463D01*
X508682Y460213D01*
X508474Y460004D01*
X508182Y459921D01*
X507891Y460046D01*
X507682Y460338D01*
X507599Y460671D01*
X507682Y461004D01*
X507891Y461296D01*
X508182Y461421D01*
X508474Y461338D01*
X508682Y461129D01*
X508766Y460879D01*
Y460463D01*
X508891Y460088D01*
X509141Y459838D01*
X509432Y459754D01*
X509724Y459838D01*
X509932Y460046D01*
X510057Y460379D01*
X510099Y460671D01*
G01X509807Y463063D02*
X510016Y463354D01*
X510099Y463688D01*
X510016Y464021D01*
X509766Y464313D01*
X509391Y464521D01*
X509016Y464604D01*
X508557D01*
X508182Y464521D01*
X507849Y464313D01*
X507682Y464063D01*
X507599Y463771D01*
X507682Y463438D01*
X507849Y463188D01*
X508099Y463021D01*
X508432Y462938D01*
X508724Y463021D01*
X509016Y463229D01*
X509182Y463479D01*
X509224Y463771D01*
X509141Y464104D01*
X508932Y464354D01*
X508557Y464604D01*
G01X511307Y455388D02*
X511182Y455138D01*
X511099Y454846D01*
Y454513D01*
X511224Y454138D01*
X511432Y453846D01*
X511682Y453638D01*
X512099Y453471D01*
X512474Y453429D01*
X512849Y453513D01*
X513099Y453638D01*
X513349Y453888D01*
X513516Y454179D01*
X513599Y454471D01*
Y454763D01*
X513516Y455054D01*
X513391Y455304D01*
X513224Y455513D01*
G01X513099Y456654D02*
X513391Y456904D01*
X513557Y457238D01*
X513599Y457613D01*
X513557Y457946D01*
X513349Y458279D01*
X513099Y458488D01*
X512849Y458529D01*
X512557Y458446D01*
X512349Y458154D01*
X512266Y457863D01*
Y457488D01*
G01Y457863D02*
X512141Y458113D01*
X511932Y458321D01*
X511682Y458404D01*
X511432Y458321D01*
X511224Y458113D01*
X511099Y457738D01*
X511141Y457363D01*
X511307Y456988D01*
G01X513599Y460671D02*
X513557Y460963D01*
X513432Y461296D01*
X513224Y461504D01*
X512932Y461588D01*
X512641Y461504D01*
X512391Y461254D01*
X512266Y460879D01*
Y460463D01*
X512182Y460213D01*
X511974Y460004D01*
X511682Y459921D01*
X511391Y460046D01*
X511182Y460338D01*
X511099Y460671D01*
X511182Y461004D01*
X511391Y461296D01*
X511682Y461421D01*
X511974Y461338D01*
X512182Y461129D01*
X512266Y460879D01*
Y460463D01*
X512391Y460088D01*
X512641Y459838D01*
X512932Y459754D01*
X513224Y459838D01*
X513432Y460046D01*
X513557Y460379D01*
X513599Y460671D01*
G01Y463771D02*
X513557Y464063D01*
X513432Y464396D01*
X513224Y464604D01*
X512932Y464688D01*
X512641Y464604D01*
X512391Y464354D01*
X512266Y463979D01*
Y463563D01*
X512182Y463313D01*
X511974Y463104D01*
X511682Y463021D01*
X511391Y463146D01*
X511182Y463438D01*
X511099Y463771D01*
X511182Y464104D01*
X511391Y464396D01*
X511682Y464521D01*
X511974Y464438D01*
X512182Y464229D01*
X512266Y463979D01*
Y463563D01*
X512391Y463188D01*
X512641Y462938D01*
X512932Y462854D01*
X513224Y462938D01*
X513432Y463146D01*
X513557Y463479D01*
X513599Y463771D01*
G01X534483Y455388D02*
X534358Y455138D01*
X534275Y454846D01*
Y454513D01*
X534400Y454138D01*
X534608Y453846D01*
X534858Y453638D01*
X535275Y453471D01*
X535650Y453429D01*
X536025Y453513D01*
X536275Y453638D01*
X536525Y453888D01*
X536692Y454179D01*
X536775Y454471D01*
Y454763D01*
X536692Y455054D01*
X536567Y455304D01*
X536400Y455513D01*
G01X536275Y456654D02*
X536567Y456904D01*
X536733Y457238D01*
X536775Y457613D01*
X536733Y457946D01*
X536525Y458279D01*
X536275Y458488D01*
X536025Y458529D01*
X535733Y458446D01*
X535525Y458154D01*
X535442Y457863D01*
Y457488D01*
G01Y457863D02*
X535317Y458113D01*
X535108Y458321D01*
X534858Y458404D01*
X534608Y458321D01*
X534400Y458113D01*
X534275Y457738D01*
X534317Y457363D01*
X534483Y456988D01*
G01X536483Y459963D02*
X536692Y460254D01*
X536775Y460588D01*
X536692Y460921D01*
X536442Y461213D01*
X536067Y461421D01*
X535692Y461504D01*
X535233D01*
X534858Y461421D01*
X534525Y461213D01*
X534358Y460963D01*
X534275Y460671D01*
X534358Y460338D01*
X534525Y460088D01*
X534775Y459921D01*
X535108Y459838D01*
X535400Y459921D01*
X535692Y460129D01*
X535858Y460379D01*
X535900Y460671D01*
X535817Y461004D01*
X535608Y461254D01*
X535233Y461504D01*
G01X536483Y463063D02*
X536692Y463354D01*
X536775Y463688D01*
X536692Y464021D01*
X536442Y464313D01*
X536067Y464521D01*
X535692Y464604D01*
X535233D01*
X534858Y464521D01*
X534525Y464313D01*
X534358Y464063D01*
X534275Y463771D01*
X534358Y463438D01*
X534525Y463188D01*
X534775Y463021D01*
X535108Y462938D01*
X535400Y463021D01*
X535692Y463229D01*
X535858Y463479D01*
X535900Y463771D01*
X535817Y464104D01*
X535608Y464354D01*
X535233Y464604D01*
G01X530983Y455388D02*
X530858Y455138D01*
X530775Y454846D01*
Y454513D01*
X530900Y454138D01*
X531108Y453846D01*
X531358Y453638D01*
X531775Y453471D01*
X532150Y453429D01*
X532525Y453513D01*
X532775Y453638D01*
X533025Y453888D01*
X533192Y454179D01*
X533275Y454471D01*
Y454763D01*
X533192Y455054D01*
X533067Y455304D01*
X532900Y455513D01*
G01X532775Y456654D02*
X533067Y456904D01*
X533233Y457238D01*
X533275Y457613D01*
X533233Y457946D01*
X533025Y458279D01*
X532775Y458488D01*
X532525Y458529D01*
X532233Y458446D01*
X532025Y458154D01*
X531942Y457863D01*
Y457488D01*
G01Y457863D02*
X531817Y458113D01*
X531608Y458321D01*
X531358Y458404D01*
X531108Y458321D01*
X530900Y458113D01*
X530775Y457738D01*
X530817Y457363D01*
X530983Y456988D01*
G01X532983Y459963D02*
X533192Y460254D01*
X533275Y460588D01*
X533192Y460921D01*
X532942Y461213D01*
X532567Y461421D01*
X532192Y461504D01*
X531733D01*
X531358Y461421D01*
X531025Y461213D01*
X530858Y460963D01*
X530775Y460671D01*
X530858Y460338D01*
X531025Y460088D01*
X531275Y459921D01*
X531608Y459838D01*
X531900Y459921D01*
X532192Y460129D01*
X532358Y460379D01*
X532400Y460671D01*
X532317Y461004D01*
X532108Y461254D01*
X531733Y461504D01*
G01X533275Y463771D02*
X533233Y464063D01*
X533108Y464396D01*
X532900Y464604D01*
X532608Y464688D01*
X532317Y464604D01*
X532067Y464354D01*
X531942Y463979D01*
Y463563D01*
X531858Y463313D01*
X531650Y463104D01*
X531358Y463021D01*
X531067Y463146D01*
X530858Y463438D01*
X530775Y463771D01*
X530858Y464104D01*
X531067Y464396D01*
X531358Y464521D01*
X531650Y464438D01*
X531858Y464229D01*
X531942Y463979D01*
Y463563D01*
X532067Y463188D01*
X532317Y462938D01*
X532608Y462854D01*
X532900Y462938D01*
X533108Y463146D01*
X533233Y463479D01*
X533275Y463771D01*
G01X519107Y455288D02*
X518982Y455038D01*
X518899Y454746D01*
Y454413D01*
X519024Y454038D01*
X519232Y453746D01*
X519482Y453538D01*
X519899Y453371D01*
X520274Y453329D01*
X520649Y453413D01*
X520899Y453538D01*
X521149Y453788D01*
X521316Y454079D01*
X521399Y454371D01*
Y454663D01*
X521316Y454954D01*
X521191Y455204D01*
X521024Y455413D01*
G01X520899Y456554D02*
X521191Y456804D01*
X521357Y457138D01*
X521399Y457513D01*
X521357Y457846D01*
X521149Y458179D01*
X520899Y458388D01*
X520649Y458429D01*
X520357Y458346D01*
X520149Y458054D01*
X520066Y457763D01*
Y457388D01*
G01Y457763D02*
X519941Y458013D01*
X519732Y458221D01*
X519482Y458304D01*
X519232Y458221D01*
X519024Y458013D01*
X518899Y457638D01*
X518941Y457263D01*
X519107Y456888D01*
G01X521107Y459863D02*
X521316Y460154D01*
X521399Y460488D01*
X521316Y460821D01*
X521066Y461113D01*
X520691Y461321D01*
X520316Y461404D01*
X519857D01*
X519482Y461321D01*
X519149Y461113D01*
X518982Y460863D01*
X518899Y460571D01*
X518982Y460238D01*
X519149Y459988D01*
X519399Y459821D01*
X519732Y459738D01*
X520024Y459821D01*
X520316Y460029D01*
X520482Y460279D01*
X520524Y460571D01*
X520441Y460904D01*
X520232Y461154D01*
X519857Y461404D01*
G01X521024Y462754D02*
X521232Y463004D01*
X521357Y463296D01*
X521399Y463671D01*
X521316Y464046D01*
X521149Y464338D01*
X520857Y464546D01*
X520524Y464588D01*
X520191Y464504D01*
X519982Y464296D01*
X519816Y464004D01*
X519774Y463713D01*
X519816Y463421D01*
X519982Y463046D01*
X518899Y463171D01*
Y464296D01*
G01X525906Y777098D02*
X521906D01*
Y769698D01*
G01X509906Y777098D02*
X505906D01*
Y769698D01*
G01X521906Y777098D02*
X517906D01*
Y769698D01*
G01Y777098D02*
X513906D01*
Y769698D01*
G01Y777098D02*
X509906D01*
Y769698D01*
G01X536119Y767167D02*
X533619D01*
Y768208D01*
X533744Y768542D01*
X533911Y768750D01*
X534244Y768833D01*
X534577Y768750D01*
X534786Y768500D01*
X534911Y768208D01*
Y767167D01*
G01Y768208D02*
X536119Y768833D01*
G01X535744Y770183D02*
X535952Y770433D01*
X536077Y770725D01*
X536119Y771100D01*
X536036Y771475D01*
X535869Y771767D01*
X535577Y771975D01*
X535244Y772017D01*
X534911Y771933D01*
X534702Y771725D01*
X534536Y771433D01*
X534494Y771142D01*
X534536Y770850D01*
X534702Y770475D01*
X533619Y770600D01*
Y771725D01*
G01X536119Y774700D02*
X533619D01*
X535411Y773158D01*
Y775242D01*
G01X536119Y777300D02*
X536077Y777592D01*
X535952Y777925D01*
X535744Y778133D01*
X535452Y778217D01*
X535161Y778133D01*
X534911Y777883D01*
X534786Y777508D01*
Y777092D01*
X534702Y776842D01*
X534494Y776633D01*
X534202Y776550D01*
X533911Y776675D01*
X533702Y776967D01*
X533619Y777300D01*
X533702Y777633D01*
X533911Y777925D01*
X534202Y778050D01*
X534494Y777967D01*
X534702Y777758D01*
X534786Y777508D01*
Y777092D01*
X534911Y776717D01*
X535161Y776467D01*
X535452Y776383D01*
X535744Y776467D01*
X535952Y776675D01*
X536077Y777008D01*
X536119Y777300D01*
G01X530100Y777000D02*
X526100D01*
Y769600D01*
G01X519906Y805398D02*
Y791398D01*
G01X537254Y797141D02*
X534754D01*
Y798182D01*
X534879Y798516D01*
X535046Y798724D01*
X535379Y798807D01*
X535712Y798724D01*
X535921Y798474D01*
X536046Y798182D01*
Y797141D01*
G01Y798182D02*
X537254Y798807D01*
G01Y800991D02*
X536712Y801074D01*
X536254Y801199D01*
X535837Y801366D01*
X535379Y801574D01*
X534754Y801907D01*
Y800241D01*
G01X536962Y803466D02*
X537171Y803757D01*
X537254Y804091D01*
X537171Y804424D01*
X536921Y804716D01*
X536546Y804924D01*
X536171Y805007D01*
X535712D01*
X535337Y804924D01*
X535004Y804716D01*
X534837Y804466D01*
X534754Y804174D01*
X534837Y803841D01*
X535004Y803591D01*
X535254Y803424D01*
X535587Y803341D01*
X535879Y803424D01*
X536171Y803632D01*
X536337Y803882D01*
X536379Y804174D01*
X536296Y804507D01*
X536087Y804757D01*
X535712Y805007D01*
G01X537254Y807191D02*
X536712Y807274D01*
X536254Y807399D01*
X535837Y807566D01*
X535379Y807774D01*
X534754Y808107D01*
Y806441D01*
G01X537254Y810374D02*
X534754D01*
X535254Y809874D01*
G01X537254D02*
Y810874D01*
G01X524818Y795972D02*
X522318D01*
Y797013D01*
X522443Y797347D01*
X522610Y797555D01*
X522943Y797638D01*
X523276Y797555D01*
X523485Y797305D01*
X523610Y797013D01*
Y795972D01*
G01Y797013D02*
X524818Y797638D01*
G01Y799822D02*
X524276Y799905D01*
X523818Y800030D01*
X523401Y800197D01*
X522943Y800405D01*
X522318Y800738D01*
Y799072D01*
G01X524526Y802297D02*
X524735Y802588D01*
X524818Y802922D01*
X524735Y803255D01*
X524485Y803547D01*
X524110Y803755D01*
X523735Y803838D01*
X523276D01*
X522901Y803755D01*
X522568Y803547D01*
X522401Y803297D01*
X522318Y803005D01*
X522401Y802672D01*
X522568Y802422D01*
X522818Y802255D01*
X523151Y802172D01*
X523443Y802255D01*
X523735Y802463D01*
X523901Y802713D01*
X523943Y803005D01*
X523860Y803338D01*
X523651Y803588D01*
X523276Y803838D01*
G01X524443Y805188D02*
X524651Y805438D01*
X524776Y805730D01*
X524818Y806105D01*
X524735Y806480D01*
X524568Y806772D01*
X524276Y806980D01*
X523943Y807022D01*
X523610Y806938D01*
X523401Y806730D01*
X523235Y806438D01*
X523193Y806147D01*
X523235Y805855D01*
X523401Y805480D01*
X522318Y805605D01*
Y806730D01*
G01X524443Y808288D02*
X524651Y808538D01*
X524776Y808830D01*
X524818Y809205D01*
X524735Y809580D01*
X524568Y809872D01*
X524276Y810080D01*
X523943Y810122D01*
X523610Y810038D01*
X523401Y809830D01*
X523235Y809538D01*
X523193Y809247D01*
X523235Y808955D01*
X523401Y808580D01*
X522318Y808705D01*
Y809830D01*
G01X528927Y797093D02*
X526427D01*
Y798134D01*
X526552Y798468D01*
X526719Y798676D01*
X527052Y798759D01*
X527385Y798676D01*
X527594Y798426D01*
X527719Y798134D01*
Y797093D01*
G01Y798134D02*
X528927Y798759D01*
G01Y800943D02*
X528385Y801026D01*
X527927Y801151D01*
X527510Y801318D01*
X527052Y801526D01*
X526427Y801859D01*
Y800193D01*
G01X528635Y803418D02*
X528844Y803709D01*
X528927Y804043D01*
X528844Y804376D01*
X528594Y804668D01*
X528219Y804876D01*
X527844Y804959D01*
X527385D01*
X527010Y804876D01*
X526677Y804668D01*
X526510Y804418D01*
X526427Y804126D01*
X526510Y803793D01*
X526677Y803543D01*
X526927Y803376D01*
X527260Y803293D01*
X527552Y803376D01*
X527844Y803584D01*
X528010Y803834D01*
X528052Y804126D01*
X527969Y804459D01*
X527760Y804709D01*
X527385Y804959D01*
G01X528927Y807726D02*
X526427D01*
X528219Y806184D01*
Y808268D01*
G01X528927Y810326D02*
X526427D01*
X526927Y809826D01*
G01X528927D02*
Y810826D01*
G01X533027Y797093D02*
X530527D01*
Y798134D01*
X530652Y798468D01*
X530819Y798676D01*
X531152Y798759D01*
X531485Y798676D01*
X531694Y798426D01*
X531819Y798134D01*
Y797093D01*
G01Y798134D02*
X533027Y798759D01*
G01Y800943D02*
X532485Y801026D01*
X532027Y801151D01*
X531610Y801318D01*
X531152Y801526D01*
X530527Y801859D01*
Y800193D01*
G01X532735Y803418D02*
X532944Y803709D01*
X533027Y804043D01*
X532944Y804376D01*
X532694Y804668D01*
X532319Y804876D01*
X531944Y804959D01*
X531485D01*
X531110Y804876D01*
X530777Y804668D01*
X530610Y804418D01*
X530527Y804126D01*
X530610Y803793D01*
X530777Y803543D01*
X531027Y803376D01*
X531360Y803293D01*
X531652Y803376D01*
X531944Y803584D01*
X532110Y803834D01*
X532152Y804126D01*
X532069Y804459D01*
X531860Y804709D01*
X531485Y804959D01*
G01X530944Y806434D02*
X530694Y806684D01*
X530569Y806976D01*
X530527Y807309D01*
X530610Y807726D01*
X530819Y808018D01*
X531069Y808101D01*
X531319Y808059D01*
X531527Y807893D01*
X531944Y807059D01*
X532235Y806684D01*
X532652Y806434D01*
X533027Y806351D01*
Y808101D01*
G01Y810243D02*
X532485Y810326D01*
X532027Y810451D01*
X531610Y810618D01*
X531152Y810826D01*
X530527Y811159D01*
Y809493D01*
G01X507941Y832763D02*
X507691Y832888D01*
X507399Y832971D01*
X507066D01*
X506691Y832846D01*
X506399Y832638D01*
X506191Y832388D01*
X506024Y831971D01*
X505982Y831596D01*
X506066Y831221D01*
X506191Y830971D01*
X506441Y830721D01*
X506732Y830554D01*
X507024Y830471D01*
X507316D01*
X507607Y830554D01*
X507857Y830679D01*
X508066Y830846D01*
G01X510624Y830471D02*
Y832971D01*
X509082Y831179D01*
X511166D01*
G01X513224Y830471D02*
Y832971D01*
X512724Y832471D01*
G01Y830471D02*
X513724D01*
G01X516824D02*
Y832971D01*
X515282Y831179D01*
X517366D01*
G01X519924Y830471D02*
Y832971D01*
X518382Y831179D01*
X520466D01*
G01X518906Y818698D02*
X522906D01*
Y826098D01*
G01Y818698D02*
X526906D01*
Y826098D01*
G01X506500Y818700D02*
X510500D01*
Y826100D01*
G01X510579Y818650D02*
X514579D01*
Y826050D01*
G01X526906Y818698D02*
X530906D01*
Y826098D01*
G01X514679Y818650D02*
X518679D01*
Y826050D01*
G01X530906Y818698D02*
X534906D01*
Y826098D01*
G01X550950Y142300D02*
X550617Y142342D01*
X550325Y142508D01*
X550075Y142758D01*
X549908Y143050D01*
X549825Y143383D01*
Y143717D01*
X549908Y144050D01*
X550075Y144342D01*
X550325Y144592D01*
X550617Y144758D01*
X550950Y144800D01*
X551283Y144758D01*
X551575Y144592D01*
X551825Y144342D01*
X551992Y144050D01*
X552075Y143717D01*
Y143383D01*
X551992Y143050D01*
X551825Y142758D01*
X551575Y142508D01*
X551283Y142342D01*
X550950Y142300D01*
G01X553092D02*
Y144800D01*
X555008Y142300D01*
Y144800D01*
G01X569250Y142400D02*
X568917Y142442D01*
X568625Y142608D01*
X568375Y142858D01*
X568208Y143150D01*
X568125Y143483D01*
Y143817D01*
X568208Y144150D01*
X568375Y144442D01*
X568625Y144692D01*
X568917Y144858D01*
X569250Y144900D01*
X569583Y144858D01*
X569875Y144692D01*
X570125Y144442D01*
X570292Y144150D01*
X570375Y143817D01*
Y143483D01*
X570292Y143150D01*
X570125Y142858D01*
X569875Y142608D01*
X569583Y142442D01*
X569250Y142400D01*
G01X571392D02*
Y144900D01*
X573308Y142400D01*
Y144900D01*
G01X545100Y139800D02*
Y141000D01*
X564800D01*
Y136400D01*
X574700D01*
G01X577300Y122800D02*
X568900D01*
G01X566400D02*
X557600D01*
G01X554200D02*
X545300D01*
G01X542200D02*
X538300D01*
G01X563690Y128030D02*
X567690D01*
Y135430D01*
G01X563670Y134909D02*
Y138909D01*
X556270D01*
G01X567700Y128030D02*
X571700D01*
Y135430D01*
G01X548780Y135550D02*
Y131550D01*
X556180D01*
G01X556200Y135597D02*
Y139597D01*
X548800D01*
G01X560263Y138920D02*
X556263D01*
Y131520D01*
G01X550950Y149700D02*
X550617Y149742D01*
X550325Y149908D01*
X550075Y150158D01*
X549908Y150450D01*
X549825Y150783D01*
Y151117D01*
X549908Y151450D01*
X550075Y151742D01*
X550325Y151992D01*
X550617Y152158D01*
X550950Y152200D01*
X551283Y152158D01*
X551575Y151992D01*
X551825Y151742D01*
X551992Y151450D01*
X552075Y151117D01*
Y150783D01*
X551992Y150450D01*
X551825Y150158D01*
X551575Y149908D01*
X551283Y149742D01*
X550950Y149700D01*
G01X553092D02*
Y152200D01*
X555008Y149700D01*
Y152200D01*
G01X569250Y149700D02*
X568917Y149742D01*
X568625Y149908D01*
X568375Y150158D01*
X568208Y150450D01*
X568125Y150783D01*
Y151117D01*
X568208Y151450D01*
X568375Y151742D01*
X568625Y151992D01*
X568917Y152158D01*
X569250Y152200D01*
X569583Y152158D01*
X569875Y151992D01*
X570125Y151742D01*
X570292Y151450D01*
X570375Y151117D01*
Y150783D01*
X570292Y150450D01*
X570125Y150158D01*
X569875Y149908D01*
X569583Y149742D01*
X569250Y149700D01*
G01X571558D02*
Y152200D01*
X573142D01*
G01X572558Y150992D02*
X571558D01*
G01X574658Y149700D02*
Y152200D01*
X576242D01*
G01X575658Y150992D02*
X574658D01*
G01X564967Y157000D02*
X564133D01*
Y153667D01*
X564967D01*
G01X566817Y157000D02*
Y154500D01*
X568483D01*
G01X571583D02*
X569917D01*
Y157000D01*
X571583D01*
G01X570917Y155792D02*
X569917D01*
G01X572933Y154500D02*
Y157000D01*
X573767D01*
X574100Y156875D01*
X574350Y156708D01*
X574558Y156458D01*
X574725Y156167D01*
X574767Y155750D01*
X574725Y155333D01*
X574558Y155042D01*
X574350Y154792D01*
X574100Y154625D01*
X573767Y154500D01*
X572933D01*
G01X576242Y154792D02*
X576533Y154583D01*
X576867Y154500D01*
X577200Y154583D01*
X577492Y154833D01*
X577700Y155208D01*
X577783Y155583D01*
Y156042D01*
X577700Y156417D01*
X577492Y156750D01*
X577242Y156917D01*
X576950Y157000D01*
X576617Y156917D01*
X576367Y156750D01*
X576200Y156500D01*
X576117Y156167D01*
X576200Y155875D01*
X576408Y155583D01*
X576658Y155417D01*
X576950Y155375D01*
X577283Y155458D01*
X577533Y155667D01*
X577783Y156042D01*
G01X579633Y153667D02*
X580467D01*
Y157000D01*
X579633D01*
G01X550850Y146100D02*
X550517Y146142D01*
X550225Y146308D01*
X549975Y146558D01*
X549808Y146850D01*
X549725Y147183D01*
Y147517D01*
X549808Y147850D01*
X549975Y148142D01*
X550225Y148392D01*
X550517Y148558D01*
X550850Y148600D01*
X551183Y148558D01*
X551475Y148392D01*
X551725Y148142D01*
X551892Y147850D01*
X551975Y147517D01*
Y147183D01*
X551892Y146850D01*
X551725Y146558D01*
X551475Y146308D01*
X551183Y146142D01*
X550850Y146100D01*
G01X552992D02*
Y148600D01*
X554908Y146100D01*
Y148600D01*
G01X569250Y146100D02*
X568917Y146142D01*
X568625Y146308D01*
X568375Y146558D01*
X568208Y146850D01*
X568125Y147183D01*
Y147517D01*
X568208Y147850D01*
X568375Y148142D01*
X568625Y148392D01*
X568917Y148558D01*
X569250Y148600D01*
X569583Y148558D01*
X569875Y148392D01*
X570125Y148142D01*
X570292Y147850D01*
X570375Y147517D01*
Y147183D01*
X570292Y146850D01*
X570125Y146558D01*
X569875Y146308D01*
X569583Y146142D01*
X569250Y146100D01*
G01X571392D02*
Y148600D01*
X573308Y146100D01*
Y148600D01*
G01X543267Y156700D02*
X542433D01*
Y153367D01*
X543267D01*
G01X545117Y156700D02*
Y154200D01*
X546783D01*
G01X549883D02*
X548217D01*
Y156700D01*
X549883D01*
G01X549217Y155492D02*
X548217D01*
G01X551233Y154200D02*
Y156700D01*
X552067D01*
X552400Y156575D01*
X552650Y156408D01*
X552858Y156158D01*
X553025Y155867D01*
X553067Y155450D01*
X553025Y155033D01*
X552858Y154742D01*
X552650Y154492D01*
X552400Y154325D01*
X552067Y154200D01*
X551233D01*
G01X555250D02*
X555542Y154242D01*
X555875Y154367D01*
X556083Y154575D01*
X556167Y154867D01*
X556083Y155158D01*
X555833Y155408D01*
X555458Y155533D01*
X555042D01*
X554792Y155617D01*
X554583Y155825D01*
X554500Y156117D01*
X554625Y156408D01*
X554917Y156617D01*
X555250Y156700D01*
X555583Y156617D01*
X555875Y156408D01*
X556000Y156117D01*
X555917Y155825D01*
X555708Y155617D01*
X555458Y155533D01*
X555042D01*
X554667Y155408D01*
X554417Y155158D01*
X554333Y154867D01*
X554417Y154575D01*
X554625Y154367D01*
X554958Y154242D01*
X555250Y154200D01*
G01X557933Y153367D02*
X558767D01*
Y156700D01*
X557933D01*
G01X548400Y159600D02*
X552400D01*
Y167000D01*
G01X565200Y159300D02*
X569200D01*
Y166700D01*
G01X569400Y159300D02*
X573400D01*
Y166700D01*
G01X552500Y159600D02*
X556500D01*
Y167000D01*
G01X561100Y159300D02*
X565100D01*
Y166700D01*
G01X540490Y158401D02*
X544490D01*
Y165801D01*
G01X572100Y207700D02*
X568100D01*
Y200300D01*
G01X554000Y206417D02*
X551500D01*
Y207458D01*
X551625Y207792D01*
X551792Y208000D01*
X552125Y208083D01*
X552458Y208000D01*
X552667Y207750D01*
X552792Y207458D01*
Y206417D01*
G01Y207458D02*
X554000Y208083D01*
G01X553708Y209642D02*
X553917Y209933D01*
X554000Y210267D01*
X553917Y210600D01*
X553667Y210892D01*
X553292Y211100D01*
X552917Y211183D01*
X552458D01*
X552083Y211100D01*
X551750Y210892D01*
X551583Y210642D01*
X551500Y210350D01*
X551583Y210017D01*
X551750Y209767D01*
X552000Y209600D01*
X552333Y209517D01*
X552625Y209600D01*
X552917Y209808D01*
X553083Y210058D01*
X553125Y210350D01*
X553042Y210683D01*
X552833Y210933D01*
X552458Y211183D01*
G01X553500Y212533D02*
X553792Y212783D01*
X553958Y213117D01*
X554000Y213492D01*
X553958Y213825D01*
X553750Y214158D01*
X553500Y214367D01*
X553250Y214408D01*
X552958Y214325D01*
X552750Y214033D01*
X552667Y213742D01*
Y213367D01*
G01Y213742D02*
X552542Y213992D01*
X552333Y214200D01*
X552083Y214283D01*
X551833Y214200D01*
X551625Y213992D01*
X551500Y213617D01*
X551542Y213242D01*
X551708Y212867D01*
G01X554000Y216550D02*
X551500D01*
X552000Y216050D01*
G01X554000D02*
Y217050D01*
G01X537228Y205346D02*
X537561Y205138D01*
X537936Y205013D01*
X538270D01*
X538603Y205138D01*
X538853Y205346D01*
X538978Y205638D01*
X538895Y205930D01*
X538686Y206180D01*
X538311Y206346D01*
X537811Y206430D01*
X537520Y206596D01*
X537395Y206888D01*
X537478Y207180D01*
X537686Y207388D01*
X537978Y207513D01*
X538270D01*
X538561Y207430D01*
X538811Y207221D01*
G01X542120Y207305D02*
X541870Y207430D01*
X541578Y207513D01*
X541245D01*
X540870Y207388D01*
X540578Y207180D01*
X540370Y206930D01*
X540203Y206513D01*
X540161Y206138D01*
X540245Y205763D01*
X540370Y205513D01*
X540620Y205263D01*
X540911Y205096D01*
X541203Y205013D01*
X541495D01*
X541786Y205096D01*
X542036Y205221D01*
X542245Y205388D01*
G01X543345Y205013D02*
Y207513D01*
X545261Y205013D01*
Y207513D01*
G01X546695Y205305D02*
X546986Y205096D01*
X547320Y205013D01*
X547653Y205096D01*
X547945Y205346D01*
X548153Y205721D01*
X548236Y206096D01*
Y206555D01*
X548153Y206930D01*
X547945Y207263D01*
X547695Y207430D01*
X547403Y207513D01*
X547070Y207430D01*
X546820Y207263D01*
X546653Y207013D01*
X546570Y206680D01*
X546653Y206388D01*
X546861Y206096D01*
X547111Y205930D01*
X547403Y205888D01*
X547736Y205971D01*
X547986Y206180D01*
X548236Y206555D01*
G01X559344Y202422D02*
X559094Y202547D01*
X558802Y202630D01*
X558469D01*
X558094Y202505D01*
X557802Y202297D01*
X557594Y202047D01*
X557427Y201630D01*
X557385Y201255D01*
X557469Y200880D01*
X557594Y200630D01*
X557844Y200380D01*
X558135Y200213D01*
X558427Y200130D01*
X558719D01*
X559010Y200213D01*
X559260Y200338D01*
X559469Y200505D01*
G01X560569Y200130D02*
Y202630D01*
X562485Y200130D01*
Y202630D01*
G01X563710Y200505D02*
X563960Y200297D01*
X564252Y200172D01*
X564627Y200130D01*
X565002Y200213D01*
X565294Y200380D01*
X565502Y200672D01*
X565544Y201005D01*
X565460Y201338D01*
X565252Y201547D01*
X564960Y201713D01*
X564669Y201755D01*
X564377Y201713D01*
X564002Y201547D01*
X564127Y202630D01*
X565252D01*
G01X556667Y219000D02*
Y221500D01*
X557667D01*
X558000Y221375D01*
X558250Y221083D01*
X558333Y220750D01*
X558250Y220417D01*
X558042Y220167D01*
X557667Y220042D01*
X556667D01*
G01X561517Y221292D02*
X561267Y221417D01*
X560975Y221500D01*
X560642D01*
X560267Y221375D01*
X559975Y221167D01*
X559767Y220917D01*
X559600Y220500D01*
X559558Y220125D01*
X559642Y219750D01*
X559767Y219500D01*
X560017Y219250D01*
X560308Y219083D01*
X560600Y219000D01*
X560892D01*
X561183Y219083D01*
X561433Y219208D01*
X561642Y219375D01*
G01X563700Y219000D02*
Y221500D01*
X563200Y221000D01*
G01Y219000D02*
X564200D01*
G01X566092Y219292D02*
X566383Y219083D01*
X566717Y219000D01*
X567050Y219083D01*
X567342Y219333D01*
X567550Y219708D01*
X567633Y220083D01*
Y220542D01*
X567550Y220917D01*
X567342Y221250D01*
X567092Y221417D01*
X566800Y221500D01*
X566467Y221417D01*
X566217Y221250D01*
X566050Y221000D01*
X565967Y220667D01*
X566050Y220375D01*
X566258Y220083D01*
X566508Y219917D01*
X566800Y219875D01*
X567133Y219958D01*
X567383Y220167D01*
X567633Y220542D01*
G01X569900Y219000D02*
X570192Y219042D01*
X570525Y219167D01*
X570733Y219375D01*
X570817Y219667D01*
X570733Y219958D01*
X570483Y220208D01*
X570108Y220333D01*
X569692D01*
X569442Y220417D01*
X569233Y220625D01*
X569150Y220917D01*
X569275Y221208D01*
X569567Y221417D01*
X569900Y221500D01*
X570233Y221417D01*
X570525Y221208D01*
X570650Y220917D01*
X570567Y220625D01*
X570358Y220417D01*
X570108Y220333D01*
X569692D01*
X569317Y220208D01*
X569067Y219958D01*
X568983Y219667D01*
X569067Y219375D01*
X569275Y219167D01*
X569608Y219042D01*
X569900Y219000D01*
G01X556667Y215400D02*
Y217900D01*
X557667D01*
X558000Y217775D01*
X558250Y217483D01*
X558333Y217150D01*
X558250Y216817D01*
X558042Y216567D01*
X557667Y216442D01*
X556667D01*
G01X561517Y217692D02*
X561267Y217817D01*
X560975Y217900D01*
X560642D01*
X560267Y217775D01*
X559975Y217567D01*
X559767Y217317D01*
X559600Y216900D01*
X559558Y216525D01*
X559642Y216150D01*
X559767Y215900D01*
X560017Y215650D01*
X560308Y215483D01*
X560600Y215400D01*
X560892D01*
X561183Y215483D01*
X561433Y215608D01*
X561642Y215775D01*
G01X562908Y217483D02*
X563158Y217733D01*
X563450Y217858D01*
X563783Y217900D01*
X564200Y217817D01*
X564492Y217608D01*
X564575Y217358D01*
X564533Y217108D01*
X564367Y216900D01*
X563533Y216483D01*
X563158Y216192D01*
X562908Y215775D01*
X562825Y215400D01*
X564575D01*
G01X566800Y217900D02*
X566467Y217817D01*
X566217Y217608D01*
X566050Y217358D01*
X565925Y217025D01*
X565883Y216650D01*
X565925Y216275D01*
X566050Y215942D01*
X566217Y215692D01*
X566467Y215483D01*
X566800Y215400D01*
X567133Y215483D01*
X567383Y215692D01*
X567550Y215942D01*
X567675Y216275D01*
X567717Y216650D01*
X567675Y217025D01*
X567550Y217358D01*
X567383Y217608D01*
X567133Y217817D01*
X566800Y217900D01*
G01X569108Y216442D02*
X569400Y216733D01*
X569650Y216900D01*
X569983Y216983D01*
X570275Y216900D01*
X570483Y216733D01*
X570650Y216483D01*
X570692Y216192D01*
X570650Y215942D01*
X570483Y215692D01*
X570233Y215483D01*
X569942Y215400D01*
X569608Y215483D01*
X569317Y215733D01*
X569150Y216108D01*
X569108Y216525D01*
X569192Y217067D01*
X569317Y217358D01*
X569525Y217650D01*
X569817Y217858D01*
X570108Y217900D01*
X570400Y217817D01*
X570608Y217608D01*
G01X549410Y229347D02*
X546910D01*
Y230388D01*
X547035Y230722D01*
X547202Y230930D01*
X547535Y231013D01*
X547868Y230930D01*
X548077Y230680D01*
X548202Y230388D01*
Y229347D01*
G01Y230388D02*
X549410Y231013D01*
G01X548368Y232488D02*
X548077Y232780D01*
X547910Y233030D01*
X547827Y233363D01*
X547910Y233655D01*
X548077Y233863D01*
X548327Y234030D01*
X548618Y234072D01*
X548868Y234030D01*
X549118Y233863D01*
X549327Y233613D01*
X549410Y233322D01*
X549327Y232988D01*
X549077Y232697D01*
X548702Y232530D01*
X548285Y232488D01*
X547743Y232572D01*
X547452Y232697D01*
X547160Y232905D01*
X546952Y233197D01*
X546910Y233488D01*
X546993Y233780D01*
X547202Y233988D01*
G01X549035Y235463D02*
X549243Y235713D01*
X549368Y236005D01*
X549410Y236380D01*
X549327Y236755D01*
X549160Y237047D01*
X548868Y237255D01*
X548535Y237297D01*
X548202Y237213D01*
X547993Y237005D01*
X547827Y236713D01*
X547785Y236422D01*
X547827Y236130D01*
X547993Y235755D01*
X546910Y235880D01*
Y237005D01*
G01X549410Y239480D02*
X546910D01*
X547410Y238980D01*
G01X549410D02*
Y239980D01*
G01X556667Y211500D02*
Y214000D01*
X557667D01*
X558000Y213875D01*
X558250Y213583D01*
X558333Y213250D01*
X558250Y212917D01*
X558042Y212667D01*
X557667Y212542D01*
X556667D01*
G01X559767Y211500D02*
Y214000D01*
X560808D01*
X561142Y213875D01*
X561350Y213708D01*
X561433Y213375D01*
X561350Y213042D01*
X561100Y212833D01*
X560808Y212708D01*
X559767D01*
G01X560808D02*
X561433Y211500D01*
G01X563700D02*
Y214000D01*
X563200Y213500D01*
G01Y211500D02*
X564200D01*
G01X566717D02*
X566800Y212042D01*
X566925Y212500D01*
X567092Y212917D01*
X567300Y213375D01*
X567633Y214000D01*
X565967D01*
G01X568983Y211875D02*
X569233Y211667D01*
X569525Y211542D01*
X569900Y211500D01*
X570275Y211583D01*
X570567Y211750D01*
X570775Y212042D01*
X570817Y212375D01*
X570733Y212708D01*
X570525Y212917D01*
X570233Y213083D01*
X569942Y213125D01*
X569650Y213083D01*
X569275Y212917D01*
X569400Y214000D01*
X570525D01*
G01X545420Y229214D02*
X542920D01*
Y230255D01*
X543045Y230589D01*
X543212Y230797D01*
X543545Y230880D01*
X543878Y230797D01*
X544087Y230547D01*
X544212Y230255D01*
Y229214D01*
G01Y230255D02*
X545420Y230880D01*
G01X545128Y232439D02*
X545337Y232730D01*
X545420Y233064D01*
X545337Y233397D01*
X545087Y233689D01*
X544712Y233897D01*
X544337Y233980D01*
X543878D01*
X543503Y233897D01*
X543170Y233689D01*
X543003Y233439D01*
X542920Y233147D01*
X543003Y232814D01*
X543170Y232564D01*
X543420Y232397D01*
X543753Y232314D01*
X544045Y232397D01*
X544337Y232605D01*
X544503Y232855D01*
X544545Y233147D01*
X544462Y233480D01*
X544253Y233730D01*
X543878Y233980D01*
G01X545045Y235330D02*
X545253Y235580D01*
X545378Y235872D01*
X545420Y236247D01*
X545337Y236622D01*
X545170Y236914D01*
X544878Y237122D01*
X544545Y237164D01*
X544212Y237080D01*
X544003Y236872D01*
X543837Y236580D01*
X543795Y236289D01*
X543837Y235997D01*
X544003Y235622D01*
X542920Y235747D01*
Y236872D01*
G01X545045Y238430D02*
X545253Y238680D01*
X545378Y238972D01*
X545420Y239347D01*
X545337Y239722D01*
X545170Y240014D01*
X544878Y240222D01*
X544545Y240264D01*
X544212Y240180D01*
X544003Y239972D01*
X543837Y239680D01*
X543795Y239389D01*
X543837Y239097D01*
X544003Y238722D01*
X542920Y238847D01*
Y239972D01*
G01X553399Y229081D02*
X550899D01*
Y230122D01*
X551024Y230456D01*
X551191Y230664D01*
X551524Y230747D01*
X551857Y230664D01*
X552066Y230414D01*
X552191Y230122D01*
Y229081D01*
G01Y230122D02*
X553399Y230747D01*
G01X553107Y232306D02*
X553316Y232597D01*
X553399Y232931D01*
X553316Y233264D01*
X553066Y233556D01*
X552691Y233764D01*
X552316Y233847D01*
X551857D01*
X551482Y233764D01*
X551149Y233556D01*
X550982Y233306D01*
X550899Y233014D01*
X550982Y232681D01*
X551149Y232431D01*
X551399Y232264D01*
X551732Y232181D01*
X552024Y232264D01*
X552316Y232472D01*
X552482Y232722D01*
X552524Y233014D01*
X552441Y233347D01*
X552232Y233597D01*
X551857Y233847D01*
G01X553024Y235197D02*
X553232Y235447D01*
X553357Y235739D01*
X553399Y236114D01*
X553316Y236489D01*
X553149Y236781D01*
X552857Y236989D01*
X552524Y237031D01*
X552191Y236947D01*
X551982Y236739D01*
X551816Y236447D01*
X551774Y236156D01*
X551816Y235864D01*
X551982Y235489D01*
X550899Y235614D01*
Y236739D01*
G01X552357Y238422D02*
X552066Y238714D01*
X551899Y238964D01*
X551816Y239297D01*
X551899Y239589D01*
X552066Y239797D01*
X552316Y239964D01*
X552607Y240006D01*
X552857Y239964D01*
X553107Y239797D01*
X553316Y239547D01*
X553399Y239256D01*
X553316Y238922D01*
X553066Y238631D01*
X552691Y238464D01*
X552274Y238422D01*
X551732Y238506D01*
X551441Y238631D01*
X551149Y238839D01*
X550941Y239131D01*
X550899Y239422D01*
X550982Y239714D01*
X551191Y239922D01*
G01X547613Y210180D02*
X547821Y210513D01*
X547946Y210888D01*
Y211222D01*
X547821Y211555D01*
X547613Y211805D01*
X547321Y211930D01*
X547029Y211847D01*
X546779Y211638D01*
X546613Y211263D01*
X546529Y210763D01*
X546363Y210472D01*
X546071Y210347D01*
X545779Y210430D01*
X545571Y210638D01*
X545446Y210930D01*
Y211222D01*
X545529Y211513D01*
X545738Y211763D01*
G01X545654Y215072D02*
X545529Y214822D01*
X545446Y214530D01*
Y214197D01*
X545571Y213822D01*
X545779Y213530D01*
X546029Y213322D01*
X546446Y213155D01*
X546821Y213113D01*
X547196Y213197D01*
X547446Y213322D01*
X547696Y213572D01*
X547863Y213863D01*
X547946Y214155D01*
Y214447D01*
X547863Y214738D01*
X547738Y214988D01*
X547571Y215197D01*
G01X547946Y217255D02*
X545446D01*
X545946Y216755D01*
G01X547946D02*
Y217755D01*
G01X547446Y219438D02*
X547738Y219688D01*
X547904Y220022D01*
X547946Y220397D01*
X547904Y220730D01*
X547696Y221063D01*
X547446Y221272D01*
X547196Y221313D01*
X546904Y221230D01*
X546696Y220938D01*
X546613Y220647D01*
Y220272D01*
G01Y220647D02*
X546488Y220897D01*
X546279Y221105D01*
X546029Y221188D01*
X545779Y221105D01*
X545571Y220897D01*
X545446Y220522D01*
X545488Y220147D01*
X545654Y219772D01*
G01X545446Y223455D02*
X545529Y223122D01*
X545738Y222872D01*
X545988Y222705D01*
X546321Y222580D01*
X546696Y222538D01*
X547071Y222580D01*
X547404Y222705D01*
X547654Y222872D01*
X547863Y223122D01*
X547946Y223455D01*
X547863Y223788D01*
X547654Y224038D01*
X547404Y224205D01*
X547071Y224330D01*
X546696Y224372D01*
X546321Y224330D01*
X545988Y224205D01*
X545738Y224038D01*
X545529Y223788D01*
X545446Y223455D01*
G01X547946Y226472D02*
X547404Y226555D01*
X546946Y226680D01*
X546529Y226847D01*
X546071Y227055D01*
X545446Y227388D01*
Y225722D01*
G01X556667Y223200D02*
Y225700D01*
X557667D01*
X558000Y225575D01*
X558250Y225283D01*
X558333Y224950D01*
X558250Y224617D01*
X558042Y224367D01*
X557667Y224242D01*
X556667D01*
G01X561517Y225492D02*
X561267Y225617D01*
X560975Y225700D01*
X560642D01*
X560267Y225575D01*
X559975Y225367D01*
X559767Y225117D01*
X559600Y224700D01*
X559558Y224325D01*
X559642Y223950D01*
X559767Y223700D01*
X560017Y223450D01*
X560308Y223283D01*
X560600Y223200D01*
X560892D01*
X561183Y223283D01*
X561433Y223408D01*
X561642Y223575D01*
G01X562908Y225283D02*
X563158Y225533D01*
X563450Y225658D01*
X563783Y225700D01*
X564200Y225617D01*
X564492Y225408D01*
X564575Y225158D01*
X564533Y224908D01*
X564367Y224700D01*
X563533Y224283D01*
X563158Y223992D01*
X562908Y223575D01*
X562825Y223200D01*
X564575D01*
G01X566800Y225700D02*
X566467Y225617D01*
X566217Y225408D01*
X566050Y225158D01*
X565925Y224825D01*
X565883Y224450D01*
X565925Y224075D01*
X566050Y223742D01*
X566217Y223492D01*
X566467Y223283D01*
X566800Y223200D01*
X567133Y223283D01*
X567383Y223492D01*
X567550Y223742D01*
X567675Y224075D01*
X567717Y224450D01*
X567675Y224825D01*
X567550Y225158D01*
X567383Y225408D01*
X567133Y225617D01*
X566800Y225700D01*
G01X569900Y223200D02*
Y225700D01*
X569400Y225200D01*
G01Y223200D02*
X570400D01*
G01X556667Y227100D02*
Y229600D01*
X557667D01*
X558000Y229475D01*
X558250Y229183D01*
X558333Y228850D01*
X558250Y228517D01*
X558042Y228267D01*
X557667Y228142D01*
X556667D01*
G01X561517Y229392D02*
X561267Y229517D01*
X560975Y229600D01*
X560642D01*
X560267Y229475D01*
X559975Y229267D01*
X559767Y229017D01*
X559600Y228600D01*
X559558Y228225D01*
X559642Y227850D01*
X559767Y227600D01*
X560017Y227350D01*
X560308Y227183D01*
X560600Y227100D01*
X560892D01*
X561183Y227183D01*
X561433Y227308D01*
X561642Y227475D01*
G01X563700Y227100D02*
Y229600D01*
X563200Y229100D01*
G01Y227100D02*
X564200D01*
G01X566092Y227392D02*
X566383Y227183D01*
X566717Y227100D01*
X567050Y227183D01*
X567342Y227433D01*
X567550Y227808D01*
X567633Y228183D01*
Y228642D01*
X567550Y229017D01*
X567342Y229350D01*
X567092Y229517D01*
X566800Y229600D01*
X566467Y229517D01*
X566217Y229350D01*
X566050Y229100D01*
X565967Y228767D01*
X566050Y228475D01*
X566258Y228183D01*
X566508Y228017D01*
X566800Y227975D01*
X567133Y228058D01*
X567383Y228267D01*
X567633Y228642D01*
G01X569192Y227392D02*
X569483Y227183D01*
X569817Y227100D01*
X570150Y227183D01*
X570442Y227433D01*
X570650Y227808D01*
X570733Y228183D01*
Y228642D01*
X570650Y229017D01*
X570442Y229350D01*
X570192Y229517D01*
X569900Y229600D01*
X569567Y229517D01*
X569317Y229350D01*
X569150Y229100D01*
X569067Y228767D01*
X569150Y228475D01*
X569358Y228183D01*
X569608Y228017D01*
X569900Y227975D01*
X570233Y228058D01*
X570483Y228267D01*
X570733Y228642D01*
G01X556730Y234908D02*
Y237408D01*
X557730D01*
X558063Y237283D01*
X558313Y236991D01*
X558396Y236658D01*
X558313Y236325D01*
X558105Y236075D01*
X557730Y235950D01*
X556730D01*
G01X561580Y237200D02*
X561330Y237325D01*
X561038Y237408D01*
X560705D01*
X560330Y237283D01*
X560038Y237075D01*
X559830Y236825D01*
X559663Y236408D01*
X559621Y236033D01*
X559705Y235658D01*
X559830Y235408D01*
X560080Y235158D01*
X560371Y234991D01*
X560663Y234908D01*
X560955D01*
X561246Y234991D01*
X561496Y235116D01*
X561705Y235283D01*
G01X562971Y236991D02*
X563221Y237241D01*
X563513Y237366D01*
X563846Y237408D01*
X564263Y237325D01*
X564555Y237116D01*
X564638Y236866D01*
X564596Y236616D01*
X564430Y236408D01*
X563596Y235991D01*
X563221Y235700D01*
X562971Y235283D01*
X562888Y234908D01*
X564638D01*
G01X566863D02*
Y237408D01*
X566363Y236908D01*
G01Y234908D02*
X567363D01*
G01X570463D02*
Y237408D01*
X568921Y235616D01*
X571005D01*
G01X556667Y231000D02*
Y233500D01*
X557667D01*
X558000Y233375D01*
X558250Y233083D01*
X558333Y232750D01*
X558250Y232417D01*
X558042Y232167D01*
X557667Y232042D01*
X556667D01*
G01X561517Y233292D02*
X561267Y233417D01*
X560975Y233500D01*
X560642D01*
X560267Y233375D01*
X559975Y233167D01*
X559767Y232917D01*
X559600Y232500D01*
X559558Y232125D01*
X559642Y231750D01*
X559767Y231500D01*
X560017Y231250D01*
X560308Y231083D01*
X560600Y231000D01*
X560892D01*
X561183Y231083D01*
X561433Y231208D01*
X561642Y231375D01*
G01X563700Y231000D02*
Y233500D01*
X563200Y233000D01*
G01Y231000D02*
X564200D01*
G01X566092Y231292D02*
X566383Y231083D01*
X566717Y231000D01*
X567050Y231083D01*
X567342Y231333D01*
X567550Y231708D01*
X567633Y232083D01*
Y232542D01*
X567550Y232917D01*
X567342Y233250D01*
X567092Y233417D01*
X566800Y233500D01*
X566467Y233417D01*
X566217Y233250D01*
X566050Y233000D01*
X565967Y232667D01*
X566050Y232375D01*
X566258Y232083D01*
X566508Y231917D01*
X566800Y231875D01*
X567133Y231958D01*
X567383Y232167D01*
X567633Y232542D01*
G01X569108Y232042D02*
X569400Y232333D01*
X569650Y232500D01*
X569983Y232583D01*
X570275Y232500D01*
X570483Y232333D01*
X570650Y232083D01*
X570692Y231792D01*
X570650Y231542D01*
X570483Y231292D01*
X570233Y231083D01*
X569942Y231000D01*
X569608Y231083D01*
X569317Y231333D01*
X569150Y231708D01*
X569108Y232125D01*
X569192Y232667D01*
X569317Y232958D01*
X569525Y233250D01*
X569817Y233458D01*
X570108Y233500D01*
X570400Y233417D01*
X570608Y233208D01*
G01X562213Y269158D02*
X580913D01*
Y258858D01*
X562213D01*
Y269158D01*
G01Y281458D02*
X580913D01*
Y271158D01*
X562213D01*
Y281458D01*
G01X549830Y264429D02*
X551622D01*
X551997Y264596D01*
X552247Y264929D01*
X552330Y265346D01*
X552247Y265763D01*
X551997Y266096D01*
X551622Y266263D01*
X549830D01*
G01X552038Y267738D02*
X552247Y268029D01*
X552330Y268363D01*
X552247Y268696D01*
X551997Y268988D01*
X551622Y269196D01*
X551247Y269279D01*
X550788D01*
X550413Y269196D01*
X550080Y268988D01*
X549913Y268738D01*
X549830Y268446D01*
X549913Y268113D01*
X550080Y267863D01*
X550330Y267696D01*
X550663Y267613D01*
X550955Y267696D01*
X551247Y267904D01*
X551413Y268154D01*
X551455Y268446D01*
X551372Y268779D01*
X551163Y269029D01*
X550788Y269279D01*
G01X551318Y247514D02*
X551526Y247847D01*
X551651Y248222D01*
Y248556D01*
X551526Y248889D01*
X551318Y249139D01*
X551026Y249264D01*
X550734Y249181D01*
X550484Y248972D01*
X550318Y248597D01*
X550234Y248097D01*
X550068Y247806D01*
X549776Y247681D01*
X549484Y247764D01*
X549276Y247972D01*
X549151Y248264D01*
Y248556D01*
X549234Y248847D01*
X549443Y249097D01*
G01X551651Y250572D02*
X549151D01*
G01Y252156D02*
X550693Y250572D01*
G01X551651Y252406D02*
X549984Y251281D01*
G01X549151Y254589D02*
X551651D01*
G01X549151Y253631D02*
Y255547D01*
G01X551651Y258189D02*
X549151D01*
X550943Y256647D01*
Y258731D01*
G01X555559Y317341D02*
Y307141D01*
G01D02*
X578159D01*
G01X555559Y317341D02*
Y307141D01*
G01D02*
X578159D01*
G01X544021Y302581D02*
X541521D01*
Y303622D01*
X541646Y303956D01*
X541813Y304164D01*
X542146Y304247D01*
X542479Y304164D01*
X542688Y303914D01*
X542813Y303622D01*
Y302581D01*
G01Y303622D02*
X544021Y304247D01*
G01X542979Y305722D02*
X542688Y306014D01*
X542521Y306264D01*
X542438Y306597D01*
X542521Y306889D01*
X542688Y307097D01*
X542938Y307264D01*
X543229Y307306D01*
X543479Y307264D01*
X543729Y307097D01*
X543938Y306847D01*
X544021Y306556D01*
X543938Y306222D01*
X543688Y305931D01*
X543313Y305764D01*
X542896Y305722D01*
X542354Y305806D01*
X542063Y305931D01*
X541771Y306139D01*
X541563Y306431D01*
X541521Y306722D01*
X541604Y307014D01*
X541813Y307222D01*
G01X544021Y309614D02*
X541521D01*
X542021Y309114D01*
G01X544021D02*
Y310114D01*
G01X543646Y311797D02*
X543854Y312047D01*
X543979Y312339D01*
X544021Y312714D01*
X543938Y313089D01*
X543771Y313381D01*
X543479Y313589D01*
X543146Y313631D01*
X542813Y313547D01*
X542604Y313339D01*
X542438Y313047D01*
X542396Y312756D01*
X542438Y312464D01*
X542604Y312089D01*
X541521Y312214D01*
Y313339D01*
G01X543681Y296476D02*
X539681D01*
Y289076D01*
G01X540321Y302581D02*
X537821D01*
Y303622D01*
X537946Y303956D01*
X538113Y304164D01*
X538446Y304247D01*
X538779Y304164D01*
X538988Y303914D01*
X539113Y303622D01*
Y302581D01*
G01Y303622D02*
X540321Y304247D01*
G01X540029Y305806D02*
X540238Y306097D01*
X540321Y306431D01*
X540238Y306764D01*
X539988Y307056D01*
X539613Y307264D01*
X539238Y307347D01*
X538779D01*
X538404Y307264D01*
X538071Y307056D01*
X537904Y306806D01*
X537821Y306514D01*
X537904Y306181D01*
X538071Y305931D01*
X538321Y305764D01*
X538654Y305681D01*
X538946Y305764D01*
X539238Y305972D01*
X539404Y306222D01*
X539446Y306514D01*
X539363Y306847D01*
X539154Y307097D01*
X538779Y307347D01*
G01X539946Y308697D02*
X540154Y308947D01*
X540279Y309239D01*
X540321Y309614D01*
X540238Y309989D01*
X540071Y310281D01*
X539779Y310489D01*
X539446Y310531D01*
X539113Y310447D01*
X538904Y310239D01*
X538738Y309947D01*
X538696Y309656D01*
X538738Y309364D01*
X538904Y308989D01*
X537821Y309114D01*
Y310239D01*
G01X540321Y312714D02*
X540279Y313006D01*
X540154Y313339D01*
X539946Y313547D01*
X539654Y313631D01*
X539363Y313547D01*
X539113Y313297D01*
X538988Y312922D01*
Y312506D01*
X538904Y312256D01*
X538696Y312047D01*
X538404Y311964D01*
X538113Y312089D01*
X537904Y312381D01*
X537821Y312714D01*
X537904Y313047D01*
X538113Y313339D01*
X538404Y313464D01*
X538696Y313381D01*
X538904Y313172D01*
X538988Y312922D01*
Y312506D01*
X539113Y312131D01*
X539363Y311881D01*
X539654Y311797D01*
X539946Y311881D01*
X540154Y312089D01*
X540279Y312422D01*
X540321Y312714D01*
G01X546465Y282405D02*
Y284905D01*
X547506D01*
X547840Y284780D01*
X548048Y284613D01*
X548131Y284280D01*
X548048Y283947D01*
X547798Y283738D01*
X547506Y283613D01*
X546465D01*
G01X547506D02*
X548131Y282405D01*
G01X549690Y282697D02*
X549981Y282488D01*
X550315Y282405D01*
X550648Y282488D01*
X550940Y282738D01*
X551148Y283113D01*
X551231Y283488D01*
Y283947D01*
X551148Y284322D01*
X550940Y284655D01*
X550690Y284822D01*
X550398Y284905D01*
X550065Y284822D01*
X549815Y284655D01*
X549648Y284405D01*
X549565Y284072D01*
X549648Y283780D01*
X549856Y283488D01*
X550106Y283322D01*
X550398Y283280D01*
X550731Y283363D01*
X550981Y283572D01*
X551231Y283947D01*
G01X552581Y282780D02*
X552831Y282572D01*
X553123Y282447D01*
X553498Y282405D01*
X553873Y282488D01*
X554165Y282655D01*
X554373Y282947D01*
X554415Y283280D01*
X554331Y283613D01*
X554123Y283822D01*
X553831Y283988D01*
X553540Y284030D01*
X553248Y283988D01*
X552873Y283822D01*
X552998Y284905D01*
X554123D01*
G01X555890Y282697D02*
X556181Y282488D01*
X556515Y282405D01*
X556848Y282488D01*
X557140Y282738D01*
X557348Y283113D01*
X557431Y283488D01*
Y283947D01*
X557348Y284322D01*
X557140Y284655D01*
X556890Y284822D01*
X556598Y284905D01*
X556265Y284822D01*
X556015Y284655D01*
X555848Y284405D01*
X555765Y284072D01*
X555848Y283780D01*
X556056Y283488D01*
X556306Y283322D01*
X556598Y283280D01*
X556931Y283363D01*
X557181Y283572D01*
X557431Y283947D01*
G01X543999Y293069D02*
Y289069D01*
X551399D01*
G01X562213Y306058D02*
X580913D01*
Y295758D01*
X562213D01*
Y306058D01*
G01Y293758D02*
X580913D01*
Y283458D01*
X562213D01*
Y293758D01*
G01X565717Y318900D02*
Y321400D01*
X566717D01*
X567050Y321275D01*
X567300Y320983D01*
X567383Y320650D01*
X567300Y320317D01*
X567092Y320067D01*
X566717Y319942D01*
X565717D01*
G01X568817Y321400D02*
Y318900D01*
X570483D01*
G01X572750D02*
Y321400D01*
X572250Y320900D01*
G01Y318900D02*
X573250D01*
G01X575850Y321400D02*
X575517Y321317D01*
X575267Y321108D01*
X575100Y320858D01*
X574975Y320525D01*
X574933Y320150D01*
X574975Y319775D01*
X575100Y319442D01*
X575267Y319192D01*
X575517Y318983D01*
X575850Y318900D01*
X576183Y318983D01*
X576433Y319192D01*
X576600Y319442D01*
X576725Y319775D01*
X576767Y320150D01*
X576725Y320525D01*
X576600Y320858D01*
X576433Y321108D01*
X576183Y321317D01*
X575850Y321400D01*
G01X578159Y317341D02*
X555559D01*
G01X578159D02*
X555559D01*
G01X564448Y333980D02*
Y336480D01*
X565448D01*
X565781Y336355D01*
X566031Y336063D01*
X566114Y335730D01*
X566031Y335397D01*
X565823Y335147D01*
X565448Y335022D01*
X564448D01*
G01X567548Y333980D02*
Y336480D01*
X568589D01*
X568923Y336355D01*
X569131Y336188D01*
X569214Y335855D01*
X569131Y335522D01*
X568881Y335313D01*
X568589Y335188D01*
X567548D01*
G01X568589D02*
X569214Y333980D01*
G01X570773Y334272D02*
X571064Y334063D01*
X571398Y333980D01*
X571731Y334063D01*
X572023Y334313D01*
X572231Y334688D01*
X572314Y335063D01*
Y335522D01*
X572231Y335897D01*
X572023Y336230D01*
X571773Y336397D01*
X571481Y336480D01*
X571148Y336397D01*
X570898Y336230D01*
X570731Y335980D01*
X570648Y335647D01*
X570731Y335355D01*
X570939Y335063D01*
X571189Y334897D01*
X571481Y334855D01*
X571814Y334938D01*
X572064Y335147D01*
X572314Y335522D01*
G01X574581Y336480D02*
X574248Y336397D01*
X573998Y336188D01*
X573831Y335938D01*
X573706Y335605D01*
X573664Y335230D01*
X573706Y334855D01*
X573831Y334522D01*
X573998Y334272D01*
X574248Y334063D01*
X574581Y333980D01*
X574914Y334063D01*
X575164Y334272D01*
X575331Y334522D01*
X575456Y334855D01*
X575498Y335230D01*
X575456Y335605D01*
X575331Y335938D01*
X575164Y336188D01*
X574914Y336397D01*
X574581Y336480D01*
G01X576764Y334480D02*
X577014Y334188D01*
X577348Y334022D01*
X577723Y333980D01*
X578056Y334022D01*
X578389Y334230D01*
X578598Y334480D01*
X578639Y334730D01*
X578556Y335022D01*
X578264Y335230D01*
X577973Y335313D01*
X577598D01*
G01X577973D02*
X578223Y335438D01*
X578431Y335647D01*
X578514Y335897D01*
X578431Y336147D01*
X578223Y336355D01*
X577848Y336480D01*
X577473Y336438D01*
X577098Y336272D01*
G01X579864Y334480D02*
X580114Y334188D01*
X580448Y334022D01*
X580823Y333980D01*
X581156Y334022D01*
X581489Y334230D01*
X581698Y334480D01*
X581739Y334730D01*
X581656Y335022D01*
X581364Y335230D01*
X581073Y335313D01*
X580698D01*
G01X581073D02*
X581323Y335438D01*
X581531Y335647D01*
X581614Y335897D01*
X581531Y336147D01*
X581323Y336355D01*
X580948Y336480D01*
X580573Y336438D01*
X580198Y336272D01*
G01X563731Y332980D02*
Y336980D01*
X556331D01*
G01X564448Y341980D02*
Y344480D01*
X565448D01*
X565781Y344355D01*
X566031Y344063D01*
X566114Y343730D01*
X566031Y343397D01*
X565823Y343147D01*
X565448Y343022D01*
X564448D01*
G01X567548Y341980D02*
Y344480D01*
X568589D01*
X568923Y344355D01*
X569131Y344188D01*
X569214Y343855D01*
X569131Y343522D01*
X568881Y343313D01*
X568589Y343188D01*
X567548D01*
G01X568589D02*
X569214Y341980D01*
G01X570773Y342272D02*
X571064Y342063D01*
X571398Y341980D01*
X571731Y342063D01*
X572023Y342313D01*
X572231Y342688D01*
X572314Y343063D01*
Y343522D01*
X572231Y343897D01*
X572023Y344230D01*
X571773Y344397D01*
X571481Y344480D01*
X571148Y344397D01*
X570898Y344230D01*
X570731Y343980D01*
X570648Y343647D01*
X570731Y343355D01*
X570939Y343063D01*
X571189Y342897D01*
X571481Y342855D01*
X571814Y342938D01*
X572064Y343147D01*
X572314Y343522D01*
G01X574581Y344480D02*
X574248Y344397D01*
X573998Y344188D01*
X573831Y343938D01*
X573706Y343605D01*
X573664Y343230D01*
X573706Y342855D01*
X573831Y342522D01*
X573998Y342272D01*
X574248Y342063D01*
X574581Y341980D01*
X574914Y342063D01*
X575164Y342272D01*
X575331Y342522D01*
X575456Y342855D01*
X575498Y343230D01*
X575456Y343605D01*
X575331Y343938D01*
X575164Y344188D01*
X574914Y344397D01*
X574581Y344480D01*
G01X576764Y342480D02*
X577014Y342188D01*
X577348Y342022D01*
X577723Y341980D01*
X578056Y342022D01*
X578389Y342230D01*
X578598Y342480D01*
X578639Y342730D01*
X578556Y343022D01*
X578264Y343230D01*
X577973Y343313D01*
X577598D01*
G01X577973D02*
X578223Y343438D01*
X578431Y343647D01*
X578514Y343897D01*
X578431Y344147D01*
X578223Y344355D01*
X577848Y344480D01*
X577473Y344438D01*
X577098Y344272D01*
G01X581281Y341980D02*
Y344480D01*
X579739Y342688D01*
X581823D01*
G01X556331Y344980D02*
Y340980D01*
X563731D01*
G01X567917Y337900D02*
Y340400D01*
X568917D01*
X569250Y340275D01*
X569500Y339983D01*
X569583Y339650D01*
X569500Y339317D01*
X569292Y339067D01*
X568917Y338942D01*
X567917D01*
G01X572767Y340192D02*
X572517Y340317D01*
X572225Y340400D01*
X571892D01*
X571517Y340275D01*
X571225Y340067D01*
X571017Y339817D01*
X570850Y339400D01*
X570808Y339025D01*
X570892Y338650D01*
X571017Y338400D01*
X571267Y338150D01*
X571558Y337983D01*
X571850Y337900D01*
X572142D01*
X572433Y337983D01*
X572683Y338108D01*
X572892Y338275D01*
G01X574950Y337900D02*
X575242Y337942D01*
X575575Y338067D01*
X575783Y338275D01*
X575867Y338567D01*
X575783Y338858D01*
X575533Y339108D01*
X575158Y339233D01*
X574742D01*
X574492Y339317D01*
X574283Y339525D01*
X574200Y339817D01*
X574325Y340108D01*
X574617Y340317D01*
X574950Y340400D01*
X575283Y340317D01*
X575575Y340108D01*
X575700Y339817D01*
X575617Y339525D01*
X575408Y339317D01*
X575158Y339233D01*
X574742D01*
X574367Y339108D01*
X574117Y338858D01*
X574033Y338567D01*
X574117Y338275D01*
X574325Y338067D01*
X574658Y337942D01*
X574950Y337900D01*
G01X577967D02*
X578050Y338442D01*
X578175Y338900D01*
X578342Y339317D01*
X578550Y339775D01*
X578883Y340400D01*
X577217D01*
G01X550010Y333156D02*
X547510D01*
Y334156D01*
X547635Y334489D01*
X547927Y334739D01*
X548260Y334822D01*
X548593Y334739D01*
X548843Y334531D01*
X548968Y334156D01*
Y333156D01*
G01X547718Y338006D02*
X547593Y337756D01*
X547510Y337464D01*
Y337131D01*
X547635Y336756D01*
X547843Y336464D01*
X548093Y336256D01*
X548510Y336089D01*
X548885Y336047D01*
X549260Y336131D01*
X549510Y336256D01*
X549760Y336506D01*
X549927Y336797D01*
X550010Y337089D01*
Y337381D01*
X549927Y337672D01*
X549802Y337922D01*
X549635Y338131D01*
G01X549718Y339481D02*
X549927Y339772D01*
X550010Y340106D01*
X549927Y340439D01*
X549677Y340731D01*
X549302Y340939D01*
X548927Y341022D01*
X548468D01*
X548093Y340939D01*
X547760Y340731D01*
X547593Y340481D01*
X547510Y340189D01*
X547593Y339856D01*
X547760Y339606D01*
X548010Y339439D01*
X548343Y339356D01*
X548635Y339439D01*
X548927Y339647D01*
X549093Y339897D01*
X549135Y340189D01*
X549052Y340522D01*
X548843Y340772D01*
X548468Y341022D01*
G01X547927Y342497D02*
X547677Y342747D01*
X547552Y343039D01*
X547510Y343372D01*
X547593Y343789D01*
X547802Y344081D01*
X548052Y344164D01*
X548302Y344122D01*
X548510Y343956D01*
X548927Y343122D01*
X549218Y342747D01*
X549635Y342497D01*
X550010Y342414D01*
Y344164D01*
G01X543751Y324339D02*
X541251Y326089D01*
G01Y324339D02*
X543751Y326089D01*
G01X541668Y327522D02*
X541418Y327772D01*
X541293Y328064D01*
X541251Y328397D01*
X541334Y328814D01*
X541543Y329106D01*
X541793Y329189D01*
X542043Y329147D01*
X542251Y328981D01*
X542668Y328147D01*
X542959Y327772D01*
X543376Y327522D01*
X543751Y327439D01*
Y329189D01*
G01X549834Y350567D02*
X547334D01*
Y351567D01*
X547459Y351900D01*
X547751Y352150D01*
X548084Y352233D01*
X548417Y352150D01*
X548667Y351942D01*
X548792Y351567D01*
Y350567D01*
G01X547334Y353583D02*
X549126D01*
X549501Y353750D01*
X549751Y354083D01*
X549834Y354500D01*
X549751Y354917D01*
X549501Y355250D01*
X549126Y355417D01*
X547334D01*
G01X548792Y356808D02*
X548501Y357100D01*
X548334Y357350D01*
X548251Y357683D01*
X548334Y357975D01*
X548501Y358183D01*
X548751Y358350D01*
X549042Y358392D01*
X549292Y358350D01*
X549542Y358183D01*
X549751Y357933D01*
X549834Y357642D01*
X549751Y357308D01*
X549501Y357017D01*
X549126Y356850D01*
X548709Y356808D01*
X548167Y356892D01*
X547876Y357017D01*
X547584Y357225D01*
X547376Y357517D01*
X547334Y357808D01*
X547417Y358100D01*
X547626Y358308D01*
G01X554131Y367980D02*
X551131D01*
Y364980D01*
G01Y351180D02*
Y348180D01*
X554131D01*
G01X566931D02*
X569931D01*
Y351180D01*
G01X556631Y369080D02*
Y367080D01*
G01X564431Y349080D02*
Y346080D01*
G01X536823Y374440D02*
Y376940D01*
X537823D01*
X538156Y376815D01*
X538406Y376523D01*
X538489Y376190D01*
X538406Y375857D01*
X538198Y375607D01*
X537823Y375482D01*
X536823D01*
G01X541673Y376732D02*
X541423Y376857D01*
X541131Y376940D01*
X540798D01*
X540423Y376815D01*
X540131Y376607D01*
X539923Y376357D01*
X539756Y375940D01*
X539714Y375565D01*
X539798Y375190D01*
X539923Y374940D01*
X540173Y374690D01*
X540464Y374523D01*
X540756Y374440D01*
X541048D01*
X541339Y374523D01*
X541589Y374648D01*
X541798Y374815D01*
G01X543148Y374732D02*
X543439Y374523D01*
X543773Y374440D01*
X544106Y374523D01*
X544398Y374773D01*
X544606Y375148D01*
X544689Y375523D01*
Y375982D01*
X544606Y376357D01*
X544398Y376690D01*
X544148Y376857D01*
X543856Y376940D01*
X543523Y376857D01*
X543273Y376690D01*
X543106Y376440D01*
X543023Y376107D01*
X543106Y375815D01*
X543314Y375523D01*
X543564Y375357D01*
X543856Y375315D01*
X544189Y375398D01*
X544439Y375607D01*
X544689Y375982D01*
G01X546956Y374440D02*
Y376940D01*
X546456Y376440D01*
G01Y374440D02*
X547456D01*
G01X539000Y360017D02*
X536500D01*
Y361017D01*
X536625Y361350D01*
X536917Y361600D01*
X537250Y361683D01*
X537583Y361600D01*
X537833Y361392D01*
X537958Y361017D01*
Y360017D01*
G01X539000Y363117D02*
X536500D01*
Y364158D01*
X536625Y364492D01*
X536792Y364700D01*
X537125Y364783D01*
X537458Y364700D01*
X537667Y364450D01*
X537792Y364158D01*
Y363117D01*
G01Y364158D02*
X539000Y364783D01*
G01Y366967D02*
X538458Y367050D01*
X538000Y367175D01*
X537583Y367342D01*
X537125Y367550D01*
X536500Y367883D01*
Y366217D01*
G01X539000Y370650D02*
X536500D01*
X538292Y369108D01*
Y371192D01*
G01X565531Y378780D02*
X561531D01*
Y371380D01*
G01X567150Y402333D02*
X570650Y407333D01*
G01X567150D02*
X570650Y402333D01*
G01X572667Y403333D02*
X573167Y402750D01*
X573833Y402416D01*
X574583Y402333D01*
X575250Y402416D01*
X575917Y402833D01*
X576333Y403333D01*
X576417Y403833D01*
X576250Y404416D01*
X575667Y404833D01*
X575083Y405000D01*
X574333D01*
G01X575083D02*
X575583Y405250D01*
X576000Y405666D01*
X576167Y406166D01*
X576000Y406666D01*
X575583Y407083D01*
X574833Y407333D01*
X574083Y407250D01*
X573333Y406916D01*
G01X580100Y402166D02*
X579933Y402250D01*
Y402416D01*
X580100Y402500D01*
X580267Y402416D01*
Y402250D01*
X580100Y402166D01*
G01Y404416D02*
X579933Y404500D01*
Y404666D01*
X580100Y404750D01*
X580267Y404666D01*
Y404500D01*
X580100Y404416D01*
G01X584117Y406500D02*
X584617Y407000D01*
X585200Y407250D01*
X585867Y407333D01*
X586700Y407166D01*
X587283Y406750D01*
X587450Y406250D01*
X587367Y405750D01*
X587033Y405333D01*
X585367Y404500D01*
X584617Y403916D01*
X584117Y403083D01*
X583950Y402333D01*
X587450D01*
G01X589467Y403083D02*
X589967Y402666D01*
X590550Y402416D01*
X591300Y402333D01*
X592050Y402500D01*
X592633Y402833D01*
X593050Y403416D01*
X593133Y404083D01*
X592967Y404750D01*
X592550Y405166D01*
X591967Y405500D01*
X591383Y405583D01*
X590800Y405500D01*
X590050Y405166D01*
X590300Y407333D01*
X592550D01*
G01X594733Y402333D02*
Y407333D01*
X596900Y403166D01*
X599067Y407333D01*
Y402333D01*
G01X600750D02*
Y407333D01*
G01X604250D02*
Y402333D01*
G01Y404833D02*
X600750D01*
G01X606517Y407333D02*
X609683D01*
X606517Y402333D01*
X609683D01*
G01X562717Y387000D02*
Y389500D01*
X563717D01*
X564050Y389375D01*
X564300Y389083D01*
X564383Y388750D01*
X564300Y388417D01*
X564092Y388167D01*
X563717Y388042D01*
X562717D01*
G01X565817Y387000D02*
Y389500D01*
X566858D01*
X567192Y389375D01*
X567400Y389208D01*
X567483Y388875D01*
X567400Y388542D01*
X567150Y388333D01*
X566858Y388208D01*
X565817D01*
G01X566858D02*
X567483Y387000D01*
G01X569667D02*
X569750Y387542D01*
X569875Y388000D01*
X570042Y388417D01*
X570250Y388875D01*
X570583Y389500D01*
X568917D01*
G01X572767Y387000D02*
X572850Y387542D01*
X572975Y388000D01*
X573142Y388417D01*
X573350Y388875D01*
X573683Y389500D01*
X572017D01*
G01X559500Y388017D02*
X557000D01*
Y389017D01*
X557125Y389350D01*
X557417Y389600D01*
X557750Y389683D01*
X558083Y389600D01*
X558333Y389392D01*
X558458Y389017D01*
Y388017D01*
G01X559500Y391117D02*
X557000D01*
Y392158D01*
X557125Y392492D01*
X557292Y392700D01*
X557625Y392783D01*
X557958Y392700D01*
X558167Y392450D01*
X558292Y392158D01*
Y391117D01*
G01Y392158D02*
X559500Y392783D01*
G01Y394967D02*
X558958Y395050D01*
X558500Y395175D01*
X558083Y395342D01*
X557625Y395550D01*
X557000Y395883D01*
Y394217D01*
G01X559125Y397233D02*
X559333Y397483D01*
X559458Y397775D01*
X559500Y398150D01*
X559417Y398525D01*
X559250Y398817D01*
X558958Y399025D01*
X558625Y399067D01*
X558292Y398983D01*
X558083Y398775D01*
X557917Y398483D01*
X557875Y398192D01*
X557917Y397900D01*
X558083Y397525D01*
X557000Y397650D01*
Y398775D01*
G01X560531Y386280D02*
X556531D01*
Y378880D01*
G01X555833Y617500D02*
Y622500D01*
X557917D01*
X558583Y622250D01*
X559000Y621917D01*
X559167Y621250D01*
X559000Y620583D01*
X558500Y620167D01*
X557917Y619917D01*
X555833D01*
G01X557917D02*
X559167Y617500D01*
G01X563100D02*
X562433Y617583D01*
X561850Y617917D01*
X561350Y618417D01*
X561017Y619000D01*
X560850Y619667D01*
Y620333D01*
X561017Y621000D01*
X561350Y621583D01*
X561850Y622083D01*
X562433Y622417D01*
X563100Y622500D01*
X563767Y622417D01*
X564350Y622083D01*
X564850Y621583D01*
X565183Y621000D01*
X565350Y620333D01*
Y619667D01*
X565183Y619000D01*
X564850Y618417D01*
X564350Y617917D01*
X563767Y617583D01*
X563100Y617500D01*
G01X566950D02*
Y622500D01*
G01X570450D02*
Y617500D01*
G01Y620000D02*
X566950D01*
G01X572550Y618167D02*
X573217Y617750D01*
X573967Y617500D01*
X574633D01*
X575300Y617750D01*
X575800Y618167D01*
X576050Y618750D01*
X575883Y619333D01*
X575467Y619833D01*
X574717Y620167D01*
X573717Y620333D01*
X573133Y620667D01*
X572883Y621250D01*
X573050Y621833D01*
X573467Y622250D01*
X574050Y622500D01*
X574633D01*
X575217Y622333D01*
X575717Y621917D01*
G01X586833Y620417D02*
X586250Y620750D01*
X585750Y620833D01*
X585083Y620667D01*
X584583Y620333D01*
X584250Y619750D01*
X584167Y619167D01*
X584250Y618583D01*
X584583Y618083D01*
X585083Y617667D01*
X585750Y617500D01*
X586333Y617667D01*
X586833Y618000D01*
G01X591100Y617500D02*
X590600Y617583D01*
X590100Y617917D01*
X589767Y618500D01*
X589600Y619167D01*
X589767Y619833D01*
X590100Y620417D01*
X590600Y620750D01*
X591100Y620833D01*
X591600Y620750D01*
X592100Y620417D01*
X592433Y619833D01*
X592517Y619167D01*
X592433Y618500D01*
X592100Y617917D01*
X591600Y617583D01*
X591100Y617500D01*
G01X594200D02*
Y620833D01*
G01Y619917D02*
X594450Y620333D01*
X594867Y620667D01*
X595450Y620833D01*
X596033Y620667D01*
X596450Y620333D01*
X596700Y619917D01*
Y617500D01*
G01Y619917D02*
X596950Y620333D01*
X597367Y620667D01*
X597950Y620833D01*
X598533Y620667D01*
X598950Y620333D01*
X599200Y619833D01*
Y617500D01*
G01X600800Y615833D02*
Y620833D01*
G01Y620083D02*
X601217Y620500D01*
X601633Y620750D01*
X602300Y620833D01*
X602883Y620750D01*
X603467Y620333D01*
X603717Y619750D01*
X603800Y619167D01*
X603717Y618583D01*
X603467Y618000D01*
X602967Y617667D01*
X602300Y617500D01*
X601717Y617583D01*
X601133Y617833D01*
X600800Y618167D01*
G01X607900Y617500D02*
Y622500D01*
G01X613500Y620833D02*
Y617500D01*
G01Y622167D02*
X613333Y622250D01*
Y622417D01*
X613500Y622500D01*
X613667Y622417D01*
Y622250D01*
X613500Y622167D01*
G01X620600Y617500D02*
Y620833D01*
G01Y620250D02*
X620267Y620583D01*
X619767Y620750D01*
X619183Y620833D01*
X618600Y620667D01*
X618100Y620333D01*
X617767Y619833D01*
X617600Y619167D01*
X617767Y618500D01*
X618100Y618000D01*
X618600Y617667D01*
X619183Y617500D01*
X619767Y617583D01*
X620267Y617833D01*
X620600Y618167D01*
G01X623283Y617500D02*
Y620833D01*
G01Y620000D02*
X623617Y620417D01*
X624117Y620750D01*
X624783Y620833D01*
X625367Y620750D01*
X625867Y620417D01*
X626117Y619833D01*
Y617500D01*
G01X631633Y620417D02*
X631050Y620750D01*
X630550Y620833D01*
X629883Y620667D01*
X629383Y620333D01*
X629050Y619750D01*
X628967Y619167D01*
X629050Y618583D01*
X629383Y618083D01*
X629883Y617667D01*
X630550Y617500D01*
X631133Y617667D01*
X631633Y618000D01*
G01X634650Y619750D02*
X637317D01*
X637067Y620333D01*
X636650Y620667D01*
X636067Y620833D01*
X635483Y620750D01*
X634983Y620500D01*
X634650Y619917D01*
X634483Y619417D01*
Y618917D01*
X634650Y618417D01*
X635067Y617917D01*
X635567Y617583D01*
X636150Y617500D01*
X636733Y617667D01*
X637317Y618167D01*
G01X556085Y642280D02*
X558335D01*
G01X556085Y636400D02*
Y642280D01*
G01X558335Y636400D02*
X556085D01*
G01X557435Y639435D02*
X556085D01*
G01X561835Y638070D02*
Y642280D01*
G01X561605Y637185D02*
X561835Y638070D01*
G01X561155Y636600D02*
X561605Y637185D01*
G01X560590Y636400D02*
X561155Y636600D01*
G01X560025D02*
X560590Y636400D01*
G01X559575Y637185D02*
X560025Y636600D01*
G01X559350Y638070D02*
X559575Y637185D01*
G01X559350Y642280D02*
Y638070D01*
G01X567800Y636495D02*
X567355Y636400D01*
G01X568200Y636890D02*
X567800Y636495D01*
G01X568535Y637480D02*
X568200Y636890D01*
G01X568765Y638165D02*
X568535Y637480D01*
G01X568875Y638950D02*
X568765Y638165D01*
G01X568875Y639730D02*
Y638950D01*
G01X568765Y640515D02*
X568875Y639730D01*
G01X568535Y641200D02*
X568765Y640515D01*
G01X568200Y641790D02*
X568535Y641200D01*
G01X567800Y642185D02*
X568200Y641790D01*
G01X567355Y642280D02*
X567800Y642185D01*
G01X566905D02*
X567355Y642280D01*
G01X566505Y641790D02*
X566905Y642185D01*
G01X566170Y641200D02*
X566505Y641790D01*
G01X565940Y640515D02*
X566170Y641200D01*
G01X565830Y639730D02*
X565940Y640515D01*
G01X565830Y638950D02*
Y639730D01*
G01X565940Y638165D02*
X565830Y638950D01*
G01X566170Y637480D02*
X565940Y638165D01*
G01X566505Y636890D02*
X566170Y637480D01*
G01X566905Y636495D02*
X566505Y636890D01*
G01X567355Y636400D02*
X566905Y636495D01*
G01X569780Y636400D02*
Y640320D01*
G01X570000Y639830D02*
X570335Y640220D01*
G01X569780Y639340D02*
X570000Y639830D01*
G01X571923Y766965D02*
X569423D01*
Y768006D01*
X569548Y768340D01*
X569715Y768548D01*
X570048Y768631D01*
X570381Y768548D01*
X570590Y768298D01*
X570715Y768006D01*
Y766965D01*
G01Y768006D02*
X571923Y768631D01*
G01Y770815D02*
X571381Y770898D01*
X570923Y771023D01*
X570506Y771190D01*
X570048Y771398D01*
X569423Y771731D01*
Y770065D01*
G01X571631Y773290D02*
X571840Y773581D01*
X571923Y773915D01*
X571840Y774248D01*
X571590Y774540D01*
X571215Y774748D01*
X570840Y774831D01*
X570381D01*
X570006Y774748D01*
X569673Y774540D01*
X569506Y774290D01*
X569423Y773998D01*
X569506Y773665D01*
X569673Y773415D01*
X569923Y773248D01*
X570256Y773165D01*
X570548Y773248D01*
X570840Y773456D01*
X571006Y773706D01*
X571048Y773998D01*
X570965Y774331D01*
X570756Y774581D01*
X570381Y774831D01*
G01X571923Y777015D02*
X571381Y777098D01*
X570923Y777223D01*
X570506Y777390D01*
X570048Y777598D01*
X569423Y777931D01*
Y776265D01*
G01X571923Y780698D02*
X569423D01*
X571215Y779156D01*
Y781240D01*
G01X555923Y766965D02*
X553423D01*
Y768006D01*
X553548Y768340D01*
X553715Y768548D01*
X554048Y768631D01*
X554381Y768548D01*
X554590Y768298D01*
X554715Y768006D01*
Y766965D01*
G01Y768006D02*
X555923Y768631D01*
G01Y770815D02*
X555381Y770898D01*
X554923Y771023D01*
X554506Y771190D01*
X554048Y771398D01*
X553423Y771731D01*
Y770065D01*
G01X555631Y773290D02*
X555840Y773581D01*
X555923Y773915D01*
X555840Y774248D01*
X555590Y774540D01*
X555215Y774748D01*
X554840Y774831D01*
X554381D01*
X554006Y774748D01*
X553673Y774540D01*
X553506Y774290D01*
X553423Y773998D01*
X553506Y773665D01*
X553673Y773415D01*
X553923Y773248D01*
X554256Y773165D01*
X554548Y773248D01*
X554840Y773456D01*
X555006Y773706D01*
X555048Y773998D01*
X554965Y774331D01*
X554756Y774581D01*
X554381Y774831D01*
G01X554881Y776306D02*
X554590Y776598D01*
X554423Y776848D01*
X554340Y777181D01*
X554423Y777473D01*
X554590Y777681D01*
X554840Y777848D01*
X555131Y777890D01*
X555381Y777848D01*
X555631Y777681D01*
X555840Y777431D01*
X555923Y777140D01*
X555840Y776806D01*
X555590Y776515D01*
X555215Y776348D01*
X554798Y776306D01*
X554256Y776390D01*
X553965Y776515D01*
X553673Y776723D01*
X553465Y777015D01*
X553423Y777306D01*
X553506Y777598D01*
X553715Y777806D01*
G01X555923Y780198D02*
X555881Y780490D01*
X555756Y780823D01*
X555548Y781031D01*
X555256Y781115D01*
X554965Y781031D01*
X554715Y780781D01*
X554590Y780406D01*
Y779990D01*
X554506Y779740D01*
X554298Y779531D01*
X554006Y779448D01*
X553715Y779573D01*
X553506Y779865D01*
X553423Y780198D01*
X553506Y780531D01*
X553715Y780823D01*
X554006Y780948D01*
X554298Y780865D01*
X554506Y780656D01*
X554590Y780406D01*
Y779990D01*
X554715Y779615D01*
X554965Y779365D01*
X555256Y779281D01*
X555548Y779365D01*
X555756Y779573D01*
X555881Y779906D01*
X555923Y780198D01*
G01X567923Y766965D02*
X565423D01*
Y768006D01*
X565548Y768340D01*
X565715Y768548D01*
X566048Y768631D01*
X566381Y768548D01*
X566590Y768298D01*
X566715Y768006D01*
Y766965D01*
G01Y768006D02*
X567923Y768631D01*
G01Y770815D02*
X567381Y770898D01*
X566923Y771023D01*
X566506Y771190D01*
X566048Y771398D01*
X565423Y771731D01*
Y770065D01*
G01X567631Y773290D02*
X567840Y773581D01*
X567923Y773915D01*
X567840Y774248D01*
X567590Y774540D01*
X567215Y774748D01*
X566840Y774831D01*
X566381D01*
X566006Y774748D01*
X565673Y774540D01*
X565506Y774290D01*
X565423Y773998D01*
X565506Y773665D01*
X565673Y773415D01*
X565923Y773248D01*
X566256Y773165D01*
X566548Y773248D01*
X566840Y773456D01*
X567006Y773706D01*
X567048Y773998D01*
X566965Y774331D01*
X566756Y774581D01*
X566381Y774831D01*
G01X567548Y776181D02*
X567756Y776431D01*
X567881Y776723D01*
X567923Y777098D01*
X567840Y777473D01*
X567673Y777765D01*
X567381Y777973D01*
X567048Y778015D01*
X566715Y777931D01*
X566506Y777723D01*
X566340Y777431D01*
X566298Y777140D01*
X566340Y776848D01*
X566506Y776473D01*
X565423Y776598D01*
Y777723D01*
G01X567631Y779490D02*
X567840Y779781D01*
X567923Y780115D01*
X567840Y780448D01*
X567590Y780740D01*
X567215Y780948D01*
X566840Y781031D01*
X566381D01*
X566006Y780948D01*
X565673Y780740D01*
X565506Y780490D01*
X565423Y780198D01*
X565506Y779865D01*
X565673Y779615D01*
X565923Y779448D01*
X566256Y779365D01*
X566548Y779448D01*
X566840Y779656D01*
X567006Y779906D01*
X567048Y780198D01*
X566965Y780531D01*
X566756Y780781D01*
X566381Y781031D01*
G01X551923Y766965D02*
X549423D01*
Y768006D01*
X549548Y768340D01*
X549715Y768548D01*
X550048Y768631D01*
X550381Y768548D01*
X550590Y768298D01*
X550715Y768006D01*
Y766965D01*
G01Y768006D02*
X551923Y768631D01*
G01Y770815D02*
X551381Y770898D01*
X550923Y771023D01*
X550506Y771190D01*
X550048Y771398D01*
X549423Y771731D01*
Y770065D01*
G01X551631Y773290D02*
X551840Y773581D01*
X551923Y773915D01*
X551840Y774248D01*
X551590Y774540D01*
X551215Y774748D01*
X550840Y774831D01*
X550381D01*
X550006Y774748D01*
X549673Y774540D01*
X549506Y774290D01*
X549423Y773998D01*
X549506Y773665D01*
X549673Y773415D01*
X549923Y773248D01*
X550256Y773165D01*
X550548Y773248D01*
X550840Y773456D01*
X551006Y773706D01*
X551048Y773998D01*
X550965Y774331D01*
X550756Y774581D01*
X550381Y774831D01*
G01X551548Y776181D02*
X551756Y776431D01*
X551881Y776723D01*
X551923Y777098D01*
X551840Y777473D01*
X551673Y777765D01*
X551381Y777973D01*
X551048Y778015D01*
X550715Y777931D01*
X550506Y777723D01*
X550340Y777431D01*
X550298Y777140D01*
X550340Y776848D01*
X550506Y776473D01*
X549423Y776598D01*
Y777723D01*
G01X551423Y779281D02*
X551715Y779531D01*
X551881Y779865D01*
X551923Y780240D01*
X551881Y780573D01*
X551673Y780906D01*
X551423Y781115D01*
X551173Y781156D01*
X550881Y781073D01*
X550673Y780781D01*
X550590Y780490D01*
Y780115D01*
G01Y780490D02*
X550465Y780740D01*
X550256Y780948D01*
X550006Y781031D01*
X549756Y780948D01*
X549548Y780740D01*
X549423Y780365D01*
X549465Y779990D01*
X549631Y779615D01*
G01X563923Y766965D02*
X561423D01*
Y768006D01*
X561548Y768340D01*
X561715Y768548D01*
X562048Y768631D01*
X562381Y768548D01*
X562590Y768298D01*
X562715Y768006D01*
Y766965D01*
G01Y768006D02*
X563923Y768631D01*
G01Y770815D02*
X563381Y770898D01*
X562923Y771023D01*
X562506Y771190D01*
X562048Y771398D01*
X561423Y771731D01*
Y770065D01*
G01X563631Y773290D02*
X563840Y773581D01*
X563923Y773915D01*
X563840Y774248D01*
X563590Y774540D01*
X563215Y774748D01*
X562840Y774831D01*
X562381D01*
X562006Y774748D01*
X561673Y774540D01*
X561506Y774290D01*
X561423Y773998D01*
X561506Y773665D01*
X561673Y773415D01*
X561923Y773248D01*
X562256Y773165D01*
X562548Y773248D01*
X562840Y773456D01*
X563006Y773706D01*
X563048Y773998D01*
X562965Y774331D01*
X562756Y774581D01*
X562381Y774831D01*
G01X563923Y777598D02*
X561423D01*
X563215Y776056D01*
Y778140D01*
G01X563923Y780698D02*
X561423D01*
X563215Y779156D01*
Y781240D01*
G01X547923Y766965D02*
X545423D01*
Y768006D01*
X545548Y768340D01*
X545715Y768548D01*
X546048Y768631D01*
X546381Y768548D01*
X546590Y768298D01*
X546715Y768006D01*
Y766965D01*
G01Y768006D02*
X547923Y768631D01*
G01Y770815D02*
X547381Y770898D01*
X546923Y771023D01*
X546506Y771190D01*
X546048Y771398D01*
X545423Y771731D01*
Y770065D01*
G01X547631Y773290D02*
X547840Y773581D01*
X547923Y773915D01*
X547840Y774248D01*
X547590Y774540D01*
X547215Y774748D01*
X546840Y774831D01*
X546381D01*
X546006Y774748D01*
X545673Y774540D01*
X545506Y774290D01*
X545423Y773998D01*
X545506Y773665D01*
X545673Y773415D01*
X545923Y773248D01*
X546256Y773165D01*
X546548Y773248D01*
X546840Y773456D01*
X547006Y773706D01*
X547048Y773998D01*
X546965Y774331D01*
X546756Y774581D01*
X546381Y774831D01*
G01X547423Y776181D02*
X547715Y776431D01*
X547881Y776765D01*
X547923Y777140D01*
X547881Y777473D01*
X547673Y777806D01*
X547423Y778015D01*
X547173Y778056D01*
X546881Y777973D01*
X546673Y777681D01*
X546590Y777390D01*
Y777015D01*
G01Y777390D02*
X546465Y777640D01*
X546256Y777848D01*
X546006Y777931D01*
X545756Y777848D01*
X545548Y777640D01*
X545423Y777265D01*
X545465Y776890D01*
X545631Y776515D01*
G01X547923Y780198D02*
X547881Y780490D01*
X547756Y780823D01*
X547548Y781031D01*
X547256Y781115D01*
X546965Y781031D01*
X546715Y780781D01*
X546590Y780406D01*
Y779990D01*
X546506Y779740D01*
X546298Y779531D01*
X546006Y779448D01*
X545715Y779573D01*
X545506Y779865D01*
X545423Y780198D01*
X545506Y780531D01*
X545715Y780823D01*
X546006Y780948D01*
X546298Y780865D01*
X546506Y780656D01*
X546590Y780406D01*
Y779990D01*
X546715Y779615D01*
X546965Y779365D01*
X547256Y779281D01*
X547548Y779365D01*
X547756Y779573D01*
X547881Y779906D01*
X547923Y780198D01*
G01X559923Y766965D02*
X557423D01*
Y768006D01*
X557548Y768340D01*
X557715Y768548D01*
X558048Y768631D01*
X558381Y768548D01*
X558590Y768298D01*
X558715Y768006D01*
Y766965D01*
G01Y768006D02*
X559923Y768631D01*
G01Y770815D02*
X559381Y770898D01*
X558923Y771023D01*
X558506Y771190D01*
X558048Y771398D01*
X557423Y771731D01*
Y770065D01*
G01X559631Y773290D02*
X559840Y773581D01*
X559923Y773915D01*
X559840Y774248D01*
X559590Y774540D01*
X559215Y774748D01*
X558840Y774831D01*
X558381D01*
X558006Y774748D01*
X557673Y774540D01*
X557506Y774290D01*
X557423Y773998D01*
X557506Y773665D01*
X557673Y773415D01*
X557923Y773248D01*
X558256Y773165D01*
X558548Y773248D01*
X558840Y773456D01*
X559006Y773706D01*
X559048Y773998D01*
X558965Y774331D01*
X558756Y774581D01*
X558381Y774831D01*
G01X557840Y776306D02*
X557590Y776556D01*
X557465Y776848D01*
X557423Y777181D01*
X557506Y777598D01*
X557715Y777890D01*
X557965Y777973D01*
X558215Y777931D01*
X558423Y777765D01*
X558840Y776931D01*
X559131Y776556D01*
X559548Y776306D01*
X559923Y776223D01*
Y777973D01*
G01X557840Y779406D02*
X557590Y779656D01*
X557465Y779948D01*
X557423Y780281D01*
X557506Y780698D01*
X557715Y780990D01*
X557965Y781073D01*
X558215Y781031D01*
X558423Y780865D01*
X558840Y780031D01*
X559131Y779656D01*
X559548Y779406D01*
X559923Y779323D01*
Y781073D01*
G01X543923Y766965D02*
X541423D01*
Y768006D01*
X541548Y768340D01*
X541715Y768548D01*
X542048Y768631D01*
X542381Y768548D01*
X542590Y768298D01*
X542715Y768006D01*
Y766965D01*
G01Y768006D02*
X543923Y768631D01*
G01Y770815D02*
X543381Y770898D01*
X542923Y771023D01*
X542506Y771190D01*
X542048Y771398D01*
X541423Y771731D01*
Y770065D01*
G01X543631Y773290D02*
X543840Y773581D01*
X543923Y773915D01*
X543840Y774248D01*
X543590Y774540D01*
X543215Y774748D01*
X542840Y774831D01*
X542381D01*
X542006Y774748D01*
X541673Y774540D01*
X541506Y774290D01*
X541423Y773998D01*
X541506Y773665D01*
X541673Y773415D01*
X541923Y773248D01*
X542256Y773165D01*
X542548Y773248D01*
X542840Y773456D01*
X543006Y773706D01*
X543048Y773998D01*
X542965Y774331D01*
X542756Y774581D01*
X542381Y774831D01*
G01X541840Y776306D02*
X541590Y776556D01*
X541465Y776848D01*
X541423Y777181D01*
X541506Y777598D01*
X541715Y777890D01*
X541965Y777973D01*
X542215Y777931D01*
X542423Y777765D01*
X542840Y776931D01*
X543131Y776556D01*
X543548Y776306D01*
X543923Y776223D01*
Y777973D01*
G01Y780198D02*
X541423D01*
X541923Y779698D01*
G01X543923D02*
Y780698D01*
G01X540119Y767167D02*
X537619D01*
Y768208D01*
X537744Y768542D01*
X537911Y768750D01*
X538244Y768833D01*
X538577Y768750D01*
X538786Y768500D01*
X538911Y768208D01*
Y767167D01*
G01Y768208D02*
X540119Y768833D01*
G01X539744Y770183D02*
X539952Y770433D01*
X540077Y770725D01*
X540119Y771100D01*
X540036Y771475D01*
X539869Y771767D01*
X539577Y771975D01*
X539244Y772017D01*
X538911Y771933D01*
X538702Y771725D01*
X538536Y771433D01*
X538494Y771142D01*
X538536Y770850D01*
X538702Y770475D01*
X537619Y770600D01*
Y771725D01*
G01X540119Y774700D02*
X537619D01*
X539411Y773158D01*
Y775242D01*
G01X540119Y777217D02*
X539577Y777300D01*
X539119Y777425D01*
X538702Y777592D01*
X538244Y777800D01*
X537619Y778133D01*
Y776467D01*
G01X541254Y797141D02*
X538754D01*
Y798182D01*
X538879Y798516D01*
X539046Y798724D01*
X539379Y798807D01*
X539712Y798724D01*
X539921Y798474D01*
X540046Y798182D01*
Y797141D01*
G01Y798182D02*
X541254Y798807D01*
G01Y800991D02*
X540712Y801074D01*
X540254Y801199D01*
X539837Y801366D01*
X539379Y801574D01*
X538754Y801907D01*
Y800241D01*
G01X540962Y803466D02*
X541171Y803757D01*
X541254Y804091D01*
X541171Y804424D01*
X540921Y804716D01*
X540546Y804924D01*
X540171Y805007D01*
X539712D01*
X539337Y804924D01*
X539004Y804716D01*
X538837Y804466D01*
X538754Y804174D01*
X538837Y803841D01*
X539004Y803591D01*
X539254Y803424D01*
X539587Y803341D01*
X539879Y803424D01*
X540171Y803632D01*
X540337Y803882D01*
X540379Y804174D01*
X540296Y804507D01*
X540087Y804757D01*
X539712Y805007D01*
G01X540879Y806357D02*
X541087Y806607D01*
X541212Y806899D01*
X541254Y807274D01*
X541171Y807649D01*
X541004Y807941D01*
X540712Y808149D01*
X540379Y808191D01*
X540046Y808107D01*
X539837Y807899D01*
X539671Y807607D01*
X539629Y807316D01*
X539671Y807024D01*
X539837Y806649D01*
X538754Y806774D01*
Y807899D01*
G01X540212Y809582D02*
X539921Y809874D01*
X539754Y810124D01*
X539671Y810457D01*
X539754Y810749D01*
X539921Y810957D01*
X540171Y811124D01*
X540462Y811166D01*
X540712Y811124D01*
X540962Y810957D01*
X541171Y810707D01*
X541254Y810416D01*
X541171Y810082D01*
X540921Y809791D01*
X540546Y809624D01*
X540129Y809582D01*
X539587Y809666D01*
X539296Y809791D01*
X539004Y809999D01*
X538796Y810291D01*
X538754Y810582D01*
X538837Y810874D01*
X539046Y811082D01*
G01X545254Y797141D02*
X542754D01*
Y798182D01*
X542879Y798516D01*
X543046Y798724D01*
X543379Y798807D01*
X543712Y798724D01*
X543921Y798474D01*
X544046Y798182D01*
Y797141D01*
G01Y798182D02*
X545254Y798807D01*
G01Y800991D02*
X544712Y801074D01*
X544254Y801199D01*
X543837Y801366D01*
X543379Y801574D01*
X542754Y801907D01*
Y800241D01*
G01X544962Y803466D02*
X545171Y803757D01*
X545254Y804091D01*
X545171Y804424D01*
X544921Y804716D01*
X544546Y804924D01*
X544171Y805007D01*
X543712D01*
X543337Y804924D01*
X543004Y804716D01*
X542837Y804466D01*
X542754Y804174D01*
X542837Y803841D01*
X543004Y803591D01*
X543254Y803424D01*
X543587Y803341D01*
X543879Y803424D01*
X544171Y803632D01*
X544337Y803882D01*
X544379Y804174D01*
X544296Y804507D01*
X544087Y804757D01*
X543712Y805007D01*
G01X545254Y807774D02*
X542754D01*
X544546Y806232D01*
Y808316D01*
G01X542754Y810374D02*
X542837Y810041D01*
X543046Y809791D01*
X543296Y809624D01*
X543629Y809499D01*
X544004Y809457D01*
X544379Y809499D01*
X544712Y809624D01*
X544962Y809791D01*
X545171Y810041D01*
X545254Y810374D01*
X545171Y810707D01*
X544962Y810957D01*
X544712Y811124D01*
X544379Y811249D01*
X544004Y811291D01*
X543629Y811249D01*
X543296Y811124D01*
X543046Y810957D01*
X542837Y810707D01*
X542754Y810374D01*
G01X549254Y797141D02*
X546754D01*
Y798182D01*
X546879Y798516D01*
X547046Y798724D01*
X547379Y798807D01*
X547712Y798724D01*
X547921Y798474D01*
X548046Y798182D01*
Y797141D01*
G01Y798182D02*
X549254Y798807D01*
G01Y800991D02*
X548712Y801074D01*
X548254Y801199D01*
X547837Y801366D01*
X547379Y801574D01*
X546754Y801907D01*
Y800241D01*
G01X548962Y803466D02*
X549171Y803757D01*
X549254Y804091D01*
X549171Y804424D01*
X548921Y804716D01*
X548546Y804924D01*
X548171Y805007D01*
X547712D01*
X547337Y804924D01*
X547004Y804716D01*
X546837Y804466D01*
X546754Y804174D01*
X546837Y803841D01*
X547004Y803591D01*
X547254Y803424D01*
X547587Y803341D01*
X547879Y803424D01*
X548171Y803632D01*
X548337Y803882D01*
X548379Y804174D01*
X548296Y804507D01*
X548087Y804757D01*
X547712Y805007D01*
G01X547171Y806482D02*
X546921Y806732D01*
X546796Y807024D01*
X546754Y807357D01*
X546837Y807774D01*
X547046Y808066D01*
X547296Y808149D01*
X547546Y808107D01*
X547754Y807941D01*
X548171Y807107D01*
X548462Y806732D01*
X548879Y806482D01*
X549254Y806399D01*
Y808149D01*
G01X548212Y809582D02*
X547921Y809874D01*
X547754Y810124D01*
X547671Y810457D01*
X547754Y810749D01*
X547921Y810957D01*
X548171Y811124D01*
X548462Y811166D01*
X548712Y811124D01*
X548962Y810957D01*
X549171Y810707D01*
X549254Y810416D01*
X549171Y810082D01*
X548921Y809791D01*
X548546Y809624D01*
X548129Y809582D01*
X547587Y809666D01*
X547296Y809791D01*
X547004Y809999D01*
X546796Y810291D01*
X546754Y810582D01*
X546837Y810874D01*
X547046Y811082D01*
G01X543909Y816818D02*
X543784Y816568D01*
X543701Y816276D01*
Y815943D01*
X543826Y815568D01*
X544034Y815276D01*
X544284Y815068D01*
X544701Y814901D01*
X545076Y814859D01*
X545451Y814943D01*
X545701Y815068D01*
X545951Y815318D01*
X546118Y815609D01*
X546201Y815901D01*
Y816193D01*
X546118Y816484D01*
X545993Y816734D01*
X545826Y816943D01*
G01X545701Y818084D02*
X545993Y818334D01*
X546159Y818668D01*
X546201Y819043D01*
X546159Y819376D01*
X545951Y819709D01*
X545701Y819918D01*
X545451Y819959D01*
X545159Y819876D01*
X544951Y819584D01*
X544868Y819293D01*
Y818918D01*
G01Y819293D02*
X544743Y819543D01*
X544534Y819751D01*
X544284Y819834D01*
X544034Y819751D01*
X543826Y819543D01*
X543701Y819168D01*
X543743Y818793D01*
X543909Y818418D01*
G01X546201Y822601D02*
X543701D01*
X545493Y821059D01*
Y823143D01*
G01X546201Y825701D02*
X543701D01*
X545493Y824159D01*
Y826243D01*
G01X547909Y816818D02*
X547784Y816568D01*
X547701Y816276D01*
Y815943D01*
X547826Y815568D01*
X548034Y815276D01*
X548284Y815068D01*
X548701Y814901D01*
X549076Y814859D01*
X549451Y814943D01*
X549701Y815068D01*
X549951Y815318D01*
X550118Y815609D01*
X550201Y815901D01*
Y816193D01*
X550118Y816484D01*
X549993Y816734D01*
X549826Y816943D01*
G01X549701Y818084D02*
X549993Y818334D01*
X550159Y818668D01*
X550201Y819043D01*
X550159Y819376D01*
X549951Y819709D01*
X549701Y819918D01*
X549451Y819959D01*
X549159Y819876D01*
X548951Y819584D01*
X548868Y819293D01*
Y818918D01*
G01Y819293D02*
X548743Y819543D01*
X548534Y819751D01*
X548284Y819834D01*
X548034Y819751D01*
X547826Y819543D01*
X547701Y819168D01*
X547743Y818793D01*
X547909Y818418D01*
G01X550201Y822601D02*
X547701D01*
X549493Y821059D01*
Y823143D01*
G01X549701Y824284D02*
X549993Y824534D01*
X550159Y824868D01*
X550201Y825243D01*
X550159Y825576D01*
X549951Y825909D01*
X549701Y826118D01*
X549451Y826159D01*
X549159Y826076D01*
X548951Y825784D01*
X548868Y825493D01*
Y825118D01*
G01Y825493D02*
X548743Y825743D01*
X548534Y825951D01*
X548284Y826034D01*
X548034Y825951D01*
X547826Y825743D01*
X547701Y825368D01*
X547743Y824993D01*
X547909Y824618D01*
G01X556994Y816093D02*
X556869Y815843D01*
X556786Y815551D01*
Y815218D01*
X556911Y814843D01*
X557119Y814551D01*
X557369Y814343D01*
X557786Y814176D01*
X558161Y814134D01*
X558536Y814218D01*
X558786Y814343D01*
X559036Y814593D01*
X559203Y814884D01*
X559286Y815176D01*
Y815468D01*
X559203Y815759D01*
X559078Y816009D01*
X558911Y816218D01*
G01X558786Y817359D02*
X559078Y817609D01*
X559244Y817943D01*
X559286Y818318D01*
X559244Y818651D01*
X559036Y818984D01*
X558786Y819193D01*
X558536Y819234D01*
X558244Y819151D01*
X558036Y818859D01*
X557953Y818568D01*
Y818193D01*
G01Y818568D02*
X557828Y818818D01*
X557619Y819026D01*
X557369Y819109D01*
X557119Y819026D01*
X556911Y818818D01*
X556786Y818443D01*
X556828Y818068D01*
X556994Y817693D01*
G01X559286Y821876D02*
X556786D01*
X558578Y820334D01*
Y822418D01*
G01X557203Y823684D02*
X556953Y823934D01*
X556828Y824226D01*
X556786Y824559D01*
X556869Y824976D01*
X557078Y825268D01*
X557328Y825351D01*
X557578Y825309D01*
X557786Y825143D01*
X558203Y824309D01*
X558494Y823934D01*
X558911Y823684D01*
X559286Y823601D01*
Y825351D01*
G01X560994Y816093D02*
X560869Y815843D01*
X560786Y815551D01*
Y815218D01*
X560911Y814843D01*
X561119Y814551D01*
X561369Y814343D01*
X561786Y814176D01*
X562161Y814134D01*
X562536Y814218D01*
X562786Y814343D01*
X563036Y814593D01*
X563203Y814884D01*
X563286Y815176D01*
Y815468D01*
X563203Y815759D01*
X563078Y816009D01*
X562911Y816218D01*
G01X562786Y817359D02*
X563078Y817609D01*
X563244Y817943D01*
X563286Y818318D01*
X563244Y818651D01*
X563036Y818984D01*
X562786Y819193D01*
X562536Y819234D01*
X562244Y819151D01*
X562036Y818859D01*
X561953Y818568D01*
Y818193D01*
G01Y818568D02*
X561828Y818818D01*
X561619Y819026D01*
X561369Y819109D01*
X561119Y819026D01*
X560911Y818818D01*
X560786Y818443D01*
X560828Y818068D01*
X560994Y817693D01*
G01X563286Y821876D02*
X560786D01*
X562578Y820334D01*
Y822418D01*
G01X563286Y824476D02*
X560786D01*
X561286Y823976D01*
G01X563286D02*
Y824976D01*
G01X569593Y816093D02*
X569468Y815843D01*
X569385Y815551D01*
Y815218D01*
X569510Y814843D01*
X569718Y814551D01*
X569968Y814343D01*
X570385Y814176D01*
X570760Y814134D01*
X571135Y814218D01*
X571385Y814343D01*
X571635Y814593D01*
X571802Y814884D01*
X571885Y815176D01*
Y815468D01*
X571802Y815759D01*
X571677Y816009D01*
X571510Y816218D01*
G01X571385Y817359D02*
X571677Y817609D01*
X571843Y817943D01*
X571885Y818318D01*
X571843Y818651D01*
X571635Y818984D01*
X571385Y819193D01*
X571135Y819234D01*
X570843Y819151D01*
X570635Y818859D01*
X570552Y818568D01*
Y818193D01*
G01Y818568D02*
X570427Y818818D01*
X570218Y819026D01*
X569968Y819109D01*
X569718Y819026D01*
X569510Y818818D01*
X569385Y818443D01*
X569427Y818068D01*
X569593Y817693D01*
G01X571885Y821376D02*
X569385D01*
X569885Y820876D01*
G01X571885D02*
Y821876D01*
G01X571510Y823559D02*
X571718Y823809D01*
X571843Y824101D01*
X571885Y824476D01*
X571802Y824851D01*
X571635Y825143D01*
X571343Y825351D01*
X571010Y825393D01*
X570677Y825309D01*
X570468Y825101D01*
X570302Y824809D01*
X570260Y824518D01*
X570302Y824226D01*
X570468Y823851D01*
X569385Y823976D01*
Y825101D01*
G01X581390Y-13114D02*
Y-9114D01*
X582990D01*
X583523Y-9314D01*
X583923Y-9781D01*
X584056Y-10314D01*
X583923Y-10847D01*
X583590Y-11247D01*
X582990Y-11447D01*
X581390D01*
G01X586390Y-13114D02*
Y-10447D01*
G01Y-10981D02*
X586723Y-10714D01*
X587056Y-10514D01*
X587523Y-10447D01*
X587856Y-10514D01*
X588256Y-10714D01*
G01X590923Y-11314D02*
X593056D01*
X592856Y-10847D01*
X592523Y-10581D01*
X592056Y-10447D01*
X591590Y-10514D01*
X591190Y-10714D01*
X590923Y-11181D01*
X590790Y-11581D01*
Y-11981D01*
X590923Y-12381D01*
X591256Y-12781D01*
X591656Y-13047D01*
X592123Y-13114D01*
X592590Y-12981D01*
X593056Y-12581D01*
G01X595523Y-12647D02*
X595856Y-12914D01*
X596323Y-13114D01*
X596723D01*
X597123Y-12981D01*
X597390Y-12781D01*
X597523Y-12514D01*
X597456Y-12114D01*
X597190Y-11914D01*
X595990Y-11514D01*
X595723Y-11047D01*
X595856Y-10714D01*
X596123Y-10514D01*
X596523Y-10447D01*
X596923Y-10514D01*
X597323Y-10714D01*
G01X600123Y-12647D02*
X600456Y-12914D01*
X600923Y-13114D01*
X601323D01*
X601723Y-12981D01*
X601990Y-12781D01*
X602123Y-12514D01*
X602056Y-12114D01*
X601790Y-11914D01*
X600590Y-11514D01*
X600323Y-11047D01*
X600456Y-10714D01*
X600723Y-10514D01*
X601123Y-10447D01*
X601523Y-10514D01*
X601923Y-10714D01*
G01X609056Y-13114D02*
Y-9114D01*
X611590D01*
G01X610656Y-11047D02*
X609056D01*
G01X614923Y-10447D02*
Y-13114D01*
G01Y-9381D02*
X614790Y-9314D01*
Y-9181D01*
X614923Y-9114D01*
X615056Y-9181D01*
Y-9314D01*
X614923Y-9381D01*
G01X619523Y-9114D02*
Y-13114D01*
G01X618590Y-10447D02*
X620456D01*
G01X586550Y141700D02*
X586217Y141742D01*
X585925Y141908D01*
X585675Y142158D01*
X585508Y142450D01*
X585425Y142783D01*
Y143117D01*
X585508Y143450D01*
X585675Y143742D01*
X585925Y143992D01*
X586217Y144158D01*
X586550Y144200D01*
X586883Y144158D01*
X587175Y143992D01*
X587425Y143742D01*
X587592Y143450D01*
X587675Y143117D01*
Y142783D01*
X587592Y142450D01*
X587425Y142158D01*
X587175Y141908D01*
X586883Y141742D01*
X586550Y141700D01*
G01X588692D02*
Y144200D01*
X590608Y141700D01*
Y144200D01*
G01X577250Y113597D02*
X577650Y113847D01*
X577950Y114263D01*
X578150Y114847D01*
X577950Y115347D01*
X577550Y115680D01*
X576850Y115930D01*
X574150D01*
Y110930D01*
X577450D01*
X578150Y111263D01*
X578550Y111763D01*
X578750Y112347D01*
X578550Y112930D01*
X577950Y113430D01*
X577250Y113597D01*
X574150D01*
G01X577400Y136500D02*
X584700D01*
G01X587900D02*
X593500D01*
G01X596200D02*
X601300D01*
G01Y122800D02*
X596000D01*
G01X593200D02*
X587700D01*
G01X584900D02*
X580800D01*
G01X583633Y163900D02*
Y162108D01*
X583800Y161733D01*
X584133Y161483D01*
X584550Y161400D01*
X584967Y161483D01*
X585300Y161733D01*
X585467Y162108D01*
Y163900D01*
G01X586900Y160567D02*
Y163067D01*
G01Y162692D02*
X587108Y162900D01*
X587317Y163025D01*
X587650Y163067D01*
X587942Y163025D01*
X588233Y162817D01*
X588358Y162525D01*
X588400Y162233D01*
X588358Y161942D01*
X588233Y161650D01*
X587983Y161483D01*
X587650Y161400D01*
X587358Y161442D01*
X587067Y161567D01*
X586900Y161733D01*
G01X590750Y161400D02*
Y163900D01*
G01X593850Y163067D02*
Y161400D01*
G01Y163733D02*
X593767Y163775D01*
Y163858D01*
X593850Y163900D01*
X593933Y163858D01*
Y163775D01*
X593850Y163733D01*
G01X596242Y161400D02*
Y163067D01*
G01Y162650D02*
X596408Y162858D01*
X596658Y163025D01*
X596992Y163067D01*
X597283Y163025D01*
X597533Y162858D01*
X597658Y162567D01*
Y161400D01*
G01X599342D02*
Y163900D01*
G01X600675Y163067D02*
X599342Y162108D01*
G01X599883Y162483D02*
X600758Y161400D01*
G01X605750Y163900D02*
X606750D01*
G01X606250D02*
Y161400D01*
G01X605750D02*
X606750D01*
G01X608642D02*
Y163067D01*
G01Y162650D02*
X608808Y162858D01*
X609058Y163025D01*
X609392Y163067D01*
X609683Y163025D01*
X609933Y162858D01*
X610058Y162567D01*
Y161400D01*
G01X613200Y163900D02*
Y161400D01*
G01Y161775D02*
X613033Y161567D01*
X612783Y161442D01*
X612492Y161400D01*
X612158Y161483D01*
X611908Y161692D01*
X611742Y161942D01*
X611700Y162233D01*
X611742Y162525D01*
X611908Y162775D01*
X612158Y162983D01*
X612492Y163067D01*
X612783Y163025D01*
X612992Y162942D01*
X613200Y162775D01*
G01X615550Y163067D02*
Y161400D01*
G01Y163733D02*
X615467Y163775D01*
Y163858D01*
X615550Y163900D01*
X615633Y163858D01*
Y163775D01*
X615550Y163733D01*
G01X619317Y162858D02*
X619025Y163025D01*
X618775Y163067D01*
X618442Y162983D01*
X618192Y162817D01*
X618025Y162525D01*
X617983Y162233D01*
X618025Y161942D01*
X618192Y161692D01*
X618442Y161483D01*
X618775Y161400D01*
X619067Y161483D01*
X619317Y161650D01*
G01X622500Y161400D02*
Y163067D01*
G01Y162775D02*
X622333Y162942D01*
X622083Y163025D01*
X621792Y163067D01*
X621500Y162983D01*
X621250Y162817D01*
X621083Y162567D01*
X621000Y162233D01*
X621083Y161900D01*
X621250Y161650D01*
X621500Y161483D01*
X621792Y161400D01*
X622083Y161442D01*
X622333Y161567D01*
X622500Y161733D01*
G01X624850Y163900D02*
Y161400D01*
G01X624267Y163067D02*
X625433D01*
G01X627950D02*
Y161400D01*
G01Y163733D02*
X627867Y163775D01*
Y163858D01*
X627950Y163900D01*
X628033Y163858D01*
Y163775D01*
X627950Y163733D01*
G01X631050Y161400D02*
X630800Y161442D01*
X630550Y161608D01*
X630383Y161900D01*
X630300Y162233D01*
X630383Y162567D01*
X630550Y162858D01*
X630800Y163025D01*
X631050Y163067D01*
X631300Y163025D01*
X631550Y162858D01*
X631717Y162567D01*
X631758Y162233D01*
X631717Y161900D01*
X631550Y161608D01*
X631300Y161442D01*
X631050Y161400D01*
G01X633442D02*
Y163067D01*
G01Y162650D02*
X633608Y162858D01*
X633858Y163025D01*
X634192Y163067D01*
X634483Y163025D01*
X634733Y162858D01*
X634858Y162567D01*
Y161400D01*
G01X637250Y161317D02*
X637167Y161358D01*
Y161442D01*
X637250Y161483D01*
X637333Y161442D01*
Y161358D01*
X637250Y161317D01*
G01Y162442D02*
X637167Y162483D01*
Y162567D01*
X637250Y162608D01*
X637333Y162567D01*
Y162483D01*
X637250Y162442D01*
G01X584667Y156900D02*
X583833D01*
Y153567D01*
X584667D01*
G01X586517Y156900D02*
Y154400D01*
X588183D01*
G01X591283D02*
X589617D01*
Y156900D01*
X591283D01*
G01X590617Y155692D02*
X589617D01*
G01X592633Y154400D02*
Y156900D01*
X593467D01*
X593800Y156775D01*
X594050Y156608D01*
X594258Y156358D01*
X594425Y156067D01*
X594467Y155650D01*
X594425Y155233D01*
X594258Y154942D01*
X594050Y154692D01*
X593800Y154525D01*
X593467Y154400D01*
X592633D01*
G01X596650D02*
Y156900D01*
X596150Y156400D01*
G01Y154400D02*
X597150D01*
G01X599750Y156900D02*
X599417Y156817D01*
X599167Y156608D01*
X599000Y156358D01*
X598875Y156025D01*
X598833Y155650D01*
X598875Y155275D01*
X599000Y154942D01*
X599167Y154692D01*
X599417Y154483D01*
X599750Y154400D01*
X600083Y154483D01*
X600333Y154692D01*
X600500Y154942D01*
X600625Y155275D01*
X600667Y155650D01*
X600625Y156025D01*
X600500Y156358D01*
X600333Y156608D01*
X600083Y156817D01*
X599750Y156900D01*
G01X602433Y153567D02*
X603267D01*
Y156900D01*
X602433D01*
G01X586550Y149400D02*
X586217Y149442D01*
X585925Y149608D01*
X585675Y149858D01*
X585508Y150150D01*
X585425Y150483D01*
Y150817D01*
X585508Y151150D01*
X585675Y151442D01*
X585925Y151692D01*
X586217Y151858D01*
X586550Y151900D01*
X586883Y151858D01*
X587175Y151692D01*
X587425Y151442D01*
X587592Y151150D01*
X587675Y150817D01*
Y150483D01*
X587592Y150150D01*
X587425Y149858D01*
X587175Y149608D01*
X586883Y149442D01*
X586550Y149400D01*
G01X588858D02*
Y151900D01*
X590442D01*
G01X589858Y150692D02*
X588858D01*
G01X591958Y149400D02*
Y151900D01*
X593542D01*
G01X592958Y150692D02*
X591958D01*
G01X593327Y169849D02*
X589993D01*
Y174849D01*
X593327D01*
G01X591993Y172432D02*
X589993D01*
G01X595593Y170849D02*
X596010Y170349D01*
X596510Y170016D01*
X597093Y169849D01*
X597760Y170016D01*
X598260Y170349D01*
X598760Y170849D01*
X598927Y171516D01*
Y174849D01*
G01X602860D02*
Y169849D01*
G01X600943Y174849D02*
X604777D01*
G01X606377Y169849D02*
X608460Y174849D01*
X610543Y169849D01*
G01X609793Y171599D02*
X607127D01*
G01X614560Y172349D02*
X616227D01*
Y170849D01*
X615727Y170349D01*
X615143Y170016D01*
X614310Y169849D01*
X613477Y170016D01*
X612893Y170349D01*
X612393Y170849D01*
X612060Y171432D01*
X611893Y172099D01*
Y172682D01*
X612060Y173182D01*
X612393Y173766D01*
X612893Y174266D01*
X613393Y174599D01*
X614060Y174849D01*
X614643D01*
X615310Y174682D01*
X615810Y174349D01*
G01X586450Y145600D02*
X586117Y145642D01*
X585825Y145808D01*
X585575Y146058D01*
X585408Y146350D01*
X585325Y146683D01*
Y147017D01*
X585408Y147350D01*
X585575Y147642D01*
X585825Y147892D01*
X586117Y148058D01*
X586450Y148100D01*
X586783Y148058D01*
X587075Y147892D01*
X587325Y147642D01*
X587492Y147350D01*
X587575Y147017D01*
Y146683D01*
X587492Y146350D01*
X587325Y146058D01*
X587075Y145808D01*
X586783Y145642D01*
X586450Y145600D01*
G01X588758D02*
Y148100D01*
X590342D01*
G01X589758Y146892D02*
X588758D01*
G01X591858Y145600D02*
Y148100D01*
X593442D01*
G01X592858Y146892D02*
X591858D01*
G01X573600Y159200D02*
X577600D01*
Y166600D01*
G01X595000Y207500D02*
Y199600D01*
G03X595100Y199500I100J0D01*
G01X634500D01*
Y240000D01*
X621000D01*
G01X609508Y208537D02*
X596108D01*
G01D02*
Y210537D01*
G01X581963Y188155D02*
Y190655D01*
X583004D01*
X583338Y190530D01*
X583546Y190363D01*
X583629Y190030D01*
X583546Y189697D01*
X583296Y189488D01*
X583004Y189363D01*
X581963D01*
G01X583004D02*
X583629Y188155D01*
G01X585813D02*
X585896Y188697D01*
X586021Y189155D01*
X586188Y189572D01*
X586396Y190030D01*
X586729Y190655D01*
X585063D01*
G01X588913Y188155D02*
X588996Y188697D01*
X589121Y189155D01*
X589288Y189572D01*
X589496Y190030D01*
X589829Y190655D01*
X588163D01*
G01X592096Y188155D02*
Y190655D01*
X591596Y190155D01*
G01Y188155D02*
X592596D01*
G01X582162Y179571D02*
Y182071D01*
X583203D01*
X583537Y181946D01*
X583745Y181779D01*
X583828Y181446D01*
X583745Y181113D01*
X583495Y180904D01*
X583203Y180779D01*
X582162D01*
G01X583203D02*
X583828Y179571D01*
G01X586012D02*
X586095Y180113D01*
X586220Y180571D01*
X586387Y180988D01*
X586595Y181446D01*
X586928Y182071D01*
X585262D01*
G01X588278Y179946D02*
X588528Y179738D01*
X588820Y179613D01*
X589195Y179571D01*
X589570Y179654D01*
X589862Y179821D01*
X590070Y180113D01*
X590112Y180446D01*
X590028Y180779D01*
X589820Y180988D01*
X589528Y181154D01*
X589237Y181196D01*
X588945Y181154D01*
X588570Y180988D01*
X588695Y182071D01*
X589820D01*
G01X591587Y179863D02*
X591878Y179654D01*
X592212Y179571D01*
X592545Y179654D01*
X592837Y179904D01*
X593045Y180279D01*
X593128Y180654D01*
Y181113D01*
X593045Y181488D01*
X592837Y181821D01*
X592587Y181988D01*
X592295Y182071D01*
X591962Y181988D01*
X591712Y181821D01*
X591545Y181571D01*
X591462Y181238D01*
X591545Y180946D01*
X591753Y180654D01*
X592003Y180488D01*
X592295Y180446D01*
X592628Y180529D01*
X592878Y180738D01*
X593128Y181113D01*
G01X582342Y183889D02*
Y186389D01*
X583383D01*
X583717Y186264D01*
X583925Y186097D01*
X584008Y185764D01*
X583925Y185431D01*
X583675Y185222D01*
X583383Y185097D01*
X582342D01*
G01X583383D02*
X584008Y183889D01*
G01X586192D02*
X586275Y184431D01*
X586400Y184889D01*
X586567Y185306D01*
X586775Y185764D01*
X587108Y186389D01*
X585442D01*
G01X588458Y184264D02*
X588708Y184056D01*
X589000Y183931D01*
X589375Y183889D01*
X589750Y183972D01*
X590042Y184139D01*
X590250Y184431D01*
X590292Y184764D01*
X590208Y185097D01*
X590000Y185306D01*
X589708Y185472D01*
X589417Y185514D01*
X589125Y185472D01*
X588750Y185306D01*
X588875Y186389D01*
X590000D01*
G01X591683Y184931D02*
X591975Y185222D01*
X592225Y185389D01*
X592558Y185472D01*
X592850Y185389D01*
X593058Y185222D01*
X593225Y184972D01*
X593267Y184681D01*
X593225Y184431D01*
X593058Y184181D01*
X592808Y183972D01*
X592517Y183889D01*
X592183Y183972D01*
X591892Y184222D01*
X591725Y184597D01*
X591683Y185014D01*
X591767Y185556D01*
X591892Y185847D01*
X592100Y186139D01*
X592392Y186347D01*
X592683Y186389D01*
X592975Y186306D01*
X593183Y186097D01*
G01X573570Y202580D02*
Y205080D01*
X574611D01*
X574945Y204955D01*
X575153Y204788D01*
X575236Y204455D01*
X575153Y204122D01*
X574903Y203913D01*
X574611Y203788D01*
X573570D01*
G01X574611D02*
X575236Y202580D01*
G01X577420D02*
X577503Y203122D01*
X577628Y203580D01*
X577795Y203997D01*
X578003Y204455D01*
X578336Y205080D01*
X576670D01*
G01X579686Y202955D02*
X579936Y202747D01*
X580228Y202622D01*
X580603Y202580D01*
X580978Y202663D01*
X581270Y202830D01*
X581478Y203122D01*
X581520Y203455D01*
X581436Y203788D01*
X581228Y203997D01*
X580936Y204163D01*
X580645Y204205D01*
X580353Y204163D01*
X579978Y203997D01*
X580103Y205080D01*
X581228D01*
G01X582786Y202955D02*
X583036Y202747D01*
X583328Y202622D01*
X583703Y202580D01*
X584078Y202663D01*
X584370Y202830D01*
X584578Y203122D01*
X584620Y203455D01*
X584536Y203788D01*
X584328Y203997D01*
X584036Y204163D01*
X583745Y204205D01*
X583453Y204163D01*
X583078Y203997D01*
X583203Y205080D01*
X584328D01*
G01X595116Y182794D02*
Y185294D01*
X596157D01*
X596491Y185169D01*
X596699Y185002D01*
X596782Y184669D01*
X596699Y184336D01*
X596449Y184127D01*
X596157Y184002D01*
X595116D01*
G01X596157D02*
X596782Y182794D01*
G01X598966D02*
X599049Y183336D01*
X599174Y183794D01*
X599341Y184211D01*
X599549Y184669D01*
X599882Y185294D01*
X598216D01*
G01X601232Y183169D02*
X601482Y182961D01*
X601774Y182836D01*
X602149Y182794D01*
X602524Y182877D01*
X602816Y183044D01*
X603024Y183336D01*
X603066Y183669D01*
X602982Y184002D01*
X602774Y184211D01*
X602482Y184377D01*
X602191Y184419D01*
X601899Y184377D01*
X601524Y184211D01*
X601649Y185294D01*
X602774D01*
G01X605249Y182794D02*
X605541Y182836D01*
X605874Y182961D01*
X606082Y183169D01*
X606166Y183461D01*
X606082Y183752D01*
X605832Y184002D01*
X605457Y184127D01*
X605041D01*
X604791Y184211D01*
X604582Y184419D01*
X604499Y184711D01*
X604624Y185002D01*
X604916Y185211D01*
X605249Y185294D01*
X605582Y185211D01*
X605874Y185002D01*
X605999Y184711D01*
X605916Y184419D01*
X605707Y184211D01*
X605457Y184127D01*
X605041D01*
X604666Y184002D01*
X604416Y183752D01*
X604332Y183461D01*
X604416Y183169D01*
X604624Y182961D01*
X604957Y182836D01*
X605249Y182794D01*
G01X595116Y186814D02*
Y189314D01*
X596157D01*
X596491Y189189D01*
X596699Y189022D01*
X596782Y188689D01*
X596699Y188356D01*
X596449Y188147D01*
X596157Y188022D01*
X595116D01*
G01X596157D02*
X596782Y186814D01*
G01X598966D02*
X599049Y187356D01*
X599174Y187814D01*
X599341Y188231D01*
X599549Y188689D01*
X599882Y189314D01*
X598216D01*
G01X601232Y187314D02*
X601482Y187022D01*
X601816Y186856D01*
X602191Y186814D01*
X602524Y186856D01*
X602857Y187064D01*
X603066Y187314D01*
X603107Y187564D01*
X603024Y187856D01*
X602732Y188064D01*
X602441Y188147D01*
X602066D01*
G01X602441D02*
X602691Y188272D01*
X602899Y188481D01*
X602982Y188731D01*
X602899Y188981D01*
X602691Y189189D01*
X602316Y189314D01*
X601941Y189272D01*
X601566Y189106D01*
G01X605249Y189314D02*
X604916Y189231D01*
X604666Y189022D01*
X604499Y188772D01*
X604374Y188439D01*
X604332Y188064D01*
X604374Y187689D01*
X604499Y187356D01*
X604666Y187106D01*
X604916Y186897D01*
X605249Y186814D01*
X605582Y186897D01*
X605832Y187106D01*
X605999Y187356D01*
X606124Y187689D01*
X606166Y188064D01*
X606124Y188439D01*
X605999Y188772D01*
X605832Y189022D01*
X605582Y189231D01*
X605249Y189314D01*
G01X595000Y219000D02*
Y227000D01*
X612000D01*
G01X596108Y210537D02*
X609508D01*
G01X583167Y222600D02*
Y225100D01*
X584167D01*
X584500Y224975D01*
X584750Y224683D01*
X584833Y224350D01*
X584750Y224017D01*
X584542Y223767D01*
X584167Y223642D01*
X583167D01*
G01X586183Y225100D02*
Y223308D01*
X586350Y222933D01*
X586683Y222683D01*
X587100Y222600D01*
X587517Y222683D01*
X587850Y222933D01*
X588017Y223308D01*
Y225100D01*
G01X590200Y222600D02*
Y225100D01*
X589700Y224600D01*
G01Y222600D02*
X590700D01*
G01X589920Y234952D02*
X586920D01*
G01X588913Y231858D02*
Y226858D01*
X593913D01*
G01X575400Y218567D02*
X572900D01*
Y219567D01*
X573025Y219900D01*
X573317Y220150D01*
X573650Y220233D01*
X573983Y220150D01*
X574233Y219942D01*
X574358Y219567D01*
Y218567D01*
G01X573108Y223417D02*
X572983Y223167D01*
X572900Y222875D01*
Y222542D01*
X573025Y222167D01*
X573233Y221875D01*
X573483Y221667D01*
X573900Y221500D01*
X574275Y221458D01*
X574650Y221542D01*
X574900Y221667D01*
X575150Y221917D01*
X575317Y222208D01*
X575400Y222500D01*
Y222792D01*
X575317Y223083D01*
X575192Y223333D01*
X575025Y223542D01*
G01X575400Y225600D02*
X572900D01*
X573400Y225100D01*
G01X575400D02*
Y226100D01*
G01X575108Y227992D02*
X575317Y228283D01*
X575400Y228617D01*
X575317Y228950D01*
X575067Y229242D01*
X574692Y229450D01*
X574317Y229533D01*
X573858D01*
X573483Y229450D01*
X573150Y229242D01*
X572983Y228992D01*
X572900Y228700D01*
X572983Y228367D01*
X573150Y228117D01*
X573400Y227950D01*
X573733Y227867D01*
X574025Y227950D01*
X574317Y228158D01*
X574483Y228408D01*
X574525Y228700D01*
X574442Y229033D01*
X574233Y229283D01*
X573858Y229533D01*
G01X574900Y230883D02*
X575192Y231133D01*
X575358Y231467D01*
X575400Y231842D01*
X575358Y232175D01*
X575150Y232508D01*
X574900Y232717D01*
X574650Y232758D01*
X574358Y232675D01*
X574150Y232383D01*
X574067Y232092D01*
Y231717D01*
G01Y232092D02*
X573942Y232342D01*
X573733Y232550D01*
X573483Y232633D01*
X573233Y232550D01*
X573025Y232342D01*
X572900Y231967D01*
X572942Y231592D01*
X573108Y231217D01*
G01X577967Y218700D02*
Y221200D01*
X578967D01*
X579300Y221075D01*
X579550Y220783D01*
X579633Y220450D01*
X579550Y220117D01*
X579342Y219867D01*
X578967Y219742D01*
X577967D01*
G01X581067Y218700D02*
Y221200D01*
X582108D01*
X582442Y221075D01*
X582650Y220908D01*
X582733Y220575D01*
X582650Y220242D01*
X582400Y220033D01*
X582108Y219908D01*
X581067D01*
G01X582108D02*
X582733Y218700D01*
G01X585000D02*
Y221200D01*
X584500Y220700D01*
G01Y218700D02*
X585500D01*
G01X588017D02*
X588100Y219242D01*
X588225Y219700D01*
X588392Y220117D01*
X588600Y220575D01*
X588933Y221200D01*
X587267D01*
G01X591200D02*
X590867Y221117D01*
X590617Y220908D01*
X590450Y220658D01*
X590325Y220325D01*
X590283Y219950D01*
X590325Y219575D01*
X590450Y219242D01*
X590617Y218992D01*
X590867Y218783D01*
X591200Y218700D01*
X591533Y218783D01*
X591783Y218992D01*
X591950Y219242D01*
X592075Y219575D01*
X592117Y219950D01*
X592075Y220325D01*
X591950Y220658D01*
X591783Y220908D01*
X591533Y221117D01*
X591200Y221200D01*
G01X579363Y230608D02*
Y226608D01*
X586763D01*
G01X578630Y214108D02*
Y216608D01*
X579671D01*
X580005Y216483D01*
X580213Y216316D01*
X580296Y215983D01*
X580213Y215650D01*
X579963Y215441D01*
X579671Y215316D01*
X578630D01*
G01X579671D02*
X580296Y214108D01*
G01X581771Y215150D02*
X582063Y215441D01*
X582313Y215608D01*
X582646Y215691D01*
X582938Y215608D01*
X583146Y215441D01*
X583313Y215191D01*
X583355Y214900D01*
X583313Y214650D01*
X583146Y214400D01*
X582896Y214191D01*
X582605Y214108D01*
X582271Y214191D01*
X581980Y214441D01*
X581813Y214816D01*
X581771Y215233D01*
X581855Y215775D01*
X581980Y216066D01*
X582188Y216358D01*
X582480Y216566D01*
X582771Y216608D01*
X583063Y216525D01*
X583271Y216316D01*
G01X585663Y214108D02*
X585955Y214150D01*
X586288Y214275D01*
X586496Y214483D01*
X586580Y214775D01*
X586496Y215066D01*
X586246Y215316D01*
X585871Y215441D01*
X585455D01*
X585205Y215525D01*
X584996Y215733D01*
X584913Y216025D01*
X585038Y216316D01*
X585330Y216525D01*
X585663Y216608D01*
X585996Y216525D01*
X586288Y216316D01*
X586413Y216025D01*
X586330Y215733D01*
X586121Y215525D01*
X585871Y215441D01*
X585455D01*
X585080Y215316D01*
X584830Y215066D01*
X584746Y214775D01*
X584830Y214483D01*
X585038Y214275D01*
X585371Y214150D01*
X585663Y214108D01*
G01X595163Y213308D02*
Y217308D01*
X587763D01*
G01X578630Y210108D02*
Y212608D01*
X579671D01*
X580005Y212483D01*
X580213Y212316D01*
X580296Y211983D01*
X580213Y211650D01*
X579963Y211441D01*
X579671Y211316D01*
X578630D01*
G01X579671D02*
X580296Y210108D01*
G01X582563D02*
Y212608D01*
X582063Y212108D01*
G01Y210108D02*
X583063D01*
G01X584746Y210608D02*
X584996Y210316D01*
X585330Y210150D01*
X585705Y210108D01*
X586038Y210150D01*
X586371Y210358D01*
X586580Y210608D01*
X586621Y210858D01*
X586538Y211150D01*
X586246Y211358D01*
X585955Y211441D01*
X585580D01*
G01X585955D02*
X586205Y211566D01*
X586413Y211775D01*
X586496Y212025D01*
X586413Y212275D01*
X586205Y212483D01*
X585830Y212608D01*
X585455Y212566D01*
X585080Y212400D01*
G01X587763Y213308D02*
Y209308D01*
X595163D01*
G01X577800Y236400D02*
Y240400D01*
X570400D01*
G01X589920Y244795D02*
X587920D01*
G01X593913Y254858D02*
X588913D01*
Y249858D01*
G01X605913Y269258D02*
X587213D01*
Y279558D01*
X605913D01*
Y269258D01*
G01X578159Y307141D02*
Y317341D01*
G01Y307141D02*
Y317341D01*
G01X605913Y293858D02*
X587213D01*
Y304158D01*
X605913D01*
Y293858D01*
G01Y281558D02*
X587213D01*
Y291858D01*
X605913D01*
Y281558D01*
G01X580367Y338000D02*
Y340500D01*
X581408D01*
X581742Y340375D01*
X581950Y340208D01*
X582033Y339875D01*
X581950Y339542D01*
X581700Y339333D01*
X581408Y339208D01*
X580367D01*
G01X581408D02*
X582033Y338000D01*
G01X583592Y338292D02*
X583883Y338083D01*
X584217Y338000D01*
X584550Y338083D01*
X584842Y338333D01*
X585050Y338708D01*
X585133Y339083D01*
Y339542D01*
X585050Y339917D01*
X584842Y340250D01*
X584592Y340417D01*
X584300Y340500D01*
X583967Y340417D01*
X583717Y340250D01*
X583550Y340000D01*
X583467Y339667D01*
X583550Y339375D01*
X583758Y339083D01*
X584008Y338917D01*
X584300Y338875D01*
X584633Y338958D01*
X584883Y339167D01*
X585133Y339542D01*
G01X586692Y338292D02*
X586983Y338083D01*
X587317Y338000D01*
X587650Y338083D01*
X587942Y338333D01*
X588150Y338708D01*
X588233Y339083D01*
Y339542D01*
X588150Y339917D01*
X587942Y340250D01*
X587692Y340417D01*
X587400Y340500D01*
X587067Y340417D01*
X586817Y340250D01*
X586650Y340000D01*
X586567Y339667D01*
X586650Y339375D01*
X586858Y339083D01*
X587108Y338917D01*
X587400Y338875D01*
X587733Y338958D01*
X587983Y339167D01*
X588233Y339542D01*
G01X585467Y343400D02*
Y345900D01*
X586508D01*
X586842Y345775D01*
X587050Y345608D01*
X587133Y345275D01*
X587050Y344942D01*
X586800Y344733D01*
X586508Y344608D01*
X585467D01*
G01X586508D02*
X587133Y343400D01*
G01X588483Y343900D02*
X588733Y343608D01*
X589067Y343442D01*
X589442Y343400D01*
X589775Y343442D01*
X590108Y343650D01*
X590317Y343900D01*
X590358Y344150D01*
X590275Y344442D01*
X589983Y344650D01*
X589692Y344733D01*
X589317D01*
G01X589692D02*
X589942Y344858D01*
X590150Y345067D01*
X590233Y345317D01*
X590150Y345567D01*
X589942Y345775D01*
X589567Y345900D01*
X589192Y345858D01*
X588817Y345692D01*
G01X592500Y343400D02*
Y345900D01*
X592000Y345400D01*
G01Y343400D02*
X593000D01*
G01X595600D02*
Y345900D01*
X595100Y345400D01*
G01Y343400D02*
X596100D01*
G01X598700Y345900D02*
X598367Y345817D01*
X598117Y345608D01*
X597950Y345358D01*
X597825Y345025D01*
X597783Y344650D01*
X597825Y344275D01*
X597950Y343942D01*
X598117Y343692D01*
X598367Y343483D01*
X598700Y343400D01*
X599033Y343483D01*
X599283Y343692D01*
X599450Y343942D01*
X599575Y344275D01*
X599617Y344650D01*
X599575Y345025D01*
X599450Y345358D01*
X599283Y345608D01*
X599033Y345817D01*
X598700Y345900D01*
G01X602000Y329467D02*
X599500D01*
Y330508D01*
X599625Y330842D01*
X599792Y331050D01*
X600125Y331133D01*
X600458Y331050D01*
X600667Y330800D01*
X600792Y330508D01*
Y329467D01*
G01Y330508D02*
X602000Y331133D01*
G01X601708Y332692D02*
X601917Y332983D01*
X602000Y333317D01*
X601917Y333650D01*
X601667Y333942D01*
X601292Y334150D01*
X600917Y334233D01*
X600458D01*
X600083Y334150D01*
X599750Y333942D01*
X599583Y333692D01*
X599500Y333400D01*
X599583Y333067D01*
X599750Y332817D01*
X600000Y332650D01*
X600333Y332567D01*
X600625Y332650D01*
X600917Y332858D01*
X601083Y333108D01*
X601125Y333400D01*
X601042Y333733D01*
X600833Y333983D01*
X600458Y334233D01*
G01X602000Y336500D02*
X601958Y336792D01*
X601833Y337125D01*
X601625Y337333D01*
X601333Y337417D01*
X601042Y337333D01*
X600792Y337083D01*
X600667Y336708D01*
Y336292D01*
X600583Y336042D01*
X600375Y335833D01*
X600083Y335750D01*
X599792Y335875D01*
X599583Y336167D01*
X599500Y336500D01*
X599583Y336833D01*
X599792Y337125D01*
X600083Y337250D01*
X600375Y337167D01*
X600583Y336958D01*
X600667Y336708D01*
Y336292D01*
X600792Y335917D01*
X601042Y335667D01*
X601333Y335583D01*
X601625Y335667D01*
X601833Y335875D01*
X601958Y336208D01*
X602000Y336500D01*
G01X596208Y330667D02*
X596083Y330417D01*
X596000Y330125D01*
Y329792D01*
X596125Y329417D01*
X596333Y329125D01*
X596583Y328917D01*
X597000Y328750D01*
X597375Y328708D01*
X597750Y328792D01*
X598000Y328917D01*
X598250Y329167D01*
X598417Y329458D01*
X598500Y329750D01*
Y330042D01*
X598417Y330333D01*
X598292Y330583D01*
X598125Y330792D01*
G01X598500Y332767D02*
X597958Y332850D01*
X597500Y332975D01*
X597083Y333142D01*
X596625Y333350D01*
X596000Y333683D01*
Y332017D01*
G01X598500Y335950D02*
X596000D01*
X596500Y335450D01*
G01X598500D02*
Y336450D01*
G01X598208Y338342D02*
X598417Y338633D01*
X598500Y338967D01*
X598417Y339300D01*
X598167Y339592D01*
X597792Y339800D01*
X597417Y339883D01*
X596958D01*
X596583Y339800D01*
X596250Y339592D01*
X596083Y339342D01*
X596000Y339050D01*
X596083Y338717D01*
X596250Y338467D01*
X596500Y338300D01*
X596833Y338217D01*
X597125Y338300D01*
X597417Y338508D01*
X597583Y338758D01*
X597625Y339050D01*
X597542Y339383D01*
X597333Y339633D01*
X596958Y339883D01*
G01X589300Y320917D02*
X586800D01*
Y321917D01*
X586925Y322250D01*
X587217Y322500D01*
X587550Y322583D01*
X587883Y322500D01*
X588133Y322292D01*
X588258Y321917D01*
Y320917D01*
G01X588050Y325100D02*
Y325933D01*
X588800D01*
X589050Y325683D01*
X589217Y325392D01*
X589300Y324975D01*
X589217Y324558D01*
X589050Y324267D01*
X588800Y324017D01*
X588508Y323850D01*
X588175Y323767D01*
X587883D01*
X587633Y323850D01*
X587342Y324017D01*
X587092Y324267D01*
X586925Y324517D01*
X586800Y324850D01*
Y325142D01*
X586883Y325475D01*
X587050Y325725D01*
G01X589300Y327867D02*
X588758Y327950D01*
X588300Y328075D01*
X587883Y328242D01*
X587425Y328450D01*
X586800Y328783D01*
Y327117D01*
G01Y331050D02*
X586883Y330717D01*
X587092Y330467D01*
X587342Y330300D01*
X587675Y330175D01*
X588050Y330133D01*
X588425Y330175D01*
X588758Y330300D01*
X589008Y330467D01*
X589217Y330717D01*
X589300Y331050D01*
X589217Y331383D01*
X589008Y331633D01*
X588758Y331800D01*
X588425Y331925D01*
X588050Y331967D01*
X587675Y331925D01*
X587342Y331800D01*
X587092Y331633D01*
X586883Y331383D01*
X586800Y331050D01*
G01X585500Y321017D02*
X583000D01*
Y322017D01*
X583125Y322350D01*
X583417Y322600D01*
X583750Y322683D01*
X584083Y322600D01*
X584333Y322392D01*
X584458Y322017D01*
Y321017D01*
G01X584250Y325200D02*
Y326033D01*
X585000D01*
X585250Y325783D01*
X585417Y325492D01*
X585500Y325075D01*
X585417Y324658D01*
X585250Y324367D01*
X585000Y324117D01*
X584708Y323950D01*
X584375Y323867D01*
X584083D01*
X583833Y323950D01*
X583542Y324117D01*
X583292Y324367D01*
X583125Y324617D01*
X583000Y324950D01*
Y325242D01*
X583083Y325575D01*
X583250Y325825D01*
G01X585000Y327133D02*
X585292Y327383D01*
X585458Y327717D01*
X585500Y328092D01*
X585458Y328425D01*
X585250Y328758D01*
X585000Y328967D01*
X584750Y329008D01*
X584458Y328925D01*
X584250Y328633D01*
X584167Y328342D01*
Y327967D01*
G01Y328342D02*
X584042Y328592D01*
X583833Y328800D01*
X583583Y328883D01*
X583333Y328800D01*
X583125Y328592D01*
X583000Y328217D01*
X583042Y327842D01*
X583208Y327467D01*
G01X585000Y330233D02*
X585292Y330483D01*
X585458Y330817D01*
X585500Y331192D01*
X585458Y331525D01*
X585250Y331858D01*
X585000Y332067D01*
X584750Y332108D01*
X584458Y332025D01*
X584250Y331733D01*
X584167Y331442D01*
Y331067D01*
G01Y331442D02*
X584042Y331692D01*
X583833Y331900D01*
X583583Y331983D01*
X583333Y331900D01*
X583125Y331692D01*
X583000Y331317D01*
X583042Y330942D01*
X583208Y330567D01*
G01X583417Y333800D02*
Y336300D01*
X584417D01*
X584750Y336175D01*
X585000Y335883D01*
X585083Y335550D01*
X585000Y335217D01*
X584792Y334967D01*
X584417Y334842D01*
X583417D01*
G01X587600Y335050D02*
X588433D01*
Y334300D01*
X588183Y334050D01*
X587892Y333883D01*
X587475Y333800D01*
X587058Y333883D01*
X586767Y334050D01*
X586517Y334300D01*
X586350Y334592D01*
X586267Y334925D01*
Y335217D01*
X586350Y335467D01*
X586517Y335758D01*
X586767Y336008D01*
X587017Y336175D01*
X587350Y336300D01*
X587642D01*
X587975Y336217D01*
X588225Y336050D01*
G01X590450Y333800D02*
Y336300D01*
X589950Y335800D01*
G01Y333800D02*
X590950D01*
G01X593550Y336300D02*
X593217Y336217D01*
X592967Y336008D01*
X592800Y335758D01*
X592675Y335425D01*
X592633Y335050D01*
X592675Y334675D01*
X592800Y334342D01*
X592967Y334092D01*
X593217Y333883D01*
X593550Y333800D01*
X593883Y333883D01*
X594133Y334092D01*
X594300Y334342D01*
X594425Y334675D01*
X594467Y335050D01*
X594425Y335425D01*
X594300Y335758D01*
X594133Y336008D01*
X593883Y336217D01*
X593550Y336300D01*
G01X591780Y362981D02*
X589280D01*
Y363981D01*
X589405Y364314D01*
X589697Y364564D01*
X590030Y364647D01*
X590363Y364564D01*
X590613Y364356D01*
X590738Y363981D01*
Y362981D01*
G01X589488Y367831D02*
X589363Y367581D01*
X589280Y367289D01*
Y366956D01*
X589405Y366581D01*
X589613Y366289D01*
X589863Y366081D01*
X590280Y365914D01*
X590655Y365872D01*
X591030Y365956D01*
X591280Y366081D01*
X591530Y366331D01*
X591697Y366622D01*
X591780Y366914D01*
Y367206D01*
X591697Y367497D01*
X591572Y367747D01*
X591405Y367956D01*
G01X590738Y369222D02*
X590447Y369514D01*
X590280Y369764D01*
X590197Y370097D01*
X590280Y370389D01*
X590447Y370597D01*
X590697Y370764D01*
X590988Y370806D01*
X591238Y370764D01*
X591488Y370597D01*
X591697Y370347D01*
X591780Y370056D01*
X591697Y369722D01*
X591447Y369431D01*
X591072Y369264D01*
X590655Y369222D01*
X590113Y369306D01*
X589822Y369431D01*
X589530Y369639D01*
X589322Y369931D01*
X589280Y370222D01*
X589363Y370514D01*
X589572Y370722D01*
G01X591488Y372406D02*
X591697Y372697D01*
X591780Y373031D01*
X591697Y373364D01*
X591447Y373656D01*
X591072Y373864D01*
X590697Y373947D01*
X590238D01*
X589863Y373864D01*
X589530Y373656D01*
X589363Y373406D01*
X589280Y373114D01*
X589363Y372781D01*
X589530Y372531D01*
X589780Y372364D01*
X590113Y372281D01*
X590405Y372364D01*
X590697Y372572D01*
X590863Y372822D01*
X590905Y373114D01*
X590822Y373447D01*
X590613Y373697D01*
X590238Y373947D01*
G01X583780Y362981D02*
X581280D01*
Y363981D01*
X581405Y364314D01*
X581697Y364564D01*
X582030Y364647D01*
X582363Y364564D01*
X582613Y364356D01*
X582738Y363981D01*
Y362981D01*
G01X581488Y367831D02*
X581363Y367581D01*
X581280Y367289D01*
Y366956D01*
X581405Y366581D01*
X581613Y366289D01*
X581863Y366081D01*
X582280Y365914D01*
X582655Y365872D01*
X583030Y365956D01*
X583280Y366081D01*
X583530Y366331D01*
X583697Y366622D01*
X583780Y366914D01*
Y367206D01*
X583697Y367497D01*
X583572Y367747D01*
X583405Y367956D01*
G01X583780Y370014D02*
X583738Y370306D01*
X583613Y370639D01*
X583405Y370847D01*
X583113Y370931D01*
X582822Y370847D01*
X582572Y370597D01*
X582447Y370222D01*
Y369806D01*
X582363Y369556D01*
X582155Y369347D01*
X581863Y369264D01*
X581572Y369389D01*
X581363Y369681D01*
X581280Y370014D01*
X581363Y370347D01*
X581572Y370639D01*
X581863Y370764D01*
X582155Y370681D01*
X582363Y370472D01*
X582447Y370222D01*
Y369806D01*
X582572Y369431D01*
X582822Y369181D01*
X583113Y369097D01*
X583405Y369181D01*
X583613Y369389D01*
X583738Y369722D01*
X583780Y370014D01*
G01Y373114D02*
X583738Y373406D01*
X583613Y373739D01*
X583405Y373947D01*
X583113Y374031D01*
X582822Y373947D01*
X582572Y373697D01*
X582447Y373322D01*
Y372906D01*
X582363Y372656D01*
X582155Y372447D01*
X581863Y372364D01*
X581572Y372489D01*
X581363Y372781D01*
X581280Y373114D01*
X581363Y373447D01*
X581572Y373739D01*
X581863Y373864D01*
X582155Y373781D01*
X582363Y373572D01*
X582447Y373322D01*
Y372906D01*
X582572Y372531D01*
X582822Y372281D01*
X583113Y372197D01*
X583405Y372281D01*
X583613Y372489D01*
X583738Y372822D01*
X583780Y373114D01*
G01X587780Y362981D02*
X585280D01*
Y363981D01*
X585405Y364314D01*
X585697Y364564D01*
X586030Y364647D01*
X586363Y364564D01*
X586613Y364356D01*
X586738Y363981D01*
Y362981D01*
G01X585488Y367831D02*
X585363Y367581D01*
X585280Y367289D01*
Y366956D01*
X585405Y366581D01*
X585613Y366289D01*
X585863Y366081D01*
X586280Y365914D01*
X586655Y365872D01*
X587030Y365956D01*
X587280Y366081D01*
X587530Y366331D01*
X587697Y366622D01*
X587780Y366914D01*
Y367206D01*
X587697Y367497D01*
X587572Y367747D01*
X587405Y367956D01*
G01X587488Y369306D02*
X587697Y369597D01*
X587780Y369931D01*
X587697Y370264D01*
X587447Y370556D01*
X587072Y370764D01*
X586697Y370847D01*
X586238D01*
X585863Y370764D01*
X585530Y370556D01*
X585363Y370306D01*
X585280Y370014D01*
X585363Y369681D01*
X585530Y369431D01*
X585780Y369264D01*
X586113Y369181D01*
X586405Y369264D01*
X586697Y369472D01*
X586863Y369722D01*
X586905Y370014D01*
X586822Y370347D01*
X586613Y370597D01*
X586238Y370847D01*
G01X585280Y373114D02*
X585363Y372781D01*
X585572Y372531D01*
X585822Y372364D01*
X586155Y372239D01*
X586530Y372197D01*
X586905Y372239D01*
X587238Y372364D01*
X587488Y372531D01*
X587697Y372781D01*
X587780Y373114D01*
X587697Y373447D01*
X587488Y373697D01*
X587238Y373864D01*
X586905Y373989D01*
X586530Y374031D01*
X586155Y373989D01*
X585822Y373864D01*
X585572Y373697D01*
X585363Y373447D01*
X585280Y373114D01*
G01X596075Y371166D02*
X597825Y373666D01*
G01X596075D02*
X597825Y371166D01*
G01X599133Y371666D02*
X599383Y371374D01*
X599717Y371208D01*
X600092Y371166D01*
X600425Y371208D01*
X600758Y371416D01*
X600967Y371666D01*
X601008Y371916D01*
X600925Y372208D01*
X600633Y372416D01*
X600342Y372499D01*
X599967D01*
G01X600342D02*
X600592Y372624D01*
X600800Y372833D01*
X600883Y373083D01*
X600800Y373333D01*
X600592Y373541D01*
X600217Y373666D01*
X599842Y373624D01*
X599467Y373458D01*
G01X606600Y353250D02*
Y369950D01*
X594400D01*
Y353250D01*
X606600D01*
G01X610400Y342200D02*
Y346200D01*
X603000D01*
G01Y350200D02*
Y346200D01*
X610400D01*
G01X581617Y380100D02*
Y382600D01*
X582617D01*
X582950Y382475D01*
X583200Y382183D01*
X583283Y381850D01*
X583200Y381517D01*
X582992Y381267D01*
X582617Y381142D01*
X581617D01*
G01X586467Y382392D02*
X586217Y382517D01*
X585925Y382600D01*
X585592D01*
X585217Y382475D01*
X584925Y382267D01*
X584717Y382017D01*
X584550Y381600D01*
X584508Y381225D01*
X584592Y380850D01*
X584717Y380600D01*
X584967Y380350D01*
X585258Y380183D01*
X585550Y380100D01*
X585842D01*
X586133Y380183D01*
X586383Y380308D01*
X586592Y380475D01*
G01X587942Y380392D02*
X588233Y380183D01*
X588567Y380100D01*
X588900Y380183D01*
X589192Y380433D01*
X589400Y380808D01*
X589483Y381183D01*
Y381642D01*
X589400Y382017D01*
X589192Y382350D01*
X588942Y382517D01*
X588650Y382600D01*
X588317Y382517D01*
X588067Y382350D01*
X587900Y382100D01*
X587817Y381767D01*
X587900Y381475D01*
X588108Y381183D01*
X588358Y381017D01*
X588650Y380975D01*
X588983Y381058D01*
X589233Y381267D01*
X589483Y381642D01*
G01X590833Y380600D02*
X591083Y380308D01*
X591417Y380142D01*
X591792Y380100D01*
X592125Y380142D01*
X592458Y380350D01*
X592667Y380600D01*
X592708Y380850D01*
X592625Y381142D01*
X592333Y381350D01*
X592042Y381433D01*
X591667D01*
G01X592042D02*
X592292Y381558D01*
X592500Y381767D01*
X592583Y382017D01*
X592500Y382267D01*
X592292Y382475D01*
X591917Y382600D01*
X591542Y382558D01*
X591167Y382392D01*
G01X580200Y380017D02*
X577700D01*
Y381017D01*
X577825Y381350D01*
X578117Y381600D01*
X578450Y381683D01*
X578783Y381600D01*
X579033Y381392D01*
X579158Y381017D01*
Y380017D01*
G01X580200Y383117D02*
X577700D01*
Y384158D01*
X577825Y384492D01*
X577992Y384700D01*
X578325Y384783D01*
X578658Y384700D01*
X578867Y384450D01*
X578992Y384158D01*
Y383117D01*
G01Y384158D02*
X580200Y384783D01*
G01Y386967D02*
X579658Y387050D01*
X579200Y387175D01*
X578783Y387342D01*
X578325Y387550D01*
X577700Y387883D01*
Y386217D01*
G01X580200Y390150D02*
X580158Y390442D01*
X580033Y390775D01*
X579825Y390983D01*
X579533Y391067D01*
X579242Y390983D01*
X578992Y390733D01*
X578867Y390358D01*
Y389942D01*
X578783Y389692D01*
X578575Y389483D01*
X578283Y389400D01*
X577992Y389525D01*
X577783Y389817D01*
X577700Y390150D01*
X577783Y390483D01*
X577992Y390775D01*
X578283Y390900D01*
X578575Y390817D01*
X578783Y390608D01*
X578867Y390358D01*
Y389942D01*
X578992Y389567D01*
X579242Y389317D01*
X579533Y389233D01*
X579825Y389317D01*
X580033Y389525D01*
X580158Y389858D01*
X580200Y390150D01*
G01X571690Y639140D02*
Y636400D01*
G01X571520Y639830D02*
X571690Y639140D01*
G01X571180Y640220D02*
X571520Y639830D01*
G01X570790Y640320D02*
X571180Y640220D01*
G01X570335D02*
X570790Y640320D01*
G01X574115Y636400D02*
Y642280D01*
G01X577945Y637085D02*
X578680Y640320D01*
G01X577605Y635520D02*
X577945Y637085D01*
G01X577385Y635025D02*
X577605Y635520D01*
G01X577100Y634635D02*
X577385Y635025D01*
G01X576650Y634440D02*
X577100Y634635D01*
G01X576310D02*
X576650Y634440D01*
G01X576880Y640320D02*
X577945Y637085D01*
G01X576034Y766819D02*
X573534D01*
Y767860D01*
X573659Y768194D01*
X573826Y768402D01*
X574159Y768485D01*
X574492Y768402D01*
X574701Y768152D01*
X574826Y767860D01*
Y766819D01*
G01Y767860D02*
X576034Y768485D01*
G01X575742Y770044D02*
X575951Y770335D01*
X576034Y770669D01*
X575951Y771002D01*
X575701Y771294D01*
X575326Y771502D01*
X574951Y771585D01*
X574492D01*
X574117Y771502D01*
X573784Y771294D01*
X573617Y771044D01*
X573534Y770752D01*
X573617Y770419D01*
X573784Y770169D01*
X574034Y770002D01*
X574367Y769919D01*
X574659Y770002D01*
X574951Y770210D01*
X575117Y770460D01*
X575159Y770752D01*
X575076Y771085D01*
X574867Y771335D01*
X574492Y771585D01*
G01X573534Y773852D02*
X573617Y773519D01*
X573826Y773269D01*
X574076Y773102D01*
X574409Y772977D01*
X574784Y772935D01*
X575159Y772977D01*
X575492Y773102D01*
X575742Y773269D01*
X575951Y773519D01*
X576034Y773852D01*
X575951Y774185D01*
X575742Y774435D01*
X575492Y774602D01*
X575159Y774727D01*
X574784Y774769D01*
X574409Y774727D01*
X574076Y774602D01*
X573826Y774435D01*
X573617Y774185D01*
X573534Y773852D01*
G01X575534Y776035D02*
X575826Y776285D01*
X575992Y776619D01*
X576034Y776994D01*
X575992Y777327D01*
X575784Y777660D01*
X575534Y777869D01*
X575284Y777910D01*
X574992Y777827D01*
X574784Y777535D01*
X574701Y777244D01*
Y776869D01*
G01Y777244D02*
X574576Y777494D01*
X574367Y777702D01*
X574117Y777785D01*
X573867Y777702D01*
X573659Y777494D01*
X573534Y777119D01*
X573576Y776744D01*
X573742Y776369D01*
G01X576034Y780052D02*
X573534D01*
X574034Y779552D01*
G01X576034D02*
Y780552D01*
G01X573593Y816093D02*
X573468Y815843D01*
X573385Y815551D01*
Y815218D01*
X573510Y814843D01*
X573718Y814551D01*
X573968Y814343D01*
X574385Y814176D01*
X574760Y814134D01*
X575135Y814218D01*
X575385Y814343D01*
X575635Y814593D01*
X575802Y814884D01*
X575885Y815176D01*
Y815468D01*
X575802Y815759D01*
X575677Y816009D01*
X575510Y816218D01*
G01X575385Y817359D02*
X575677Y817609D01*
X575843Y817943D01*
X575885Y818318D01*
X575843Y818651D01*
X575635Y818984D01*
X575385Y819193D01*
X575135Y819234D01*
X574843Y819151D01*
X574635Y818859D01*
X574552Y818568D01*
Y818193D01*
G01Y818568D02*
X574427Y818818D01*
X574218Y819026D01*
X573968Y819109D01*
X573718Y819026D01*
X573510Y818818D01*
X573385Y818443D01*
X573427Y818068D01*
X573593Y817693D01*
G01X575885Y821376D02*
X573385D01*
X573885Y820876D01*
G01X575885D02*
Y821876D01*
G01Y824976D02*
X573385D01*
X575177Y823434D01*
Y825518D01*
G01X586191Y816093D02*
X586066Y815843D01*
X585983Y815551D01*
Y815218D01*
X586108Y814843D01*
X586316Y814551D01*
X586566Y814343D01*
X586983Y814176D01*
X587358Y814134D01*
X587733Y814218D01*
X587983Y814343D01*
X588233Y814593D01*
X588400Y814884D01*
X588483Y815176D01*
Y815468D01*
X588400Y815759D01*
X588275Y816009D01*
X588108Y816218D01*
G01X587983Y817359D02*
X588275Y817609D01*
X588441Y817943D01*
X588483Y818318D01*
X588441Y818651D01*
X588233Y818984D01*
X587983Y819193D01*
X587733Y819234D01*
X587441Y819151D01*
X587233Y818859D01*
X587150Y818568D01*
Y818193D01*
G01Y818568D02*
X587025Y818818D01*
X586816Y819026D01*
X586566Y819109D01*
X586316Y819026D01*
X586108Y818818D01*
X585983Y818443D01*
X586025Y818068D01*
X586191Y817693D01*
G01X588483Y821376D02*
X585983D01*
X586483Y820876D01*
G01X588483D02*
Y821876D01*
G01X587983Y823559D02*
X588275Y823809D01*
X588441Y824143D01*
X588483Y824518D01*
X588441Y824851D01*
X588233Y825184D01*
X587983Y825393D01*
X587733Y825434D01*
X587441Y825351D01*
X587233Y825059D01*
X587150Y824768D01*
Y824393D01*
G01Y824768D02*
X587025Y825018D01*
X586816Y825226D01*
X586566Y825309D01*
X586316Y825226D01*
X586108Y825018D01*
X585983Y824643D01*
X586025Y824268D01*
X586191Y823893D01*
G01X582191Y816093D02*
X582066Y815843D01*
X581983Y815551D01*
Y815218D01*
X582108Y814843D01*
X582316Y814551D01*
X582566Y814343D01*
X582983Y814176D01*
X583358Y814134D01*
X583733Y814218D01*
X583983Y814343D01*
X584233Y814593D01*
X584400Y814884D01*
X584483Y815176D01*
Y815468D01*
X584400Y815759D01*
X584275Y816009D01*
X584108Y816218D01*
G01X582400Y817484D02*
X582150Y817734D01*
X582025Y818026D01*
X581983Y818359D01*
X582066Y818776D01*
X582275Y819068D01*
X582525Y819151D01*
X582775Y819109D01*
X582983Y818943D01*
X583400Y818109D01*
X583691Y817734D01*
X584108Y817484D01*
X584483Y817401D01*
Y819151D01*
G01Y821293D02*
X583941Y821376D01*
X583483Y821501D01*
X583066Y821668D01*
X582608Y821876D01*
X581983Y822209D01*
Y820543D01*
G01X583983Y823559D02*
X584275Y823809D01*
X584441Y824143D01*
X584483Y824518D01*
X584441Y824851D01*
X584233Y825184D01*
X583983Y825393D01*
X583733Y825434D01*
X583441Y825351D01*
X583233Y825059D01*
X583150Y824768D01*
Y824393D01*
G01Y824768D02*
X583025Y825018D01*
X582816Y825226D01*
X582566Y825309D01*
X582316Y825226D01*
X582108Y825018D01*
X581983Y824643D01*
X582025Y824268D01*
X582191Y823893D01*
G01X598790Y816093D02*
X598665Y815843D01*
X598582Y815551D01*
Y815218D01*
X598707Y814843D01*
X598915Y814551D01*
X599165Y814343D01*
X599582Y814176D01*
X599957Y814134D01*
X600332Y814218D01*
X600582Y814343D01*
X600832Y814593D01*
X600999Y814884D01*
X601082Y815176D01*
Y815468D01*
X600999Y815759D01*
X600874Y816009D01*
X600707Y816218D01*
G01X598999Y817484D02*
X598749Y817734D01*
X598624Y818026D01*
X598582Y818359D01*
X598665Y818776D01*
X598874Y819068D01*
X599124Y819151D01*
X599374Y819109D01*
X599582Y818943D01*
X599999Y818109D01*
X600290Y817734D01*
X600707Y817484D01*
X601082Y817401D01*
Y819151D01*
G01X600040Y820584D02*
X599749Y820876D01*
X599582Y821126D01*
X599499Y821459D01*
X599582Y821751D01*
X599749Y821959D01*
X599999Y822126D01*
X600290Y822168D01*
X600540Y822126D01*
X600790Y821959D01*
X600999Y821709D01*
X601082Y821418D01*
X600999Y821084D01*
X600749Y820793D01*
X600374Y820626D01*
X599957Y820584D01*
X599415Y820668D01*
X599124Y820793D01*
X598832Y821001D01*
X598624Y821293D01*
X598582Y821584D01*
X598665Y821876D01*
X598874Y822084D01*
G01X598582Y824476D02*
X598665Y824143D01*
X598874Y823893D01*
X599124Y823726D01*
X599457Y823601D01*
X599832Y823559D01*
X600207Y823601D01*
X600540Y823726D01*
X600790Y823893D01*
X600999Y824143D01*
X601082Y824476D01*
X600999Y824809D01*
X600790Y825059D01*
X600540Y825226D01*
X600207Y825351D01*
X599832Y825393D01*
X599457Y825351D01*
X599124Y825226D01*
X598874Y825059D01*
X598665Y824809D01*
X598582Y824476D01*
G01X594790Y816093D02*
X594665Y815843D01*
X594582Y815551D01*
Y815218D01*
X594707Y814843D01*
X594915Y814551D01*
X595165Y814343D01*
X595582Y814176D01*
X595957Y814134D01*
X596332Y814218D01*
X596582Y814343D01*
X596832Y814593D01*
X596999Y814884D01*
X597082Y815176D01*
Y815468D01*
X596999Y815759D01*
X596874Y816009D01*
X596707Y816218D01*
G01X594999Y817484D02*
X594749Y817734D01*
X594624Y818026D01*
X594582Y818359D01*
X594665Y818776D01*
X594874Y819068D01*
X595124Y819151D01*
X595374Y819109D01*
X595582Y818943D01*
X595999Y818109D01*
X596290Y817734D01*
X596707Y817484D01*
X597082Y817401D01*
Y819151D01*
G01X596707Y820459D02*
X596915Y820709D01*
X597040Y821001D01*
X597082Y821376D01*
X596999Y821751D01*
X596832Y822043D01*
X596540Y822251D01*
X596207Y822293D01*
X595874Y822209D01*
X595665Y822001D01*
X595499Y821709D01*
X595457Y821418D01*
X595499Y821126D01*
X595665Y820751D01*
X594582Y820876D01*
Y822001D01*
G01X594999Y823684D02*
X594749Y823934D01*
X594624Y824226D01*
X594582Y824559D01*
X594665Y824976D01*
X594874Y825268D01*
X595124Y825351D01*
X595374Y825309D01*
X595582Y825143D01*
X595999Y824309D01*
X596290Y823934D01*
X596707Y823684D01*
X597082Y823601D01*
Y825351D01*
G01X612050Y141700D02*
X611717Y141742D01*
X611425Y141908D01*
X611175Y142158D01*
X611008Y142450D01*
X610925Y142783D01*
Y143117D01*
X611008Y143450D01*
X611175Y143742D01*
X611425Y143992D01*
X611717Y144158D01*
X612050Y144200D01*
X612383Y144158D01*
X612675Y143992D01*
X612925Y143742D01*
X613092Y143450D01*
X613175Y143117D01*
Y142783D01*
X613092Y142450D01*
X612925Y142158D01*
X612675Y141908D01*
X612383Y141742D01*
X612050Y141700D01*
G01X614192D02*
Y144200D01*
X616108Y141700D01*
Y144200D01*
G01X630700Y115383D02*
X630100Y115633D01*
X629400Y115800D01*
X628600D01*
X627700Y115550D01*
X627000Y115133D01*
X626500Y114633D01*
X626100Y113800D01*
X626000Y113050D01*
X626200Y112300D01*
X626500Y111800D01*
X627100Y111300D01*
X627800Y110967D01*
X628500Y110800D01*
X629200D01*
X629900Y110967D01*
X630500Y111217D01*
X631000Y111550D01*
G01X606983Y125900D02*
Y133900D01*
X611417D01*
G01X609783Y130033D02*
X606983D01*
G01X627400Y136500D02*
X630100D01*
Y122800D01*
X627200D01*
G01X624700D02*
X617000D01*
G01X604100Y136470D02*
X624800D01*
G01X614100Y122800D02*
X604100D01*
G01X611709Y127881D02*
X615709D01*
Y135281D01*
G01X615711Y127881D02*
X619711D01*
Y135281D01*
G01X611950Y149100D02*
X611617Y149142D01*
X611325Y149308D01*
X611075Y149558D01*
X610908Y149850D01*
X610825Y150183D01*
Y150517D01*
X610908Y150850D01*
X611075Y151142D01*
X611325Y151392D01*
X611617Y151558D01*
X611950Y151600D01*
X612283Y151558D01*
X612575Y151392D01*
X612825Y151142D01*
X612992Y150850D01*
X613075Y150517D01*
Y150183D01*
X612992Y149850D01*
X612825Y149558D01*
X612575Y149308D01*
X612283Y149142D01*
X611950Y149100D01*
G01X614258D02*
Y151600D01*
X615842D01*
G01X615258Y150392D02*
X614258D01*
G01X617358Y149100D02*
Y151600D01*
X618942D01*
G01X618358Y150392D02*
X617358D01*
G01X611950Y145300D02*
X611617Y145342D01*
X611325Y145508D01*
X611075Y145758D01*
X610908Y146050D01*
X610825Y146383D01*
Y146717D01*
X610908Y147050D01*
X611075Y147342D01*
X611325Y147592D01*
X611617Y147758D01*
X611950Y147800D01*
X612283Y147758D01*
X612575Y147592D01*
X612825Y147342D01*
X612992Y147050D01*
X613075Y146717D01*
Y146383D01*
X612992Y146050D01*
X612825Y145758D01*
X612575Y145508D01*
X612283Y145342D01*
X611950Y145300D01*
G01X614258D02*
Y147800D01*
X615842D01*
G01X615258Y146592D02*
X614258D01*
G01X617358Y145300D02*
Y147800D01*
X618942D01*
G01X618358Y146592D02*
X617358D01*
G01X608167Y156600D02*
X607333D01*
Y153267D01*
X608167D01*
G01X610017Y156600D02*
Y154100D01*
X611683D01*
G01X614783D02*
X613117D01*
Y156600D01*
X614783D01*
G01X614117Y155392D02*
X613117D01*
G01X616133Y154100D02*
Y156600D01*
X616967D01*
X617300Y156475D01*
X617550Y156308D01*
X617758Y156058D01*
X617925Y155767D01*
X617967Y155350D01*
X617925Y154933D01*
X617758Y154642D01*
X617550Y154392D01*
X617300Y154225D01*
X616967Y154100D01*
X616133D01*
G01X620150D02*
Y156600D01*
X619650Y156100D01*
G01Y154100D02*
X620650D01*
G01X623250D02*
Y156600D01*
X622750Y156100D01*
G01Y154100D02*
X623750D01*
G01X625933Y153267D02*
X626767D01*
Y156600D01*
X625933D01*
G01X609508Y210537D02*
Y208537D01*
G01X617863Y211608D02*
Y207608D01*
X625263D01*
G01X625463Y211408D02*
Y207408D01*
X632863D01*
G01X637031Y180326D02*
X634531D01*
Y181367D01*
X634656Y181701D01*
X634823Y181909D01*
X635156Y181992D01*
X635489Y181909D01*
X635698Y181659D01*
X635823Y181367D01*
Y180326D01*
G01Y181367D02*
X637031Y181992D01*
G01Y184176D02*
X636489Y184259D01*
X636031Y184384D01*
X635614Y184551D01*
X635156Y184759D01*
X634531Y185092D01*
Y183426D01*
G01X635989Y186567D02*
X635698Y186859D01*
X635531Y187109D01*
X635448Y187442D01*
X635531Y187734D01*
X635698Y187942D01*
X635948Y188109D01*
X636239Y188151D01*
X636489Y188109D01*
X636739Y187942D01*
X636948Y187692D01*
X637031Y187401D01*
X636948Y187067D01*
X636698Y186776D01*
X636323Y186609D01*
X635906Y186567D01*
X635364Y186651D01*
X635073Y186776D01*
X634781Y186984D01*
X634573Y187276D01*
X634531Y187567D01*
X634614Y187859D01*
X634823Y188067D01*
G01X637031Y190376D02*
X636489Y190459D01*
X636031Y190584D01*
X635614Y190751D01*
X635156Y190959D01*
X634531Y191292D01*
Y189626D01*
G01X615674Y180829D02*
X613174D01*
Y181870D01*
X613299Y182204D01*
X613466Y182412D01*
X613799Y182495D01*
X614132Y182412D01*
X614341Y182162D01*
X614466Y181870D01*
Y180829D01*
G01Y181870D02*
X615674Y182495D01*
G01Y184679D02*
X615132Y184762D01*
X614674Y184887D01*
X614257Y185054D01*
X613799Y185262D01*
X613174Y185595D01*
Y183929D01*
G01X615674Y187779D02*
X615132Y187862D01*
X614674Y187987D01*
X614257Y188154D01*
X613799Y188362D01*
X613174Y188695D01*
Y187029D01*
G01Y190962D02*
X613257Y190629D01*
X613466Y190379D01*
X613716Y190212D01*
X614049Y190087D01*
X614424Y190045D01*
X614799Y190087D01*
X615132Y190212D01*
X615382Y190379D01*
X615591Y190629D01*
X615674Y190962D01*
X615591Y191295D01*
X615382Y191545D01*
X615132Y191712D01*
X614799Y191837D01*
X614424Y191879D01*
X614049Y191837D01*
X613716Y191712D01*
X613466Y191545D01*
X613257Y191295D01*
X613174Y190962D01*
G01X628614Y180703D02*
X626114D01*
Y181744D01*
X626239Y182078D01*
X626406Y182286D01*
X626739Y182369D01*
X627072Y182286D01*
X627281Y182036D01*
X627406Y181744D01*
Y180703D01*
G01Y181744D02*
X628614Y182369D01*
G01Y184553D02*
X628072Y184636D01*
X627614Y184761D01*
X627197Y184928D01*
X626739Y185136D01*
X626114Y185469D01*
Y183803D01*
G01X627572Y186944D02*
X627281Y187236D01*
X627114Y187486D01*
X627031Y187819D01*
X627114Y188111D01*
X627281Y188319D01*
X627531Y188486D01*
X627822Y188528D01*
X628072Y188486D01*
X628322Y188319D01*
X628531Y188069D01*
X628614Y187778D01*
X628531Y187444D01*
X628281Y187153D01*
X627906Y186986D01*
X627489Y186944D01*
X626947Y187028D01*
X626656Y187153D01*
X626364Y187361D01*
X626156Y187653D01*
X626114Y187944D01*
X626197Y188236D01*
X626406Y188444D01*
G01X628322Y190128D02*
X628531Y190419D01*
X628614Y190753D01*
X628531Y191086D01*
X628281Y191378D01*
X627906Y191586D01*
X627531Y191669D01*
X627072D01*
X626697Y191586D01*
X626364Y191378D01*
X626197Y191128D01*
X626114Y190836D01*
X626197Y190503D01*
X626364Y190253D01*
X626614Y190086D01*
X626947Y190003D01*
X627239Y190086D01*
X627531Y190294D01*
X627697Y190544D01*
X627739Y190836D01*
X627656Y191169D01*
X627447Y191419D01*
X627072Y191669D01*
G01X633011Y180452D02*
X630511D01*
Y181493D01*
X630636Y181827D01*
X630803Y182035D01*
X631136Y182118D01*
X631469Y182035D01*
X631678Y181785D01*
X631803Y181493D01*
Y180452D01*
G01Y181493D02*
X633011Y182118D01*
G01Y184302D02*
X632469Y184385D01*
X632011Y184510D01*
X631594Y184677D01*
X631136Y184885D01*
X630511Y185218D01*
Y183552D01*
G01X631969Y186693D02*
X631678Y186985D01*
X631511Y187235D01*
X631428Y187568D01*
X631511Y187860D01*
X631678Y188068D01*
X631928Y188235D01*
X632219Y188277D01*
X632469Y188235D01*
X632719Y188068D01*
X632928Y187818D01*
X633011Y187527D01*
X632928Y187193D01*
X632678Y186902D01*
X632303Y186735D01*
X631886Y186693D01*
X631344Y186777D01*
X631053Y186902D01*
X630761Y187110D01*
X630553Y187402D01*
X630511Y187693D01*
X630594Y187985D01*
X630803Y188193D01*
G01X633011Y190585D02*
X632969Y190877D01*
X632844Y191210D01*
X632636Y191418D01*
X632344Y191502D01*
X632053Y191418D01*
X631803Y191168D01*
X631678Y190793D01*
Y190377D01*
X631594Y190127D01*
X631386Y189918D01*
X631094Y189835D01*
X630803Y189960D01*
X630594Y190252D01*
X630511Y190585D01*
X630594Y190918D01*
X630803Y191210D01*
X631094Y191335D01*
X631386Y191252D01*
X631594Y191043D01*
X631678Y190793D01*
Y190377D01*
X631803Y190002D01*
X632053Y189752D01*
X632344Y189668D01*
X632636Y189752D01*
X632844Y189960D01*
X632969Y190293D01*
X633011Y190585D01*
G01X619945Y180829D02*
X617445D01*
Y181870D01*
X617570Y182204D01*
X617737Y182412D01*
X618070Y182495D01*
X618403Y182412D01*
X618612Y182162D01*
X618737Y181870D01*
Y180829D01*
G01Y181870D02*
X619945Y182495D01*
G01Y184679D02*
X619403Y184762D01*
X618945Y184887D01*
X618528Y185054D01*
X618070Y185262D01*
X617445Y185595D01*
Y183929D01*
G01X618903Y187070D02*
X618612Y187362D01*
X618445Y187612D01*
X618362Y187945D01*
X618445Y188237D01*
X618612Y188445D01*
X618862Y188612D01*
X619153Y188654D01*
X619403Y188612D01*
X619653Y188445D01*
X619862Y188195D01*
X619945Y187904D01*
X619862Y187570D01*
X619612Y187279D01*
X619237Y187112D01*
X618820Y187070D01*
X618278Y187154D01*
X617987Y187279D01*
X617695Y187487D01*
X617487Y187779D01*
X617445Y188070D01*
X617528Y188362D01*
X617737Y188570D01*
G01X619945Y190962D02*
X617445D01*
X617945Y190462D01*
G01X619945D02*
Y191462D01*
G01X624091Y180829D02*
X621591D01*
Y181870D01*
X621716Y182204D01*
X621883Y182412D01*
X622216Y182495D01*
X622549Y182412D01*
X622758Y182162D01*
X622883Y181870D01*
Y180829D01*
G01Y181870D02*
X624091Y182495D01*
G01Y184679D02*
X623549Y184762D01*
X623091Y184887D01*
X622674Y185054D01*
X622216Y185262D01*
X621591Y185595D01*
Y183929D01*
G01X623716Y186945D02*
X623924Y187195D01*
X624049Y187487D01*
X624091Y187862D01*
X624008Y188237D01*
X623841Y188529D01*
X623549Y188737D01*
X623216Y188779D01*
X622883Y188695D01*
X622674Y188487D01*
X622508Y188195D01*
X622466Y187904D01*
X622508Y187612D01*
X622674Y187237D01*
X621591Y187362D01*
Y188487D01*
G01X624091Y190879D02*
X623549Y190962D01*
X623091Y191087D01*
X622674Y191254D01*
X622216Y191462D01*
X621591Y191795D01*
Y190129D01*
G01X611151Y180954D02*
X608651D01*
Y181995D01*
X608776Y182329D01*
X608943Y182537D01*
X609276Y182620D01*
X609609Y182537D01*
X609818Y182287D01*
X609943Y181995D01*
Y180954D01*
G01Y181995D02*
X611151Y182620D01*
G01Y184804D02*
X610609Y184887D01*
X610151Y185012D01*
X609734Y185179D01*
X609276Y185387D01*
X608651Y185720D01*
Y184054D01*
G01X610776Y187070D02*
X610984Y187320D01*
X611109Y187612D01*
X611151Y187987D01*
X611068Y188362D01*
X610901Y188654D01*
X610609Y188862D01*
X610276Y188904D01*
X609943Y188820D01*
X609734Y188612D01*
X609568Y188320D01*
X609526Y188029D01*
X609568Y187737D01*
X609734Y187362D01*
X608651Y187487D01*
Y188612D01*
G01X611151Y191587D02*
X608651D01*
X610443Y190045D01*
Y192129D01*
G01X615833Y217333D02*
X611167D01*
Y225333D01*
X615833D01*
G01X613967Y221466D02*
X611167D01*
G01X617500Y227000D02*
Y237500D01*
G01X615606Y238889D02*
X617606D01*
G01X664363Y241258D02*
Y273958D01*
X617163D01*
Y241258D01*
X664363D01*
G01X625063Y215608D02*
Y219608D01*
X617663D01*
G01X625463D02*
Y215608D01*
X632863D01*
G01X633363Y233808D02*
X629363D01*
Y226408D01*
G01X620163Y240108D02*
Y236108D01*
X627563D01*
G01X617563Y211608D02*
Y215608D01*
X610163D01*
G01X625363Y233808D02*
X621363D01*
Y226408D01*
G01X625363D02*
X629363D01*
Y233808D01*
G01X625463Y215508D02*
Y211508D01*
X632863D01*
G01X615606Y248732D02*
X618606D01*
G01X616613Y249858D02*
Y254858D01*
X611613D01*
G01X636480Y276775D02*
Y279275D01*
X637480D01*
X637813Y279150D01*
X638063Y278858D01*
X638146Y278525D01*
X638063Y278192D01*
X637855Y277942D01*
X637480Y277817D01*
X636480D01*
G01X639580Y279275D02*
Y276775D01*
X641246D01*
G01X643513D02*
Y279275D01*
X643013Y278775D01*
G01Y276775D02*
X644013D01*
G01X646613D02*
Y279275D01*
X646113Y278775D01*
G01Y276775D02*
X647113D01*
G01X616667Y288300D02*
Y290800D01*
X617667D01*
X618000Y290675D01*
X618250Y290383D01*
X618333Y290050D01*
X618250Y289717D01*
X618042Y289467D01*
X617667Y289342D01*
X616667D01*
G01X621517Y290592D02*
X621267Y290717D01*
X620975Y290800D01*
X620642D01*
X620267Y290675D01*
X619975Y290467D01*
X619767Y290217D01*
X619600Y289800D01*
X619558Y289425D01*
X619642Y289050D01*
X619767Y288800D01*
X620017Y288550D01*
X620308Y288383D01*
X620600Y288300D01*
X620892D01*
X621183Y288383D01*
X621433Y288508D01*
X621642Y288675D01*
G01X623700Y288300D02*
Y290800D01*
X623200Y290300D01*
G01Y288300D02*
X624200D01*
G01X626092Y288592D02*
X626383Y288383D01*
X626717Y288300D01*
X627050Y288383D01*
X627342Y288633D01*
X627550Y289008D01*
X627633Y289383D01*
Y289842D01*
X627550Y290217D01*
X627342Y290550D01*
X627092Y290717D01*
X626800Y290800D01*
X626467Y290717D01*
X626217Y290550D01*
X626050Y290300D01*
X625967Y289967D01*
X626050Y289675D01*
X626258Y289383D01*
X626508Y289217D01*
X626800Y289175D01*
X627133Y289258D01*
X627383Y289467D01*
X627633Y289842D01*
G01X629108Y290383D02*
X629358Y290633D01*
X629650Y290758D01*
X629983Y290800D01*
X630400Y290717D01*
X630692Y290508D01*
X630775Y290258D01*
X630733Y290008D01*
X630567Y289800D01*
X629733Y289383D01*
X629358Y289092D01*
X629108Y288675D01*
X629025Y288300D01*
X630775D01*
G01X616667Y284400D02*
Y286900D01*
X617667D01*
X618000Y286775D01*
X618250Y286483D01*
X618333Y286150D01*
X618250Y285817D01*
X618042Y285567D01*
X617667Y285442D01*
X616667D01*
G01X621517Y286692D02*
X621267Y286817D01*
X620975Y286900D01*
X620642D01*
X620267Y286775D01*
X619975Y286567D01*
X619767Y286317D01*
X619600Y285900D01*
X619558Y285525D01*
X619642Y285150D01*
X619767Y284900D01*
X620017Y284650D01*
X620308Y284483D01*
X620600Y284400D01*
X620892D01*
X621183Y284483D01*
X621433Y284608D01*
X621642Y284775D01*
G01X623700Y284400D02*
Y286900D01*
X623200Y286400D01*
G01Y284400D02*
X624200D01*
G01X626092Y284692D02*
X626383Y284483D01*
X626717Y284400D01*
X627050Y284483D01*
X627342Y284733D01*
X627550Y285108D01*
X627633Y285483D01*
Y285942D01*
X627550Y286317D01*
X627342Y286650D01*
X627092Y286817D01*
X626800Y286900D01*
X626467Y286817D01*
X626217Y286650D01*
X626050Y286400D01*
X625967Y286067D01*
X626050Y285775D01*
X626258Y285483D01*
X626508Y285317D01*
X626800Y285275D01*
X627133Y285358D01*
X627383Y285567D01*
X627633Y285942D01*
G01X629900Y284400D02*
Y286900D01*
X629400Y286400D01*
G01Y284400D02*
X630400D01*
G01X631692Y309804D02*
Y312304D01*
X632733D01*
X633067Y312179D01*
X633275Y312012D01*
X633358Y311679D01*
X633275Y311346D01*
X633025Y311137D01*
X632733Y311012D01*
X631692D01*
G01X632733D02*
X633358Y309804D01*
G01X636125D02*
Y312304D01*
X634583Y310512D01*
X636667D01*
G01X639225Y309804D02*
Y312304D01*
X637683Y310512D01*
X639767D01*
G01X616667Y292200D02*
Y294700D01*
X617667D01*
X618000Y294575D01*
X618250Y294283D01*
X618333Y293950D01*
X618250Y293617D01*
X618042Y293367D01*
X617667Y293242D01*
X616667D01*
G01X621517Y294492D02*
X621267Y294617D01*
X620975Y294700D01*
X620642D01*
X620267Y294575D01*
X619975Y294367D01*
X619767Y294117D01*
X619600Y293700D01*
X619558Y293325D01*
X619642Y292950D01*
X619767Y292700D01*
X620017Y292450D01*
X620308Y292283D01*
X620600Y292200D01*
X620892D01*
X621183Y292283D01*
X621433Y292408D01*
X621642Y292575D01*
G01X622908Y294283D02*
X623158Y294533D01*
X623450Y294658D01*
X623783Y294700D01*
X624200Y294617D01*
X624492Y294408D01*
X624575Y294158D01*
X624533Y293908D01*
X624367Y293700D01*
X623533Y293283D01*
X623158Y292992D01*
X622908Y292575D01*
X622825Y292200D01*
X624575D01*
G01X626800D02*
Y294700D01*
X626300Y294200D01*
G01Y292200D02*
X627300D01*
G01X629900Y294700D02*
X629567Y294617D01*
X629317Y294408D01*
X629150Y294158D01*
X629025Y293825D01*
X628983Y293450D01*
X629025Y293075D01*
X629150Y292742D01*
X629317Y292492D01*
X629567Y292283D01*
X629900Y292200D01*
X630233Y292283D01*
X630483Y292492D01*
X630650Y292742D01*
X630775Y293075D01*
X630817Y293450D01*
X630775Y293825D01*
X630650Y294158D01*
X630483Y294408D01*
X630233Y294617D01*
X629900Y294700D01*
G01X616530Y299908D02*
Y302408D01*
X617530D01*
X617863Y302283D01*
X618113Y301991D01*
X618196Y301658D01*
X618113Y301325D01*
X617905Y301075D01*
X617530Y300950D01*
X616530D01*
G01X621380Y302200D02*
X621130Y302325D01*
X620838Y302408D01*
X620505D01*
X620130Y302283D01*
X619838Y302075D01*
X619630Y301825D01*
X619463Y301408D01*
X619421Y301033D01*
X619505Y300658D01*
X619630Y300408D01*
X619880Y300158D01*
X620171Y299991D01*
X620463Y299908D01*
X620755D01*
X621046Y299991D01*
X621296Y300116D01*
X621505Y300283D01*
G01X622771Y301991D02*
X623021Y302241D01*
X623313Y302366D01*
X623646Y302408D01*
X624063Y302325D01*
X624355Y302116D01*
X624438Y301866D01*
X624396Y301616D01*
X624230Y301408D01*
X623396Y300991D01*
X623021Y300700D01*
X622771Y300283D01*
X622688Y299908D01*
X624438D01*
G01X626663D02*
Y302408D01*
X626163Y301908D01*
G01Y299908D02*
X627163D01*
G01X628846Y300408D02*
X629096Y300116D01*
X629430Y299950D01*
X629805Y299908D01*
X630138Y299950D01*
X630471Y300158D01*
X630680Y300408D01*
X630721Y300658D01*
X630638Y300950D01*
X630346Y301158D01*
X630055Y301241D01*
X629680D01*
G01X630055D02*
X630305Y301366D01*
X630513Y301575D01*
X630596Y301825D01*
X630513Y302075D01*
X630305Y302283D01*
X629930Y302408D01*
X629555Y302366D01*
X629180Y302200D01*
G01X616667Y296100D02*
Y298600D01*
X617667D01*
X618000Y298475D01*
X618250Y298183D01*
X618333Y297850D01*
X618250Y297517D01*
X618042Y297267D01*
X617667Y297142D01*
X616667D01*
G01X621517Y298392D02*
X621267Y298517D01*
X620975Y298600D01*
X620642D01*
X620267Y298475D01*
X619975Y298267D01*
X619767Y298017D01*
X619600Y297600D01*
X619558Y297225D01*
X619642Y296850D01*
X619767Y296600D01*
X620017Y296350D01*
X620308Y296183D01*
X620600Y296100D01*
X620892D01*
X621183Y296183D01*
X621433Y296308D01*
X621642Y296475D01*
G01X622908Y298183D02*
X623158Y298433D01*
X623450Y298558D01*
X623783Y298600D01*
X624200Y298517D01*
X624492Y298308D01*
X624575Y298058D01*
X624533Y297808D01*
X624367Y297600D01*
X623533Y297183D01*
X623158Y296892D01*
X622908Y296475D01*
X622825Y296100D01*
X624575D01*
G01X626800D02*
Y298600D01*
X626300Y298100D01*
G01Y296100D02*
X627300D01*
G01X629900D02*
Y298600D01*
X629400Y298100D01*
G01Y296100D02*
X630400D01*
G01X628079Y344157D02*
Y341157D01*
G01X619150Y347750D02*
Y342750D01*
X624150D01*
G01X611830Y324717D02*
X614330D01*
Y326383D01*
G01Y328650D02*
X611830D01*
X612330Y328150D01*
G01X614330D02*
Y329150D01*
G01X611830Y331750D02*
X611913Y331417D01*
X612122Y331167D01*
X612372Y331000D01*
X612705Y330875D01*
X613080Y330833D01*
X613455Y330875D01*
X613788Y331000D01*
X614038Y331167D01*
X614247Y331417D01*
X614330Y331750D01*
X614247Y332083D01*
X614038Y332333D01*
X613788Y332500D01*
X613455Y332625D01*
X613080Y332667D01*
X612705Y332625D01*
X612372Y332500D01*
X612122Y332333D01*
X611913Y332083D01*
X611830Y331750D01*
G01X631960Y316712D02*
Y314212D01*
G01X631002Y316712D02*
X632918D01*
G01X634227Y314212D02*
Y316712D01*
X635227D01*
X635560Y316587D01*
X635810Y316295D01*
X635893Y315962D01*
X635810Y315629D01*
X635602Y315379D01*
X635227Y315254D01*
X634227D01*
G01X638077Y314212D02*
X638160Y314754D01*
X638285Y315212D01*
X638452Y315629D01*
X638660Y316087D01*
X638993Y316712D01*
X637327D01*
G01X641260Y314212D02*
X641552Y314254D01*
X641885Y314379D01*
X642093Y314587D01*
X642177Y314879D01*
X642093Y315170D01*
X641843Y315420D01*
X641468Y315545D01*
X641052D01*
X640802Y315629D01*
X640593Y315837D01*
X640510Y316129D01*
X640635Y316420D01*
X640927Y316629D01*
X641260Y316712D01*
X641593Y316629D01*
X641885Y316420D01*
X642010Y316129D01*
X641927Y315837D01*
X641718Y315629D01*
X641468Y315545D01*
X641052D01*
X640677Y315420D01*
X640427Y315170D01*
X640343Y314879D01*
X640427Y314587D01*
X640635Y314379D01*
X640968Y314254D01*
X641260Y314212D01*
G01X628126Y311891D02*
X625626D01*
Y312932D01*
X625751Y313266D01*
X625918Y313474D01*
X626251Y313557D01*
X626584Y313474D01*
X626793Y313224D01*
X626918Y312932D01*
Y311891D01*
G01Y312932D02*
X628126Y313557D01*
G01X627626Y314907D02*
X627918Y315157D01*
X628084Y315491D01*
X628126Y315866D01*
X628084Y316199D01*
X627876Y316532D01*
X627626Y316741D01*
X627376Y316782D01*
X627084Y316699D01*
X626876Y316407D01*
X626793Y316116D01*
Y315741D01*
G01Y316116D02*
X626668Y316366D01*
X626459Y316574D01*
X626209Y316657D01*
X625959Y316574D01*
X625751Y316366D01*
X625626Y315991D01*
X625668Y315616D01*
X625834Y315241D01*
G01X628126Y318924D02*
X625626D01*
X626126Y318424D01*
G01X628126D02*
Y319424D01*
G01X625626Y322024D02*
X625709Y321691D01*
X625918Y321441D01*
X626168Y321274D01*
X626501Y321149D01*
X626876Y321107D01*
X627251Y321149D01*
X627584Y321274D01*
X627834Y321441D01*
X628043Y321691D01*
X628126Y322024D01*
X628043Y322357D01*
X627834Y322607D01*
X627584Y322774D01*
X627251Y322899D01*
X626876Y322941D01*
X626501Y322899D01*
X626168Y322774D01*
X625918Y322607D01*
X625709Y322357D01*
X625626Y322024D01*
G01X627626Y324207D02*
X627918Y324457D01*
X628084Y324791D01*
X628126Y325166D01*
X628084Y325499D01*
X627876Y325832D01*
X627626Y326041D01*
X627376Y326082D01*
X627084Y325999D01*
X626876Y325707D01*
X626793Y325416D01*
Y325041D01*
G01Y325416D02*
X626668Y325666D01*
X626459Y325874D01*
X626209Y325957D01*
X625959Y325874D01*
X625751Y325666D01*
X625626Y325291D01*
X625668Y324916D01*
X625834Y324541D01*
G01X610090Y336060D02*
X606090D01*
Y328660D01*
G01X620126Y311891D02*
X617626D01*
Y312932D01*
X617751Y313266D01*
X617918Y313474D01*
X618251Y313557D01*
X618584Y313474D01*
X618793Y313224D01*
X618918Y312932D01*
Y311891D01*
G01Y312932D02*
X620126Y313557D01*
G01Y315741D02*
X619584Y315824D01*
X619126Y315949D01*
X618709Y316116D01*
X618251Y316324D01*
X617626Y316657D01*
Y314991D01*
G01X620126Y318841D02*
X619584Y318924D01*
X619126Y319049D01*
X618709Y319216D01*
X618251Y319424D01*
X617626Y319757D01*
Y318091D01*
G01X634000Y339300D02*
X630000D01*
Y331900D01*
G01X616126Y311891D02*
X613626D01*
Y312932D01*
X613751Y313266D01*
X613918Y313474D01*
X614251Y313557D01*
X614584Y313474D01*
X614793Y313224D01*
X614918Y312932D01*
Y311891D01*
G01Y312932D02*
X616126Y313557D01*
G01Y315741D02*
X615584Y315824D01*
X615126Y315949D01*
X614709Y316116D01*
X614251Y316324D01*
X613626Y316657D01*
Y314991D01*
G01X615751Y318007D02*
X615959Y318257D01*
X616084Y318549D01*
X616126Y318924D01*
X616043Y319299D01*
X615876Y319591D01*
X615584Y319799D01*
X615251Y319841D01*
X614918Y319757D01*
X614709Y319549D01*
X614543Y319257D01*
X614501Y318966D01*
X614543Y318674D01*
X614709Y318299D01*
X613626Y318424D01*
Y319549D01*
G01X626000Y331900D02*
X630000D01*
Y339300D01*
G01X612126Y311891D02*
X609626D01*
Y312932D01*
X609751Y313266D01*
X609918Y313474D01*
X610251Y313557D01*
X610584Y313474D01*
X610793Y313224D01*
X610918Y312932D01*
Y311891D01*
G01Y312932D02*
X612126Y313557D01*
G01Y315741D02*
X611584Y315824D01*
X611126Y315949D01*
X610709Y316116D01*
X610251Y316324D01*
X609626Y316657D01*
Y314991D01*
G01X612126Y319424D02*
X609626D01*
X611418Y317882D01*
Y319966D01*
G01X622000Y331900D02*
X626000D01*
Y339300D01*
G01X630000Y318900D02*
X634000D01*
Y326300D01*
G01X624126Y311891D02*
X621626D01*
Y312932D01*
X621751Y313266D01*
X621918Y313474D01*
X622251Y313557D01*
X622584Y313474D01*
X622793Y313224D01*
X622918Y312932D01*
Y311891D01*
G01Y312932D02*
X624126Y313557D01*
G01X623626Y314907D02*
X623918Y315157D01*
X624084Y315491D01*
X624126Y315866D01*
X624084Y316199D01*
X623876Y316532D01*
X623626Y316741D01*
X623376Y316782D01*
X623084Y316699D01*
X622876Y316407D01*
X622793Y316116D01*
Y315741D01*
G01Y316116D02*
X622668Y316366D01*
X622459Y316574D01*
X622209Y316657D01*
X621959Y316574D01*
X621751Y316366D01*
X621626Y315991D01*
X621668Y315616D01*
X621834Y315241D01*
G01X624126Y318924D02*
X621626D01*
X622126Y318424D01*
G01X624126D02*
Y319424D01*
G01X621626Y322024D02*
X621709Y321691D01*
X621918Y321441D01*
X622168Y321274D01*
X622501Y321149D01*
X622876Y321107D01*
X623251Y321149D01*
X623584Y321274D01*
X623834Y321441D01*
X624043Y321691D01*
X624126Y322024D01*
X624043Y322357D01*
X623834Y322607D01*
X623584Y322774D01*
X623251Y322899D01*
X622876Y322941D01*
X622501Y322899D01*
X622168Y322774D01*
X621918Y322607D01*
X621709Y322357D01*
X621626Y322024D01*
G01X622043Y324332D02*
X621793Y324582D01*
X621668Y324874D01*
X621626Y325207D01*
X621709Y325624D01*
X621918Y325916D01*
X622168Y325999D01*
X622418Y325957D01*
X622626Y325791D01*
X623043Y324957D01*
X623334Y324582D01*
X623751Y324332D01*
X624126Y324249D01*
Y325999D01*
G01X638000Y339300D02*
X634000D01*
Y331900D01*
G01X604486Y373827D02*
X604361Y373577D01*
X604278Y373285D01*
Y372952D01*
X604403Y372577D01*
X604611Y372285D01*
X604861Y372077D01*
X605278Y371910D01*
X605653Y371868D01*
X606028Y371952D01*
X606278Y372077D01*
X606528Y372327D01*
X606695Y372618D01*
X606778Y372910D01*
Y373202D01*
X606695Y373493D01*
X606570Y373743D01*
X606403Y373952D01*
G01X606778Y376510D02*
X604278D01*
X606070Y374968D01*
Y377052D01*
G01X606778Y379110D02*
X604278D01*
X604778Y378610D01*
G01X606778D02*
Y379610D01*
G01X604695Y381418D02*
X604445Y381668D01*
X604320Y381960D01*
X604278Y382293D01*
X604361Y382710D01*
X604570Y383002D01*
X604820Y383085D01*
X605070Y383043D01*
X605278Y382877D01*
X605695Y382043D01*
X605986Y381668D01*
X606403Y381418D01*
X606778Y381335D01*
Y383085D01*
G01X620557Y355616D02*
X618557D01*
G01X630047Y369043D02*
Y372043D01*
G01X613100Y359800D02*
X617100D01*
Y367200D01*
G01X619000Y381300D02*
X615000D01*
Y373900D01*
G01X630000D02*
X634000D01*
Y381300D01*
G01X610982Y374509D02*
X608482D01*
Y375550D01*
X608607Y375884D01*
X608774Y376092D01*
X609107Y376175D01*
X609440Y376092D01*
X609649Y375842D01*
X609774Y375550D01*
Y374509D01*
G01Y375550D02*
X610982Y376175D01*
G01Y378359D02*
X610440Y378442D01*
X609982Y378567D01*
X609565Y378734D01*
X609107Y378942D01*
X608482Y379275D01*
Y377609D01*
G01X610982Y381542D02*
X610940Y381834D01*
X610815Y382167D01*
X610607Y382375D01*
X610315Y382459D01*
X610024Y382375D01*
X609774Y382125D01*
X609649Y381750D01*
Y381334D01*
X609565Y381084D01*
X609357Y380875D01*
X609065Y380792D01*
X608774Y380917D01*
X608565Y381209D01*
X608482Y381542D01*
X608565Y381875D01*
X608774Y382167D01*
X609065Y382292D01*
X609357Y382209D01*
X609565Y382000D01*
X609649Y381750D01*
Y381334D01*
X609774Y380959D01*
X610024Y380709D01*
X610315Y380625D01*
X610607Y380709D01*
X610815Y380917D01*
X610940Y381250D01*
X610982Y381542D01*
G01X611500Y351683D02*
X615500D01*
Y359083D01*
G01X625500Y373900D02*
X629500D01*
Y381300D01*
G01X634300Y373900D02*
X638300D01*
Y381300D01*
G01X625000D02*
X621000D01*
Y373900D01*
G01X604486Y388557D02*
X604361Y388307D01*
X604278Y388015D01*
Y387682D01*
X604403Y387307D01*
X604611Y387015D01*
X604861Y386807D01*
X605278Y386640D01*
X605653Y386598D01*
X606028Y386682D01*
X606278Y386807D01*
X606528Y387057D01*
X606695Y387348D01*
X606778Y387640D01*
Y387932D01*
X606695Y388223D01*
X606570Y388473D01*
X606403Y388682D01*
G01X606778Y391240D02*
X604278D01*
X606070Y389698D01*
Y391782D01*
G01X606778Y393840D02*
X604278D01*
X604778Y393340D01*
G01X606778D02*
Y394340D01*
G01X606278Y396023D02*
X606570Y396273D01*
X606736Y396607D01*
X606778Y396982D01*
X606736Y397315D01*
X606528Y397648D01*
X606278Y397857D01*
X606028Y397898D01*
X605736Y397815D01*
X605528Y397523D01*
X605445Y397232D01*
Y396857D01*
G01Y397232D02*
X605320Y397482D01*
X605111Y397690D01*
X604861Y397773D01*
X604611Y397690D01*
X604403Y397482D01*
X604278Y397107D01*
X604320Y396732D01*
X604486Y396357D01*
G01X627500Y412350D02*
X630000D01*
G01X627500Y411392D02*
Y413308D01*
G01X630000Y414617D02*
X627500D01*
Y415617D01*
X627625Y415950D01*
X627917Y416200D01*
X628250Y416283D01*
X628583Y416200D01*
X628833Y415992D01*
X628958Y415617D01*
Y414617D01*
G01X630000Y418467D02*
X629458Y418550D01*
X629000Y418675D01*
X628583Y418842D01*
X628125Y419050D01*
X627500Y419383D01*
Y417717D01*
G01X630000Y421567D02*
X629458Y421650D01*
X629000Y421775D01*
X628583Y421942D01*
X628125Y422150D01*
X627500Y422483D01*
Y420817D01*
G01X631500Y412350D02*
X634000D01*
G01X631500Y411392D02*
Y413308D01*
G01X634000Y414617D02*
X631500D01*
Y415617D01*
X631625Y415950D01*
X631917Y416200D01*
X632250Y416283D01*
X632583Y416200D01*
X632833Y415992D01*
X632958Y415617D01*
Y414617D01*
G01X634000Y418550D02*
X633958Y418842D01*
X633833Y419175D01*
X633625Y419383D01*
X633333Y419467D01*
X633042Y419383D01*
X632792Y419133D01*
X632667Y418758D01*
Y418342D01*
X632583Y418092D01*
X632375Y417883D01*
X632083Y417800D01*
X631792Y417925D01*
X631583Y418217D01*
X631500Y418550D01*
X631583Y418883D01*
X631792Y419175D01*
X632083Y419300D01*
X632375Y419217D01*
X632583Y419008D01*
X632667Y418758D01*
Y418342D01*
X632792Y417967D01*
X633042Y417717D01*
X633333Y417633D01*
X633625Y417717D01*
X633833Y417925D01*
X633958Y418258D01*
X634000Y418550D01*
G01Y421650D02*
X631500D01*
X632000Y421150D01*
G01X634000D02*
Y422150D01*
G01X635500Y412350D02*
X638000D01*
G01X635500Y411392D02*
Y413308D01*
G01X638000Y414617D02*
X635500D01*
Y415617D01*
X635625Y415950D01*
X635917Y416200D01*
X636250Y416283D01*
X636583Y416200D01*
X636833Y415992D01*
X636958Y415617D01*
Y414617D01*
G01X638000Y418550D02*
X637958Y418842D01*
X637833Y419175D01*
X637625Y419383D01*
X637333Y419467D01*
X637042Y419383D01*
X636792Y419133D01*
X636667Y418758D01*
Y418342D01*
X636583Y418092D01*
X636375Y417883D01*
X636083Y417800D01*
X635792Y417925D01*
X635583Y418217D01*
X635500Y418550D01*
X635583Y418883D01*
X635792Y419175D01*
X636083Y419300D01*
X636375Y419217D01*
X636583Y419008D01*
X636667Y418758D01*
Y418342D01*
X636792Y417967D01*
X637042Y417717D01*
X637333Y417633D01*
X637625Y417717D01*
X637833Y417925D01*
X637958Y418258D01*
X638000Y418550D01*
G01X635500Y421650D02*
X635583Y421317D01*
X635792Y421067D01*
X636042Y420900D01*
X636375Y420775D01*
X636750Y420733D01*
X637125Y420775D01*
X637458Y420900D01*
X637708Y421067D01*
X637917Y421317D01*
X638000Y421650D01*
X637917Y421983D01*
X637708Y422233D01*
X637458Y422400D01*
X637125Y422525D01*
X636750Y422567D01*
X636375Y422525D01*
X636042Y422400D01*
X635792Y422233D01*
X635583Y421983D01*
X635500Y421650D01*
G01X610982Y386076D02*
X608482D01*
Y387117D01*
X608607Y387451D01*
X608774Y387659D01*
X609107Y387742D01*
X609440Y387659D01*
X609649Y387409D01*
X609774Y387117D01*
Y386076D01*
G01Y387117D02*
X610982Y387742D01*
G01Y389926D02*
X610440Y390009D01*
X609982Y390134D01*
X609565Y390301D01*
X609107Y390509D01*
X608482Y390842D01*
Y389176D01*
G01X610982Y393109D02*
X608482D01*
X608982Y392609D01*
G01X610982D02*
Y393609D01*
G01X608899Y395417D02*
X608649Y395667D01*
X608524Y395959D01*
X608482Y396292D01*
X608565Y396709D01*
X608774Y397001D01*
X609024Y397084D01*
X609274Y397042D01*
X609482Y396876D01*
X609899Y396042D01*
X610190Y395667D01*
X610607Y395417D01*
X610982Y395334D01*
Y397084D01*
G01X616827Y395067D02*
X614327D01*
Y396108D01*
X614452Y396442D01*
X614619Y396650D01*
X614952Y396733D01*
X615285Y396650D01*
X615494Y396400D01*
X615619Y396108D01*
Y395067D01*
G01Y396108D02*
X616827Y396733D01*
G01X616535Y398292D02*
X616744Y398583D01*
X616827Y398917D01*
X616744Y399250D01*
X616494Y399542D01*
X616119Y399750D01*
X615744Y399833D01*
X615285D01*
X614910Y399750D01*
X614577Y399542D01*
X614410Y399292D01*
X614327Y399000D01*
X614410Y398667D01*
X614577Y398417D01*
X614827Y398250D01*
X615160Y398167D01*
X615452Y398250D01*
X615744Y398458D01*
X615910Y398708D01*
X615952Y399000D01*
X615869Y399333D01*
X615660Y399583D01*
X615285Y399833D01*
G01X616827Y402017D02*
X616285Y402100D01*
X615827Y402225D01*
X615410Y402392D01*
X614952Y402600D01*
X614327Y402933D01*
Y401267D01*
G01X628827Y395067D02*
X626327D01*
Y396108D01*
X626452Y396442D01*
X626619Y396650D01*
X626952Y396733D01*
X627285Y396650D01*
X627494Y396400D01*
X627619Y396108D01*
Y395067D01*
G01Y396108D02*
X628827Y396733D01*
G01Y399000D02*
X628785Y399292D01*
X628660Y399625D01*
X628452Y399833D01*
X628160Y399917D01*
X627869Y399833D01*
X627619Y399583D01*
X627494Y399208D01*
Y398792D01*
X627410Y398542D01*
X627202Y398333D01*
X626910Y398250D01*
X626619Y398375D01*
X626410Y398667D01*
X626327Y399000D01*
X626410Y399333D01*
X626619Y399625D01*
X626910Y399750D01*
X627202Y399667D01*
X627410Y399458D01*
X627494Y399208D01*
Y398792D01*
X627619Y398417D01*
X627869Y398167D01*
X628160Y398083D01*
X628452Y398167D01*
X628660Y398375D01*
X628785Y398708D01*
X628827Y399000D01*
G01X628535Y401392D02*
X628744Y401683D01*
X628827Y402017D01*
X628744Y402350D01*
X628494Y402642D01*
X628119Y402850D01*
X627744Y402933D01*
X627285D01*
X626910Y402850D01*
X626577Y402642D01*
X626410Y402392D01*
X626327Y402100D01*
X626410Y401767D01*
X626577Y401517D01*
X626827Y401350D01*
X627160Y401267D01*
X627452Y401350D01*
X627744Y401558D01*
X627910Y401808D01*
X627952Y402100D01*
X627869Y402433D01*
X627660Y402683D01*
X627285Y402933D01*
G01X624827Y395067D02*
X622327D01*
Y396108D01*
X622452Y396442D01*
X622619Y396650D01*
X622952Y396733D01*
X623285Y396650D01*
X623494Y396400D01*
X623619Y396108D01*
Y395067D01*
G01Y396108D02*
X624827Y396733D01*
G01X623785Y398208D02*
X623494Y398500D01*
X623327Y398750D01*
X623244Y399083D01*
X623327Y399375D01*
X623494Y399583D01*
X623744Y399750D01*
X624035Y399792D01*
X624285Y399750D01*
X624535Y399583D01*
X624744Y399333D01*
X624827Y399042D01*
X624744Y398708D01*
X624494Y398417D01*
X624119Y398250D01*
X623702Y398208D01*
X623160Y398292D01*
X622869Y398417D01*
X622577Y398625D01*
X622369Y398917D01*
X622327Y399208D01*
X622410Y399500D01*
X622619Y399708D01*
G01X624827Y402100D02*
X622327D01*
X622827Y401600D01*
G01X624827D02*
Y402600D01*
G01X632127Y394967D02*
X629627D01*
Y396008D01*
X629752Y396342D01*
X629919Y396550D01*
X630252Y396633D01*
X630585Y396550D01*
X630794Y396300D01*
X630919Y396008D01*
Y394967D01*
G01Y396008D02*
X632127Y396633D01*
G01X631627Y397983D02*
X631919Y398233D01*
X632085Y398567D01*
X632127Y398942D01*
X632085Y399275D01*
X631877Y399608D01*
X631627Y399817D01*
X631377Y399858D01*
X631085Y399775D01*
X630877Y399483D01*
X630794Y399192D01*
Y398817D01*
G01Y399192D02*
X630669Y399442D01*
X630460Y399650D01*
X630210Y399733D01*
X629960Y399650D01*
X629752Y399442D01*
X629627Y399067D01*
X629669Y398692D01*
X629835Y398317D01*
G01X632127Y402000D02*
X629627D01*
X630127Y401500D01*
G01X632127D02*
Y402500D01*
G01X629627Y405100D02*
X629710Y404767D01*
X629919Y404517D01*
X630169Y404350D01*
X630502Y404225D01*
X630877Y404183D01*
X631252Y404225D01*
X631585Y404350D01*
X631835Y404517D01*
X632044Y404767D01*
X632127Y405100D01*
X632044Y405433D01*
X631835Y405683D01*
X631585Y405850D01*
X631252Y405975D01*
X630877Y406017D01*
X630502Y405975D01*
X630169Y405850D01*
X629919Y405683D01*
X629710Y405433D01*
X629627Y405100D01*
G01X631835Y407492D02*
X632044Y407783D01*
X632127Y408117D01*
X632044Y408450D01*
X631794Y408742D01*
X631419Y408950D01*
X631044Y409033D01*
X630585D01*
X630210Y408950D01*
X629877Y408742D01*
X629710Y408492D01*
X629627Y408200D01*
X629710Y407867D01*
X629877Y407617D01*
X630127Y407450D01*
X630460Y407367D01*
X630752Y407450D01*
X631044Y407658D01*
X631210Y407908D01*
X631252Y408200D01*
X631169Y408533D01*
X630960Y408783D01*
X630585Y409033D01*
G01X620827Y395017D02*
X618327D01*
Y396058D01*
X618452Y396392D01*
X618619Y396600D01*
X618952Y396683D01*
X619285Y396600D01*
X619494Y396350D01*
X619619Y396058D01*
Y395017D01*
G01Y396058D02*
X620827Y396683D01*
G01Y398950D02*
X618327D01*
X618827Y398450D01*
G01X620827D02*
Y399450D01*
G01X618327Y402050D02*
X618410Y401717D01*
X618619Y401467D01*
X618869Y401300D01*
X619202Y401175D01*
X619577Y401133D01*
X619952Y401175D01*
X620285Y401300D01*
X620535Y401467D01*
X620744Y401717D01*
X620827Y402050D01*
X620744Y402383D01*
X620535Y402633D01*
X620285Y402800D01*
X619952Y402925D01*
X619577Y402967D01*
X619202Y402925D01*
X618869Y402800D01*
X618619Y402633D01*
X618410Y402383D01*
X618327Y402050D01*
G01Y405150D02*
X618410Y404817D01*
X618619Y404567D01*
X618869Y404400D01*
X619202Y404275D01*
X619577Y404233D01*
X619952Y404275D01*
X620285Y404400D01*
X620535Y404567D01*
X620744Y404817D01*
X620827Y405150D01*
X620744Y405483D01*
X620535Y405733D01*
X620285Y405900D01*
X619952Y406025D01*
X619577Y406067D01*
X619202Y406025D01*
X618869Y405900D01*
X618619Y405733D01*
X618410Y405483D01*
X618327Y405150D01*
G01X618000Y411567D02*
X615500D01*
Y412608D01*
X615625Y412942D01*
X615792Y413150D01*
X616125Y413233D01*
X616458Y413150D01*
X616667Y412900D01*
X616792Y412608D01*
Y411567D01*
G01Y412608D02*
X618000Y413233D01*
G01X617708Y414792D02*
X617917Y415083D01*
X618000Y415417D01*
X617917Y415750D01*
X617667Y416042D01*
X617292Y416250D01*
X616917Y416333D01*
X616458D01*
X616083Y416250D01*
X615750Y416042D01*
X615583Y415792D01*
X615500Y415500D01*
X615583Y415167D01*
X615750Y414917D01*
X616000Y414750D01*
X616333Y414667D01*
X616625Y414750D01*
X616917Y414958D01*
X617083Y415208D01*
X617125Y415500D01*
X617042Y415833D01*
X616833Y416083D01*
X616458Y416333D01*
G01X616958Y417808D02*
X616667Y418100D01*
X616500Y418350D01*
X616417Y418683D01*
X616500Y418975D01*
X616667Y419183D01*
X616917Y419350D01*
X617208Y419392D01*
X617458Y419350D01*
X617708Y419183D01*
X617917Y418933D01*
X618000Y418642D01*
X617917Y418308D01*
X617667Y418017D01*
X617292Y417850D01*
X616875Y417808D01*
X616333Y417892D01*
X616042Y418017D01*
X615750Y418225D01*
X615542Y418517D01*
X615500Y418808D01*
X615583Y419100D01*
X615792Y419308D01*
G01X615000Y384900D02*
X619000D01*
Y392300D01*
G01X626000Y411567D02*
X623500D01*
Y412608D01*
X623625Y412942D01*
X623792Y413150D01*
X624125Y413233D01*
X624458Y413150D01*
X624667Y412900D01*
X624792Y412608D01*
Y411567D01*
G01Y412608D02*
X626000Y413233D01*
G01X624958Y414708D02*
X624667Y415000D01*
X624500Y415250D01*
X624417Y415583D01*
X624500Y415875D01*
X624667Y416083D01*
X624917Y416250D01*
X625208Y416292D01*
X625458Y416250D01*
X625708Y416083D01*
X625917Y415833D01*
X626000Y415542D01*
X625917Y415208D01*
X625667Y414917D01*
X625292Y414750D01*
X624875Y414708D01*
X624333Y414792D01*
X624042Y414917D01*
X623750Y415125D01*
X623542Y415417D01*
X623500Y415708D01*
X623583Y416000D01*
X623792Y416208D01*
G01X623500Y418600D02*
X623583Y418267D01*
X623792Y418017D01*
X624042Y417850D01*
X624375Y417725D01*
X624750Y417683D01*
X625125Y417725D01*
X625458Y417850D01*
X625708Y418017D01*
X625917Y418267D01*
X626000Y418600D01*
X625917Y418933D01*
X625708Y419183D01*
X625458Y419350D01*
X625125Y419475D01*
X624750Y419517D01*
X624375Y419475D01*
X624042Y419350D01*
X623792Y419183D01*
X623583Y418933D01*
X623500Y418600D01*
G01X625500Y381900D02*
X629500D01*
Y389300D01*
G01X622000Y411517D02*
X619500D01*
Y412558D01*
X619625Y412892D01*
X619792Y413100D01*
X620125Y413183D01*
X620458Y413100D01*
X620667Y412850D01*
X620792Y412558D01*
Y411517D01*
G01Y412558D02*
X622000Y413183D01*
G01Y415450D02*
X619500D01*
X620000Y414950D01*
G01X622000D02*
Y415950D01*
G01X619500Y418550D02*
X619583Y418217D01*
X619792Y417967D01*
X620042Y417800D01*
X620375Y417675D01*
X620750Y417633D01*
X621125Y417675D01*
X621458Y417800D01*
X621708Y417967D01*
X621917Y418217D01*
X622000Y418550D01*
X621917Y418883D01*
X621708Y419133D01*
X621458Y419300D01*
X621125Y419425D01*
X620750Y419467D01*
X620375Y419425D01*
X620042Y419300D01*
X619792Y419133D01*
X619583Y418883D01*
X619500Y418550D01*
G01X622000Y421650D02*
X619500D01*
X620000Y421150D01*
G01X622000D02*
Y422150D01*
G01X621000Y384900D02*
X625000D01*
Y392300D01*
G01X611388Y816093D02*
X611263Y815843D01*
X611180Y815551D01*
Y815218D01*
X611305Y814843D01*
X611513Y814551D01*
X611763Y814343D01*
X612180Y814176D01*
X612555Y814134D01*
X612930Y814218D01*
X613180Y814343D01*
X613430Y814593D01*
X613597Y814884D01*
X613680Y815176D01*
Y815468D01*
X613597Y815759D01*
X613472Y816009D01*
X613305Y816218D01*
G01X611597Y817484D02*
X611347Y817734D01*
X611222Y818026D01*
X611180Y818359D01*
X611263Y818776D01*
X611472Y819068D01*
X611722Y819151D01*
X611972Y819109D01*
X612180Y818943D01*
X612597Y818109D01*
X612888Y817734D01*
X613305Y817484D01*
X613680Y817401D01*
Y819151D01*
G01X613305Y820459D02*
X613513Y820709D01*
X613638Y821001D01*
X613680Y821376D01*
X613597Y821751D01*
X613430Y822043D01*
X613138Y822251D01*
X612805Y822293D01*
X612472Y822209D01*
X612263Y822001D01*
X612097Y821709D01*
X612055Y821418D01*
X612097Y821126D01*
X612263Y820751D01*
X611180Y820876D01*
Y822001D01*
G01X613680Y824476D02*
X611180D01*
X611680Y823976D01*
G01X613680D02*
Y824976D01*
G01X607388Y816093D02*
X607263Y815843D01*
X607180Y815551D01*
Y815218D01*
X607305Y814843D01*
X607513Y814551D01*
X607763Y814343D01*
X608180Y814176D01*
X608555Y814134D01*
X608930Y814218D01*
X609180Y814343D01*
X609430Y814593D01*
X609597Y814884D01*
X609680Y815176D01*
Y815468D01*
X609597Y815759D01*
X609472Y816009D01*
X609305Y816218D01*
G01X607597Y817484D02*
X607347Y817734D01*
X607222Y818026D01*
X607180Y818359D01*
X607263Y818776D01*
X607472Y819068D01*
X607722Y819151D01*
X607972Y819109D01*
X608180Y818943D01*
X608597Y818109D01*
X608888Y817734D01*
X609305Y817484D01*
X609680Y817401D01*
Y819151D01*
G01X609305Y820459D02*
X609513Y820709D01*
X609638Y821001D01*
X609680Y821376D01*
X609597Y821751D01*
X609430Y822043D01*
X609138Y822251D01*
X608805Y822293D01*
X608472Y822209D01*
X608263Y822001D01*
X608097Y821709D01*
X608055Y821418D01*
X608097Y821126D01*
X608263Y820751D01*
X607180Y820876D01*
Y822001D01*
G01Y824476D02*
X607263Y824143D01*
X607472Y823893D01*
X607722Y823726D01*
X608055Y823601D01*
X608430Y823559D01*
X608805Y823601D01*
X609138Y823726D01*
X609388Y823893D01*
X609597Y824143D01*
X609680Y824476D01*
X609597Y824809D01*
X609388Y825059D01*
X609138Y825226D01*
X608805Y825351D01*
X608430Y825393D01*
X608055Y825351D01*
X607722Y825226D01*
X607472Y825059D01*
X607263Y824809D01*
X607180Y824476D01*
G01X623987Y816093D02*
X623862Y815843D01*
X623779Y815551D01*
Y815218D01*
X623904Y814843D01*
X624112Y814551D01*
X624362Y814343D01*
X624779Y814176D01*
X625154Y814134D01*
X625529Y814218D01*
X625779Y814343D01*
X626029Y814593D01*
X626196Y814884D01*
X626279Y815176D01*
Y815468D01*
X626196Y815759D01*
X626071Y816009D01*
X625904Y816218D01*
G01X626279Y818276D02*
X623779D01*
X624279Y817776D01*
G01X626279D02*
Y818776D01*
G01X625237Y820584D02*
X624946Y820876D01*
X624779Y821126D01*
X624696Y821459D01*
X624779Y821751D01*
X624946Y821959D01*
X625196Y822126D01*
X625487Y822168D01*
X625737Y822126D01*
X625987Y821959D01*
X626196Y821709D01*
X626279Y821418D01*
X626196Y821084D01*
X625946Y820793D01*
X625571Y820626D01*
X625154Y820584D01*
X624612Y820668D01*
X624321Y820793D01*
X624029Y821001D01*
X623821Y821293D01*
X623779Y821584D01*
X623862Y821876D01*
X624071Y822084D01*
G01X625987Y823768D02*
X626196Y824059D01*
X626279Y824393D01*
X626196Y824726D01*
X625946Y825018D01*
X625571Y825226D01*
X625196Y825309D01*
X624737D01*
X624362Y825226D01*
X624029Y825018D01*
X623862Y824768D01*
X623779Y824476D01*
X623862Y824143D01*
X624029Y823893D01*
X624279Y823726D01*
X624612Y823643D01*
X624904Y823726D01*
X625196Y823934D01*
X625362Y824184D01*
X625404Y824476D01*
X625321Y824809D01*
X625112Y825059D01*
X624737Y825309D01*
G01X619987Y816093D02*
X619862Y815843D01*
X619779Y815551D01*
Y815218D01*
X619904Y814843D01*
X620112Y814551D01*
X620362Y814343D01*
X620779Y814176D01*
X621154Y814134D01*
X621529Y814218D01*
X621779Y814343D01*
X622029Y814593D01*
X622196Y814884D01*
X622279Y815176D01*
Y815468D01*
X622196Y815759D01*
X622071Y816009D01*
X621904Y816218D01*
G01X622279Y818276D02*
X619779D01*
X620279Y817776D01*
G01X622279D02*
Y818776D01*
G01X621237Y820584D02*
X620946Y820876D01*
X620779Y821126D01*
X620696Y821459D01*
X620779Y821751D01*
X620946Y821959D01*
X621196Y822126D01*
X621487Y822168D01*
X621737Y822126D01*
X621987Y821959D01*
X622196Y821709D01*
X622279Y821418D01*
X622196Y821084D01*
X621946Y820793D01*
X621571Y820626D01*
X621154Y820584D01*
X620612Y820668D01*
X620321Y820793D01*
X620029Y821001D01*
X619821Y821293D01*
X619779Y821584D01*
X619862Y821876D01*
X620071Y822084D01*
G01X622279Y824476D02*
X622237Y824768D01*
X622112Y825101D01*
X621904Y825309D01*
X621612Y825393D01*
X621321Y825309D01*
X621071Y825059D01*
X620946Y824684D01*
Y824268D01*
X620862Y824018D01*
X620654Y823809D01*
X620362Y823726D01*
X620071Y823851D01*
X619862Y824143D01*
X619779Y824476D01*
X619862Y824809D01*
X620071Y825101D01*
X620362Y825226D01*
X620654Y825143D01*
X620862Y824934D01*
X620946Y824684D01*
Y824268D01*
X621071Y823893D01*
X621321Y823643D01*
X621612Y823559D01*
X621904Y823643D01*
X622112Y823851D01*
X622237Y824184D01*
X622279Y824476D01*
G01X636585Y816093D02*
X636460Y815843D01*
X636377Y815551D01*
Y815218D01*
X636502Y814843D01*
X636710Y814551D01*
X636960Y814343D01*
X637377Y814176D01*
X637752Y814134D01*
X638127Y814218D01*
X638377Y814343D01*
X638627Y814593D01*
X638794Y814884D01*
X638877Y815176D01*
Y815468D01*
X638794Y815759D01*
X638669Y816009D01*
X638502Y816218D01*
G01X638877Y818276D02*
X636377D01*
X636877Y817776D01*
G01X638877D02*
Y818776D01*
G01X637835Y820584D02*
X637544Y820876D01*
X637377Y821126D01*
X637294Y821459D01*
X637377Y821751D01*
X637544Y821959D01*
X637794Y822126D01*
X638085Y822168D01*
X638335Y822126D01*
X638585Y821959D01*
X638794Y821709D01*
X638877Y821418D01*
X638794Y821084D01*
X638544Y820793D01*
X638169Y820626D01*
X637752Y820584D01*
X637210Y820668D01*
X636919Y820793D01*
X636627Y821001D01*
X636419Y821293D01*
X636377Y821584D01*
X636460Y821876D01*
X636669Y822084D01*
G01X638502Y823559D02*
X638710Y823809D01*
X638835Y824101D01*
X638877Y824476D01*
X638794Y824851D01*
X638627Y825143D01*
X638335Y825351D01*
X638002Y825393D01*
X637669Y825309D01*
X637460Y825101D01*
X637294Y824809D01*
X637252Y824518D01*
X637294Y824226D01*
X637460Y823851D01*
X636377Y823976D01*
Y825101D01*
G01X632585Y816093D02*
X632460Y815843D01*
X632377Y815551D01*
Y815218D01*
X632502Y814843D01*
X632710Y814551D01*
X632960Y814343D01*
X633377Y814176D01*
X633752Y814134D01*
X634127Y814218D01*
X634377Y814343D01*
X634627Y814593D01*
X634794Y814884D01*
X634877Y815176D01*
Y815468D01*
X634794Y815759D01*
X634669Y816009D01*
X634502Y816218D01*
G01X634877Y818276D02*
X632377D01*
X632877Y817776D01*
G01X634877D02*
Y818776D01*
G01X633835Y820584D02*
X633544Y820876D01*
X633377Y821126D01*
X633294Y821459D01*
X633377Y821751D01*
X633544Y821959D01*
X633794Y822126D01*
X634085Y822168D01*
X634335Y822126D01*
X634585Y821959D01*
X634794Y821709D01*
X634877Y821418D01*
X634794Y821084D01*
X634544Y820793D01*
X634169Y820626D01*
X633752Y820584D01*
X633210Y820668D01*
X632919Y820793D01*
X632627Y821001D01*
X632419Y821293D01*
X632377Y821584D01*
X632460Y821876D01*
X632669Y822084D01*
G01X634877Y824976D02*
X632377D01*
X634169Y823434D01*
Y825518D01*
G01X660800Y110300D02*
Y115300D01*
X662800D01*
X663600Y115050D01*
X664200Y114717D01*
X664700Y114217D01*
X665100Y113633D01*
X665200Y112800D01*
X665100Y111967D01*
X664700Y111383D01*
X664200Y110883D01*
X663600Y110550D01*
X662800Y110300D01*
X660800D01*
G01X660542Y129267D02*
X660417Y129017D01*
X660334Y128725D01*
Y128392D01*
X660459Y128017D01*
X660667Y127725D01*
X660917Y127517D01*
X661334Y127350D01*
X661709Y127308D01*
X662084Y127392D01*
X662334Y127517D01*
X662584Y127767D01*
X662751Y128058D01*
X662834Y128350D01*
Y128642D01*
X662751Y128933D01*
X662626Y129183D01*
X662459Y129392D01*
G01X662334Y130533D02*
X662626Y130783D01*
X662792Y131117D01*
X662834Y131492D01*
X662792Y131825D01*
X662584Y132158D01*
X662334Y132367D01*
X662084Y132408D01*
X661792Y132325D01*
X661584Y132033D01*
X661501Y131742D01*
Y131367D01*
G01Y131742D02*
X661376Y131992D01*
X661167Y132200D01*
X660917Y132283D01*
X660667Y132200D01*
X660459Y131992D01*
X660334Y131617D01*
X660376Y131242D01*
X660542Y130867D01*
G01X662542Y133842D02*
X662751Y134133D01*
X662834Y134467D01*
X662751Y134800D01*
X662501Y135092D01*
X662126Y135300D01*
X661751Y135383D01*
X661292D01*
X660917Y135300D01*
X660584Y135092D01*
X660417Y134842D01*
X660334Y134550D01*
X660417Y134217D01*
X660584Y133967D01*
X660834Y133800D01*
X661167Y133717D01*
X661459Y133800D01*
X661751Y134008D01*
X661917Y134258D01*
X661959Y134550D01*
X661876Y134883D01*
X661667Y135133D01*
X661292Y135383D01*
G01X662834Y137567D02*
X662292Y137650D01*
X661834Y137775D01*
X661417Y137942D01*
X660959Y138150D01*
X660334Y138483D01*
Y136817D01*
G01X652708Y129267D02*
X652583Y129017D01*
X652500Y128725D01*
Y128392D01*
X652625Y128017D01*
X652833Y127725D01*
X653083Y127517D01*
X653500Y127350D01*
X653875Y127308D01*
X654250Y127392D01*
X654500Y127517D01*
X654750Y127767D01*
X654917Y128058D01*
X655000Y128350D01*
Y128642D01*
X654917Y128933D01*
X654792Y129183D01*
X654625Y129392D01*
G01X655000Y131950D02*
X652500D01*
X654292Y130408D01*
Y132492D01*
G01X652500Y134550D02*
X652583Y134217D01*
X652792Y133967D01*
X653042Y133800D01*
X653375Y133675D01*
X653750Y133633D01*
X654125Y133675D01*
X654458Y133800D01*
X654708Y133967D01*
X654917Y134217D01*
X655000Y134550D01*
X654917Y134883D01*
X654708Y135133D01*
X654458Y135300D01*
X654125Y135425D01*
X653750Y135467D01*
X653375Y135425D01*
X653042Y135300D01*
X652792Y135133D01*
X652583Y134883D01*
X652500Y134550D01*
G01X655000Y137650D02*
X652500D01*
X653000Y137150D01*
G01X655000D02*
Y138150D01*
G01X649208Y129267D02*
X649083Y129017D01*
X649000Y128725D01*
Y128392D01*
X649125Y128017D01*
X649333Y127725D01*
X649583Y127517D01*
X650000Y127350D01*
X650375Y127308D01*
X650750Y127392D01*
X651000Y127517D01*
X651250Y127767D01*
X651417Y128058D01*
X651500Y128350D01*
Y128642D01*
X651417Y128933D01*
X651292Y129183D01*
X651125Y129392D01*
G01X651500Y131950D02*
X649000D01*
X650792Y130408D01*
Y132492D01*
G01X649000Y134550D02*
X649083Y134217D01*
X649292Y133967D01*
X649542Y133800D01*
X649875Y133675D01*
X650250Y133633D01*
X650625Y133675D01*
X650958Y133800D01*
X651208Y133967D01*
X651417Y134217D01*
X651500Y134550D01*
X651417Y134883D01*
X651208Y135133D01*
X650958Y135300D01*
X650625Y135425D01*
X650250Y135467D01*
X649875Y135425D01*
X649542Y135300D01*
X649292Y135133D01*
X649083Y134883D01*
X649000Y134550D01*
G01Y137650D02*
X649083Y137317D01*
X649292Y137067D01*
X649542Y136900D01*
X649875Y136775D01*
X650250Y136733D01*
X650625Y136775D01*
X650958Y136900D01*
X651208Y137067D01*
X651417Y137317D01*
X651500Y137650D01*
X651417Y137983D01*
X651208Y138233D01*
X650958Y138400D01*
X650625Y138525D01*
X650250Y138567D01*
X649875Y138525D01*
X649542Y138400D01*
X649292Y138233D01*
X649083Y137983D01*
X649000Y137650D01*
G01X657042Y129267D02*
X656917Y129017D01*
X656834Y128725D01*
Y128392D01*
X656959Y128017D01*
X657167Y127725D01*
X657417Y127517D01*
X657834Y127350D01*
X658209Y127308D01*
X658584Y127392D01*
X658834Y127517D01*
X659084Y127767D01*
X659251Y128058D01*
X659334Y128350D01*
Y128642D01*
X659251Y128933D01*
X659126Y129183D01*
X658959Y129392D01*
G01X658834Y130533D02*
X659126Y130783D01*
X659292Y131117D01*
X659334Y131492D01*
X659292Y131825D01*
X659084Y132158D01*
X658834Y132367D01*
X658584Y132408D01*
X658292Y132325D01*
X658084Y132033D01*
X658001Y131742D01*
Y131367D01*
G01Y131742D02*
X657876Y131992D01*
X657667Y132200D01*
X657417Y132283D01*
X657167Y132200D01*
X656959Y131992D01*
X656834Y131617D01*
X656876Y131242D01*
X657042Y130867D01*
G01X659042Y133842D02*
X659251Y134133D01*
X659334Y134467D01*
X659251Y134800D01*
X659001Y135092D01*
X658626Y135300D01*
X658251Y135383D01*
X657792D01*
X657417Y135300D01*
X657084Y135092D01*
X656917Y134842D01*
X656834Y134550D01*
X656917Y134217D01*
X657084Y133967D01*
X657334Y133800D01*
X657667Y133717D01*
X657959Y133800D01*
X658251Y134008D01*
X658417Y134258D01*
X658459Y134550D01*
X658376Y134883D01*
X658167Y135133D01*
X657792Y135383D01*
G01X658292Y136858D02*
X658001Y137150D01*
X657834Y137400D01*
X657751Y137733D01*
X657834Y138025D01*
X658001Y138233D01*
X658251Y138400D01*
X658542Y138442D01*
X658792Y138400D01*
X659042Y138233D01*
X659251Y137983D01*
X659334Y137692D01*
X659251Y137358D01*
X659001Y137067D01*
X658626Y136900D01*
X658209Y136858D01*
X657667Y136942D01*
X657376Y137067D01*
X657084Y137275D01*
X656876Y137567D01*
X656834Y137858D01*
X656917Y138150D01*
X657126Y138358D01*
G01X650064Y122944D02*
X649814Y123069D01*
X649522Y123152D01*
X649189D01*
X648814Y123027D01*
X648522Y122819D01*
X648314Y122569D01*
X648147Y122152D01*
X648105Y121777D01*
X648189Y121402D01*
X648314Y121152D01*
X648564Y120902D01*
X648855Y120735D01*
X649147Y120652D01*
X649439D01*
X649730Y120735D01*
X649980Y120860D01*
X650189Y121027D01*
G01X651289Y120652D02*
Y123152D01*
X653205Y120652D01*
Y123152D01*
G01X655347Y120652D02*
Y123152D01*
X654847Y122652D01*
G01Y120652D02*
X655847D01*
G01X657530Y121027D02*
X657780Y120819D01*
X658072Y120694D01*
X658447Y120652D01*
X658822Y120735D01*
X659114Y120902D01*
X659322Y121194D01*
X659364Y121527D01*
X659280Y121860D01*
X659072Y122069D01*
X658780Y122235D01*
X658489Y122277D01*
X658197Y122235D01*
X657822Y122069D01*
X657947Y123152D01*
X659072D01*
G01X658017Y190167D02*
Y192667D01*
X659058D01*
X659392Y192542D01*
X659600Y192375D01*
X659683Y192042D01*
X659600Y191709D01*
X659350Y191500D01*
X659058Y191375D01*
X658017D01*
G01X659058D02*
X659683Y190167D01*
G01X661033Y190667D02*
X661283Y190375D01*
X661617Y190209D01*
X661992Y190167D01*
X662325Y190209D01*
X662658Y190417D01*
X662867Y190667D01*
X662908Y190917D01*
X662825Y191209D01*
X662533Y191417D01*
X662242Y191500D01*
X661867D01*
G01X662242D02*
X662492Y191625D01*
X662700Y191834D01*
X662783Y192084D01*
X662700Y192334D01*
X662492Y192542D01*
X662117Y192667D01*
X661742Y192625D01*
X661367Y192459D01*
G01X664258Y192250D02*
X664508Y192500D01*
X664800Y192625D01*
X665133Y192667D01*
X665550Y192584D01*
X665842Y192375D01*
X665925Y192125D01*
X665883Y191875D01*
X665717Y191667D01*
X664883Y191250D01*
X664508Y190959D01*
X664258Y190542D01*
X664175Y190167D01*
X665925D01*
G01X667358Y191209D02*
X667650Y191500D01*
X667900Y191667D01*
X668233Y191750D01*
X668525Y191667D01*
X668733Y191500D01*
X668900Y191250D01*
X668942Y190959D01*
X668900Y190709D01*
X668733Y190459D01*
X668483Y190250D01*
X668192Y190167D01*
X667858Y190250D01*
X667567Y190500D01*
X667400Y190875D01*
X667358Y191292D01*
X667442Y191834D01*
X667567Y192125D01*
X667775Y192417D01*
X668067Y192625D01*
X668358Y192667D01*
X668650Y192584D01*
X668858Y192375D01*
G01X664417Y179694D02*
X664375Y179361D01*
X664209Y179069D01*
X663959Y178819D01*
X663667Y178652D01*
X663334Y178569D01*
X663000D01*
X662667Y178652D01*
X662375Y178819D01*
X662125Y179069D01*
X661959Y179361D01*
X661917Y179694D01*
X661959Y180027D01*
X662125Y180319D01*
X662375Y180569D01*
X662667Y180736D01*
X663000Y180819D01*
X663334D01*
X663667Y180736D01*
X663959Y180569D01*
X664209Y180319D01*
X664375Y180027D01*
X664417Y179694D01*
G01X663750Y180027D02*
X664417Y180527D01*
G01X663917Y181877D02*
X664209Y182127D01*
X664375Y182461D01*
X664417Y182836D01*
X664375Y183169D01*
X664167Y183502D01*
X663917Y183711D01*
X663667Y183752D01*
X663375Y183669D01*
X663167Y183377D01*
X663084Y183086D01*
Y182711D01*
G01Y183086D02*
X662959Y183336D01*
X662750Y183544D01*
X662500Y183627D01*
X662250Y183544D01*
X662042Y183336D01*
X661917Y182961D01*
X661959Y182586D01*
X662125Y182211D01*
G01X664417Y186394D02*
X661917D01*
X663709Y184852D01*
Y186936D01*
G01X666381Y208192D02*
X653381D01*
G01D02*
Y194192D01*
G01D02*
X666381D01*
G01D02*
Y208192D01*
G01X680381D02*
X667381D01*
G01D02*
Y194192D01*
G01D02*
X680381D01*
G01X683763Y220408D02*
X665763D01*
G01D02*
Y231608D01*
G01X655963Y223725D02*
X653463D01*
Y224725D01*
X653588Y225058D01*
X653880Y225308D01*
X654213Y225391D01*
X654546Y225308D01*
X654796Y225100D01*
X654921Y224725D01*
Y223725D01*
G01X653671Y228575D02*
X653546Y228325D01*
X653463Y228033D01*
Y227700D01*
X653588Y227325D01*
X653796Y227033D01*
X654046Y226825D01*
X654463Y226658D01*
X654838Y226616D01*
X655213Y226700D01*
X655463Y226825D01*
X655713Y227075D01*
X655880Y227366D01*
X655963Y227658D01*
Y227950D01*
X655880Y228241D01*
X655755Y228491D01*
X655588Y228700D01*
G01X655671Y230050D02*
X655880Y230341D01*
X655963Y230675D01*
X655880Y231008D01*
X655630Y231300D01*
X655255Y231508D01*
X654880Y231591D01*
X654421D01*
X654046Y231508D01*
X653713Y231300D01*
X653546Y231050D01*
X653463Y230758D01*
X653546Y230425D01*
X653713Y230175D01*
X653963Y230008D01*
X654296Y229925D01*
X654588Y230008D01*
X654880Y230216D01*
X655046Y230466D01*
X655088Y230758D01*
X655005Y231091D01*
X654796Y231341D01*
X654421Y231591D01*
G01X655963Y234358D02*
X653463D01*
X655255Y232816D01*
Y234900D01*
G01X669200Y210000D02*
Y214000D01*
X661800D01*
G01X683763Y258808D02*
X665763D01*
G01D02*
Y247608D01*
G01X665837Y270692D02*
Y259492D01*
G01D02*
X683837D01*
G01X662834Y277967D02*
X660334D01*
Y278967D01*
X660459Y279300D01*
X660751Y279550D01*
X661084Y279633D01*
X661417Y279550D01*
X661667Y279342D01*
X661792Y278967D01*
Y277967D01*
G01X660334Y281900D02*
X662834D01*
G01X660334Y280942D02*
Y282858D01*
G01X660542Y285917D02*
X660417Y285667D01*
X660334Y285375D01*
Y285042D01*
X660459Y284667D01*
X660667Y284375D01*
X660917Y284167D01*
X661334Y284000D01*
X661709Y283958D01*
X662084Y284042D01*
X662334Y284167D01*
X662584Y284417D01*
X662751Y284708D01*
X662834Y285000D01*
Y285292D01*
X662751Y285583D01*
X662626Y285833D01*
X662459Y286042D01*
G01X662834Y288100D02*
X660334D01*
X660834Y287600D01*
G01X662834D02*
Y288600D01*
G01X660334Y291200D02*
X660417Y290867D01*
X660626Y290617D01*
X660876Y290450D01*
X661209Y290325D01*
X661584Y290283D01*
X661959Y290325D01*
X662292Y290450D01*
X662542Y290617D01*
X662751Y290867D01*
X662834Y291200D01*
X662751Y291533D01*
X662542Y291783D01*
X662292Y291950D01*
X661959Y292075D01*
X661584Y292117D01*
X661209Y292075D01*
X660876Y291950D01*
X660626Y291783D01*
X660417Y291533D01*
X660334Y291200D01*
G01X665837Y286692D02*
Y297892D01*
G01D02*
X683837D01*
G01X643433Y336500D02*
Y334708D01*
X643600Y334333D01*
X643933Y334083D01*
X644350Y334000D01*
X644767Y334083D01*
X645100Y334333D01*
X645267Y334708D01*
Y336500D01*
G01X647450Y334000D02*
Y336500D01*
X646950Y336000D01*
G01Y334000D02*
X647950D01*
G01X649842Y334292D02*
X650133Y334083D01*
X650467Y334000D01*
X650800Y334083D01*
X651092Y334333D01*
X651300Y334708D01*
X651383Y335083D01*
Y335542D01*
X651300Y335917D01*
X651092Y336250D01*
X650842Y336417D01*
X650550Y336500D01*
X650217Y336417D01*
X649967Y336250D01*
X649800Y336000D01*
X649717Y335667D01*
X649800Y335375D01*
X650008Y335083D01*
X650258Y334917D01*
X650550Y334875D01*
X650883Y334958D01*
X651133Y335167D01*
X651383Y335542D01*
G01X652858Y335042D02*
X653150Y335333D01*
X653400Y335500D01*
X653733Y335583D01*
X654025Y335500D01*
X654233Y335333D01*
X654400Y335083D01*
X654442Y334792D01*
X654400Y334542D01*
X654233Y334292D01*
X653983Y334083D01*
X653692Y334000D01*
X653358Y334083D01*
X653067Y334333D01*
X652900Y334708D01*
X652858Y335125D01*
X652942Y335667D01*
X653067Y335958D01*
X653275Y336250D01*
X653567Y336458D01*
X653858Y336500D01*
X654150Y336417D01*
X654358Y336208D01*
G01X637921Y344157D02*
Y342157D01*
G01X641850Y342750D02*
X646850D01*
Y347750D01*
G01X668067Y341500D02*
Y344000D01*
X669108D01*
X669442Y343875D01*
X669650Y343708D01*
X669733Y343375D01*
X669650Y343042D01*
X669400Y342833D01*
X669108Y342708D01*
X668067D01*
G01X669108D02*
X669733Y341500D01*
G01X671083Y341875D02*
X671333Y341667D01*
X671625Y341542D01*
X672000Y341500D01*
X672375Y341583D01*
X672667Y341750D01*
X672875Y342042D01*
X672917Y342375D01*
X672833Y342708D01*
X672625Y342917D01*
X672333Y343083D01*
X672042Y343125D01*
X671750Y343083D01*
X671375Y342917D01*
X671500Y344000D01*
X672625D01*
G01X674183Y341875D02*
X674433Y341667D01*
X674725Y341542D01*
X675100Y341500D01*
X675475Y341583D01*
X675767Y341750D01*
X675975Y342042D01*
X676017Y342375D01*
X675933Y342708D01*
X675725Y342917D01*
X675433Y343083D01*
X675142Y343125D01*
X674850Y343083D01*
X674475Y342917D01*
X674600Y344000D01*
X675725D01*
G01X650300Y342100D02*
Y338100D01*
X657700D01*
G01X657800Y342100D02*
Y338100D01*
X665200D01*
G01X642000Y339300D02*
X638000D01*
Y331900D01*
G01X650300Y346600D02*
Y342600D01*
X657700D01*
G01X645443Y355616D02*
X648443D01*
G01X639890Y369043D02*
Y371043D01*
G01X646850Y365450D02*
Y370450D01*
X641850D01*
G01X668067Y357000D02*
Y359500D01*
X669108D01*
X669442Y359375D01*
X669650Y359208D01*
X669733Y358875D01*
X669650Y358542D01*
X669400Y358333D01*
X669108Y358208D01*
X668067D01*
G01X669108D02*
X669733Y357000D01*
G01X671292Y357292D02*
X671583Y357083D01*
X671917Y357000D01*
X672250Y357083D01*
X672542Y357333D01*
X672750Y357708D01*
X672833Y358083D01*
Y358542D01*
X672750Y358917D01*
X672542Y359250D01*
X672292Y359417D01*
X672000Y359500D01*
X671667Y359417D01*
X671417Y359250D01*
X671250Y359000D01*
X671167Y358667D01*
X671250Y358375D01*
X671458Y358083D01*
X671708Y357917D01*
X672000Y357875D01*
X672333Y357958D01*
X672583Y358167D01*
X672833Y358542D01*
G01X674308Y359083D02*
X674558Y359333D01*
X674850Y359458D01*
X675183Y359500D01*
X675600Y359417D01*
X675892Y359208D01*
X675975Y358958D01*
X675933Y358708D01*
X675767Y358500D01*
X674933Y358083D01*
X674558Y357792D01*
X674308Y357375D01*
X674225Y357000D01*
X675975D01*
G01X668067Y369000D02*
Y371500D01*
X669108D01*
X669442Y371375D01*
X669650Y371208D01*
X669733Y370875D01*
X669650Y370542D01*
X669400Y370333D01*
X669108Y370208D01*
X668067D01*
G01X669108D02*
X669733Y369000D01*
G01X672000D02*
X672292Y369042D01*
X672625Y369167D01*
X672833Y369375D01*
X672917Y369667D01*
X672833Y369958D01*
X672583Y370208D01*
X672208Y370333D01*
X671792D01*
X671542Y370417D01*
X671333Y370625D01*
X671250Y370917D01*
X671375Y371208D01*
X671667Y371417D01*
X672000Y371500D01*
X672333Y371417D01*
X672625Y371208D01*
X672750Y370917D01*
X672667Y370625D01*
X672458Y370417D01*
X672208Y370333D01*
X671792D01*
X671417Y370208D01*
X671167Y369958D01*
X671083Y369667D01*
X671167Y369375D01*
X671375Y369167D01*
X671708Y369042D01*
X672000Y369000D01*
G01X675100D02*
X675392Y369042D01*
X675725Y369167D01*
X675933Y369375D01*
X676017Y369667D01*
X675933Y369958D01*
X675683Y370208D01*
X675308Y370333D01*
X674892D01*
X674642Y370417D01*
X674433Y370625D01*
X674350Y370917D01*
X674475Y371208D01*
X674767Y371417D01*
X675100Y371500D01*
X675433Y371417D01*
X675725Y371208D01*
X675850Y370917D01*
X675767Y370625D01*
X675558Y370417D01*
X675308Y370333D01*
X674892D01*
X674517Y370208D01*
X674267Y369958D01*
X674183Y369667D01*
X674267Y369375D01*
X674475Y369167D01*
X674808Y369042D01*
X675100Y369000D01*
G01X650300Y374100D02*
Y370100D01*
X657700D01*
G01X668067Y345000D02*
Y347500D01*
X669108D01*
X669442Y347375D01*
X669650Y347208D01*
X669733Y346875D01*
X669650Y346542D01*
X669400Y346333D01*
X669108Y346208D01*
X668067D01*
G01X669108D02*
X669733Y345000D01*
G01X672000D02*
X672292Y345042D01*
X672625Y345167D01*
X672833Y345375D01*
X672917Y345667D01*
X672833Y345958D01*
X672583Y346208D01*
X672208Y346333D01*
X671792D01*
X671542Y346417D01*
X671333Y346625D01*
X671250Y346917D01*
X671375Y347208D01*
X671667Y347417D01*
X672000Y347500D01*
X672333Y347417D01*
X672625Y347208D01*
X672750Y346917D01*
X672667Y346625D01*
X672458Y346417D01*
X672208Y346333D01*
X671792D01*
X671417Y346208D01*
X671167Y345958D01*
X671083Y345667D01*
X671167Y345375D01*
X671375Y345167D01*
X671708Y345042D01*
X672000Y345000D01*
G01X675017D02*
X675100Y345542D01*
X675225Y346000D01*
X675392Y346417D01*
X675600Y346875D01*
X675933Y347500D01*
X674267D01*
G01X668067Y373000D02*
Y375500D01*
X669108D01*
X669442Y375375D01*
X669650Y375208D01*
X669733Y374875D01*
X669650Y374542D01*
X669400Y374333D01*
X669108Y374208D01*
X668067D01*
G01X669108D02*
X669733Y373000D01*
G01X671208Y374042D02*
X671500Y374333D01*
X671750Y374500D01*
X672083Y374583D01*
X672375Y374500D01*
X672583Y374333D01*
X672750Y374083D01*
X672792Y373792D01*
X672750Y373542D01*
X672583Y373292D01*
X672333Y373083D01*
X672042Y373000D01*
X671708Y373083D01*
X671417Y373333D01*
X671250Y373708D01*
X671208Y374125D01*
X671292Y374667D01*
X671417Y374958D01*
X671625Y375250D01*
X671917Y375458D01*
X672208Y375500D01*
X672500Y375417D01*
X672708Y375208D01*
G01X674308Y375083D02*
X674558Y375333D01*
X674850Y375458D01*
X675183Y375500D01*
X675600Y375417D01*
X675892Y375208D01*
X675975Y374958D01*
X675933Y374708D01*
X675767Y374500D01*
X674933Y374083D01*
X674558Y373792D01*
X674308Y373375D01*
X674225Y373000D01*
X675975D01*
G01X650300Y378600D02*
Y374600D01*
X657700D01*
G01X657800Y378600D02*
Y374600D01*
X665200D01*
G01X638500Y373900D02*
X642500D01*
Y381300D01*
G01X667967Y365000D02*
Y367500D01*
X669008D01*
X669342Y367375D01*
X669550Y367208D01*
X669633Y366875D01*
X669550Y366542D01*
X669300Y366333D01*
X669008Y366208D01*
X667967D01*
G01X669008D02*
X669633Y365000D01*
G01X670983Y365500D02*
X671233Y365208D01*
X671567Y365042D01*
X671942Y365000D01*
X672275Y365042D01*
X672608Y365250D01*
X672817Y365500D01*
X672858Y365750D01*
X672775Y366042D01*
X672483Y366250D01*
X672192Y366333D01*
X671817D01*
G01X672192D02*
X672442Y366458D01*
X672650Y366667D01*
X672733Y366917D01*
X672650Y367167D01*
X672442Y367375D01*
X672067Y367500D01*
X671692Y367458D01*
X671317Y367292D01*
G01X675000Y365000D02*
Y367500D01*
X674500Y367000D01*
G01Y365000D02*
X675500D01*
G01X678100Y367500D02*
X677767Y367417D01*
X677517Y367208D01*
X677350Y366958D01*
X677225Y366625D01*
X677183Y366250D01*
X677225Y365875D01*
X677350Y365542D01*
X677517Y365292D01*
X677767Y365083D01*
X678100Y365000D01*
X678433Y365083D01*
X678683Y365292D01*
X678850Y365542D01*
X678975Y365875D01*
X679017Y366250D01*
X678975Y366625D01*
X678850Y366958D01*
X678683Y367208D01*
X678433Y367417D01*
X678100Y367500D01*
G01X681117Y365000D02*
X681200Y365542D01*
X681325Y366000D01*
X681492Y366417D01*
X681700Y366875D01*
X682033Y367500D01*
X680367D01*
G01X650300Y369100D02*
Y365100D01*
X657700D01*
G01X667967Y361000D02*
Y363500D01*
X669008D01*
X669342Y363375D01*
X669550Y363208D01*
X669633Y362875D01*
X669550Y362542D01*
X669300Y362333D01*
X669008Y362208D01*
X667967D01*
G01X669008D02*
X669633Y361000D01*
G01X670983Y361500D02*
X671233Y361208D01*
X671567Y361042D01*
X671942Y361000D01*
X672275Y361042D01*
X672608Y361250D01*
X672817Y361500D01*
X672858Y361750D01*
X672775Y362042D01*
X672483Y362250D01*
X672192Y362333D01*
X671817D01*
G01X672192D02*
X672442Y362458D01*
X672650Y362667D01*
X672733Y362917D01*
X672650Y363167D01*
X672442Y363375D01*
X672067Y363500D01*
X671692Y363458D01*
X671317Y363292D01*
G01X675000Y361000D02*
Y363500D01*
X674500Y363000D01*
G01Y361000D02*
X675500D01*
G01X678100Y363500D02*
X677767Y363417D01*
X677517Y363208D01*
X677350Y362958D01*
X677225Y362625D01*
X677183Y362250D01*
X677225Y361875D01*
X677350Y361542D01*
X677517Y361292D01*
X677767Y361083D01*
X678100Y361000D01*
X678433Y361083D01*
X678683Y361292D01*
X678850Y361542D01*
X678975Y361875D01*
X679017Y362250D01*
X678975Y362625D01*
X678850Y362958D01*
X678683Y363208D01*
X678433Y363417D01*
X678100Y363500D01*
G01X680408Y362042D02*
X680700Y362333D01*
X680950Y362500D01*
X681283Y362583D01*
X681575Y362500D01*
X681783Y362333D01*
X681950Y362083D01*
X681992Y361792D01*
X681950Y361542D01*
X681783Y361292D01*
X681533Y361083D01*
X681242Y361000D01*
X680908Y361083D01*
X680617Y361333D01*
X680450Y361708D01*
X680408Y362125D01*
X680492Y362667D01*
X680617Y362958D01*
X680825Y363250D01*
X681117Y363458D01*
X681408Y363500D01*
X681700Y363417D01*
X681908Y363208D01*
G01X650300Y364100D02*
Y360100D01*
X657700D01*
G01X667967Y353000D02*
Y355500D01*
X669008D01*
X669342Y355375D01*
X669550Y355208D01*
X669633Y354875D01*
X669550Y354542D01*
X669300Y354333D01*
X669008Y354208D01*
X667967D01*
G01X669008D02*
X669633Y353000D01*
G01X670983Y353500D02*
X671233Y353208D01*
X671567Y353042D01*
X671942Y353000D01*
X672275Y353042D01*
X672608Y353250D01*
X672817Y353500D01*
X672858Y353750D01*
X672775Y354042D01*
X672483Y354250D01*
X672192Y354333D01*
X671817D01*
G01X672192D02*
X672442Y354458D01*
X672650Y354667D01*
X672733Y354917D01*
X672650Y355167D01*
X672442Y355375D01*
X672067Y355500D01*
X671692Y355458D01*
X671317Y355292D01*
G01X675000Y353000D02*
Y355500D01*
X674500Y355000D01*
G01Y353000D02*
X675500D01*
G01X678100Y355500D02*
X677767Y355417D01*
X677517Y355208D01*
X677350Y354958D01*
X677225Y354625D01*
X677183Y354250D01*
X677225Y353875D01*
X677350Y353542D01*
X677517Y353292D01*
X677767Y353083D01*
X678100Y353000D01*
X678433Y353083D01*
X678683Y353292D01*
X678850Y353542D01*
X678975Y353875D01*
X679017Y354250D01*
X678975Y354625D01*
X678850Y354958D01*
X678683Y355208D01*
X678433Y355417D01*
X678100Y355500D01*
G01X680283Y353375D02*
X680533Y353167D01*
X680825Y353042D01*
X681200Y353000D01*
X681575Y353083D01*
X681867Y353250D01*
X682075Y353542D01*
X682117Y353875D01*
X682033Y354208D01*
X681825Y354417D01*
X681533Y354583D01*
X681242Y354625D01*
X680950Y354583D01*
X680575Y354417D01*
X680700Y355500D01*
X681825D01*
G01X650300Y354600D02*
Y350600D01*
X657700D01*
G01X667967Y349000D02*
Y351500D01*
X669008D01*
X669342Y351375D01*
X669550Y351208D01*
X669633Y350875D01*
X669550Y350542D01*
X669300Y350333D01*
X669008Y350208D01*
X667967D01*
G01X669008D02*
X669633Y349000D01*
G01X670983Y349500D02*
X671233Y349208D01*
X671567Y349042D01*
X671942Y349000D01*
X672275Y349042D01*
X672608Y349250D01*
X672817Y349500D01*
X672858Y349750D01*
X672775Y350042D01*
X672483Y350250D01*
X672192Y350333D01*
X671817D01*
G01X672192D02*
X672442Y350458D01*
X672650Y350667D01*
X672733Y350917D01*
X672650Y351167D01*
X672442Y351375D01*
X672067Y351500D01*
X671692Y351458D01*
X671317Y351292D01*
G01X675000Y349000D02*
Y351500D01*
X674500Y351000D01*
G01Y349000D02*
X675500D01*
G01X678100Y351500D02*
X677767Y351417D01*
X677517Y351208D01*
X677350Y350958D01*
X677225Y350625D01*
X677183Y350250D01*
X677225Y349875D01*
X677350Y349542D01*
X677517Y349292D01*
X677767Y349083D01*
X678100Y349000D01*
X678433Y349083D01*
X678683Y349292D01*
X678850Y349542D01*
X678975Y349875D01*
X679017Y350250D01*
X678975Y350625D01*
X678850Y350958D01*
X678683Y351208D01*
X678433Y351417D01*
X678100Y351500D01*
G01X681700Y349000D02*
Y351500D01*
X680158Y349708D01*
X682242D01*
G01X650300Y350600D02*
Y346600D01*
X657700D01*
G01X642621Y386628D02*
X640121D01*
Y387669D01*
X640246Y388003D01*
X640413Y388211D01*
X640746Y388294D01*
X641079Y388211D01*
X641288Y387961D01*
X641413Y387669D01*
Y386628D01*
G01Y387669D02*
X642621Y388294D01*
G01X642121Y389644D02*
X642413Y389894D01*
X642579Y390228D01*
X642621Y390603D01*
X642579Y390936D01*
X642371Y391269D01*
X642121Y391478D01*
X641871Y391519D01*
X641579Y391436D01*
X641371Y391144D01*
X641288Y390853D01*
Y390478D01*
G01Y390853D02*
X641163Y391103D01*
X640954Y391311D01*
X640704Y391394D01*
X640454Y391311D01*
X640246Y391103D01*
X640121Y390728D01*
X640163Y390353D01*
X640329Y389978D01*
G01X642621Y393661D02*
X640121D01*
X640621Y393161D01*
G01X642621D02*
Y394161D01*
G01X640121Y396761D02*
X640204Y396428D01*
X640413Y396178D01*
X640663Y396011D01*
X640996Y395886D01*
X641371Y395844D01*
X641746Y395886D01*
X642079Y396011D01*
X642329Y396178D01*
X642538Y396428D01*
X642621Y396761D01*
X642538Y397094D01*
X642329Y397344D01*
X642079Y397511D01*
X641746Y397636D01*
X641371Y397678D01*
X640996Y397636D01*
X640663Y397511D01*
X640413Y397344D01*
X640204Y397094D01*
X640121Y396761D01*
G01X642621Y399861D02*
X642579Y400153D01*
X642454Y400486D01*
X642246Y400694D01*
X641954Y400778D01*
X641663Y400694D01*
X641413Y400444D01*
X641288Y400069D01*
Y399653D01*
X641204Y399403D01*
X640996Y399194D01*
X640704Y399111D01*
X640413Y399236D01*
X640204Y399528D01*
X640121Y399861D01*
X640204Y400194D01*
X640413Y400486D01*
X640704Y400611D01*
X640996Y400528D01*
X641204Y400319D01*
X641288Y400069D01*
Y399653D01*
X641413Y399278D01*
X641663Y399028D01*
X641954Y398944D01*
X642246Y399028D01*
X642454Y399236D01*
X642579Y399569D01*
X642621Y399861D01*
G01X659604Y640467D02*
X660271Y640967D01*
X660771Y641800D01*
X661104Y642967D01*
X660771Y643967D01*
X660104Y644634D01*
X658938Y645134D01*
X654438D01*
Y635134D01*
X659938D01*
X661104Y635801D01*
X661771Y636801D01*
X662104Y637967D01*
X661771Y639134D01*
X660771Y640134D01*
X659604Y640467D01*
X654438D01*
G01X670871Y635134D02*
Y645134D01*
X664704Y637967D01*
X673038D01*
G01X679471Y635134D02*
X680638Y635301D01*
X681971Y635801D01*
X682804Y636634D01*
X683138Y637801D01*
X682804Y638967D01*
X681804Y639967D01*
X680304Y640467D01*
X678638D01*
X677638Y640801D01*
X676804Y641634D01*
X676471Y642801D01*
X676971Y643967D01*
X678137Y644801D01*
X679471Y645134D01*
X680804Y644801D01*
X681971Y643967D01*
X682471Y642801D01*
X682138Y641634D01*
X681304Y640801D01*
X680304Y640467D01*
X678638D01*
X677138Y639967D01*
X676138Y638967D01*
X675804Y637801D01*
X676138Y636634D01*
X676971Y635801D01*
X678304Y635301D01*
X679471Y635134D01*
G01X690071Y634801D02*
X689738Y634967D01*
Y635301D01*
X690071Y635467D01*
X690404Y635301D01*
Y634967D01*
X690071Y634801D01*
G01X700671Y645134D02*
X699337Y644801D01*
X698338Y643967D01*
X697671Y642967D01*
X697171Y641634D01*
X697004Y640134D01*
X697171Y638634D01*
X697671Y637301D01*
X698338Y636300D01*
X699337Y635467D01*
X700671Y635134D01*
X702004Y635467D01*
X703004Y636300D01*
X703671Y637301D01*
X704171Y638634D01*
X704338Y640134D01*
X704171Y641634D01*
X703671Y642967D01*
X703004Y643967D01*
X702004Y644801D01*
X700671Y645134D01*
G01X711271D02*
X709937Y644801D01*
X708938Y643967D01*
X708271Y642967D01*
X707771Y641634D01*
X707604Y640134D01*
X707771Y638634D01*
X708271Y637301D01*
X708938Y636300D01*
X709937Y635467D01*
X711271Y635134D01*
X712604Y635467D01*
X713604Y636300D01*
X714271Y637301D01*
X714771Y638634D01*
X714938Y640134D01*
X714771Y641634D01*
X714271Y642967D01*
X713604Y643967D01*
X712604Y644801D01*
X711271Y645134D01*
G01X721871Y635134D02*
X720537Y635301D01*
X719371Y635967D01*
X718371Y636967D01*
X717704Y638134D01*
X717371Y639467D01*
Y640801D01*
X717704Y642134D01*
X718371Y643301D01*
X719371Y644301D01*
X720537Y644967D01*
X721871Y645134D01*
X723204Y644967D01*
X724371Y644301D01*
X725371Y643301D01*
X726038Y642134D01*
X726371Y640801D01*
Y639467D01*
X726038Y638134D01*
X725371Y636967D01*
X724371Y635967D01*
X723204Y635301D01*
X721871Y635134D01*
G01X723204Y637801D02*
X725204Y635134D01*
G01X732471Y645134D02*
X731137Y644801D01*
X730138Y643967D01*
X729471Y642967D01*
X728971Y641634D01*
X728804Y640134D01*
X728971Y638634D01*
X729471Y637301D01*
X730138Y636300D01*
X731137Y635467D01*
X732471Y635134D01*
X733804Y635467D01*
X734804Y636300D01*
X735471Y637301D01*
X735971Y638634D01*
X736138Y640134D01*
X735971Y641634D01*
X735471Y642967D01*
X734804Y643967D01*
X733804Y644801D01*
X732471Y645134D01*
G01X739404Y637134D02*
X740404Y635967D01*
X741737Y635301D01*
X743238Y635134D01*
X744571Y635301D01*
X745904Y636134D01*
X746738Y637134D01*
X746904Y638134D01*
X746571Y639300D01*
X745404Y640134D01*
X744238Y640467D01*
X742738D01*
G01X744238D02*
X745238Y640967D01*
X746071Y641800D01*
X746404Y642801D01*
X746071Y643801D01*
X745238Y644634D01*
X743738Y645134D01*
X742238Y644967D01*
X740738Y644301D01*
G01X753671Y634801D02*
X753338Y634967D01*
Y635301D01*
X753671Y635467D01*
X754004Y635301D01*
Y634967D01*
X753671Y634801D01*
G01X764271Y645134D02*
X762937Y644801D01*
X761938Y643967D01*
X761271Y642967D01*
X760771Y641634D01*
X760604Y640134D01*
X760771Y638634D01*
X761271Y637301D01*
X761938Y636300D01*
X762937Y635467D01*
X764271Y635134D01*
X765604Y635467D01*
X766604Y636300D01*
X767271Y637301D01*
X767771Y638634D01*
X767938Y640134D01*
X767771Y641634D01*
X767271Y642967D01*
X766604Y643967D01*
X765604Y644801D01*
X764271Y645134D01*
G01X774871D02*
X773537Y644801D01*
X772538Y643967D01*
X771871Y642967D01*
X771371Y641634D01*
X771204Y640134D01*
X771371Y638634D01*
X771871Y637301D01*
X772538Y636300D01*
X773537Y635467D01*
X774871Y635134D01*
X776204Y635467D01*
X777204Y636300D01*
X777871Y637301D01*
X778371Y638634D01*
X778538Y640134D01*
X778371Y641634D01*
X777871Y642967D01*
X777204Y643967D01*
X776204Y644801D01*
X774871Y645134D01*
G01X785471Y635134D02*
Y645134D01*
X783471Y643134D01*
G01Y635134D02*
X787471D01*
G01X796071D02*
Y645134D01*
X794071Y643134D01*
G01Y635134D02*
X798071D01*
G01X654838Y618634D02*
Y628634D01*
X659171Y620301D01*
X663504Y628634D01*
Y618634D01*
G01X665604D02*
X669771Y628634D01*
X673938Y618634D01*
G01X672438Y622134D02*
X667104D01*
G01X676704Y618634D02*
Y628634D01*
X680038D01*
X681371Y628134D01*
X682371Y627467D01*
X683204Y626467D01*
X683871Y625300D01*
X684038Y623634D01*
X683871Y621967D01*
X683204Y620801D01*
X682371Y619800D01*
X681371Y619134D01*
X680038Y618634D01*
X676704D01*
G01X694304D02*
X687638D01*
Y628634D01*
X694304D01*
G01X691638Y623801D02*
X687638D01*
G01X710171Y628634D02*
X714171D01*
G01X712171D02*
Y618634D01*
G01X710171D02*
X714171D01*
G01X718938D02*
Y628634D01*
X726604Y618634D01*
Y628634D01*
G01X743971D02*
Y618634D01*
G01X740138Y628634D02*
X747804D01*
G01X750404Y618634D02*
X754571Y628634D01*
X758738Y618634D01*
G01X757238Y622134D02*
X751904D01*
G01X763171Y628634D02*
X767171D01*
G01X765171D02*
Y618634D01*
G01X763171D02*
X767171D01*
G01X770771Y628634D02*
X773104Y618634D01*
X775771Y628634D01*
X778438Y618634D01*
X780771Y628634D01*
G01X782204Y618634D02*
X786371Y628634D01*
X790538Y618634D01*
G01X789038Y622134D02*
X783704D01*
G01X793138Y618634D02*
Y628634D01*
X800804Y618634D01*
Y628634D01*
G01X658471Y652434D02*
Y662434D01*
X656471Y660434D01*
G01Y652434D02*
X660471D01*
G01X665404Y653934D02*
X666404Y653101D01*
X667571Y652601D01*
X669071Y652434D01*
X670571Y652767D01*
X671738Y653434D01*
X672571Y654601D01*
X672738Y655934D01*
X672404Y657267D01*
X671571Y658101D01*
X670404Y658767D01*
X669238Y658934D01*
X668071Y658767D01*
X666571Y658101D01*
X667071Y662434D01*
X671571D01*
G01X679671Y652434D02*
Y662434D01*
X677671Y660434D01*
G01Y652434D02*
X681671D01*
G01X690271Y662434D02*
X688937Y662101D01*
X687938Y661267D01*
X687271Y660267D01*
X686771Y658934D01*
X686604Y657434D01*
X686771Y655934D01*
X687271Y654601D01*
X687938Y653600D01*
X688937Y652767D01*
X690271Y652434D01*
X691604Y652767D01*
X692604Y653600D01*
X693271Y654601D01*
X693771Y655934D01*
X693938Y657434D01*
X693771Y658934D01*
X693271Y660267D01*
X692604Y661267D01*
X691604Y662101D01*
X690271Y662434D01*
G01X697204Y653934D02*
X698204Y653101D01*
X699371Y652601D01*
X700871Y652434D01*
X702371Y652767D01*
X703538Y653434D01*
X704371Y654601D01*
X704538Y655934D01*
X704204Y657267D01*
X703371Y658101D01*
X702204Y658767D01*
X701038Y658934D01*
X699871Y658767D01*
X698371Y658101D01*
X698871Y662434D01*
X703371D01*
G01X709304Y655767D02*
X713638D01*
G01X722071Y652434D02*
Y662434D01*
X720071Y660434D01*
G01Y652434D02*
X724071D01*
G01X656710Y678724D02*
Y668724D01*
X663376D01*
G01X670643Y675390D02*
Y668724D01*
G01Y678057D02*
X670310Y678224D01*
Y678557D01*
X670643Y678724D01*
X670976Y678557D01*
Y678224D01*
X670643Y678057D01*
G01X678910Y666224D02*
X680076Y665557D01*
X681410Y665391D01*
X682576Y665557D01*
X683576Y666391D01*
X684243Y667557D01*
Y675390D01*
G01Y674057D02*
X683576Y674724D01*
X682576Y675224D01*
X681410Y675390D01*
X680076Y675057D01*
X679243Y674391D01*
X678576Y673224D01*
X678243Y672057D01*
X678410Y671057D01*
X679076Y669890D01*
X680076Y669057D01*
X681410Y668724D01*
X682410Y668891D01*
X683576Y669557D01*
X684243Y670224D01*
G01X689010Y668724D02*
Y678724D01*
G01Y673891D02*
X689843Y674724D01*
X690676Y675224D01*
X692010Y675390D01*
X693010Y675224D01*
X694176Y674557D01*
X694676Y673557D01*
Y668724D01*
G01X702443Y678724D02*
Y668724D01*
G01X700110Y675390D02*
X704776D01*
G01X710210Y668724D02*
Y675390D01*
G01Y673724D02*
X710876Y674557D01*
X711876Y675224D01*
X713210Y675390D01*
X714376Y675224D01*
X715376Y674557D01*
X715876Y673391D01*
Y668724D01*
G01X723643Y675390D02*
Y668724D01*
G01Y678057D02*
X723310Y678224D01*
Y678557D01*
X723643Y678724D01*
X723976Y678557D01*
Y678224D01*
X723643Y678057D01*
G01X731410Y668724D02*
Y675390D01*
G01Y673724D02*
X732076Y674557D01*
X733076Y675224D01*
X734410Y675390D01*
X735576Y675224D01*
X736576Y674557D01*
X737076Y673391D01*
Y668724D01*
G01X742510Y666224D02*
X743676Y665557D01*
X745010Y665391D01*
X746176Y665557D01*
X747176Y666391D01*
X747843Y667557D01*
Y675390D01*
G01Y674057D02*
X747176Y674724D01*
X746176Y675224D01*
X745010Y675390D01*
X743676Y675057D01*
X742843Y674391D01*
X742176Y673224D01*
X741843Y672057D01*
X742010Y671057D01*
X742676Y669890D01*
X743676Y669057D01*
X745010Y668724D01*
X746010Y668891D01*
X747176Y669557D01*
X747843Y670224D01*
G01X762710Y668724D02*
Y678724D01*
X766710D01*
X768043Y678224D01*
X769043Y677057D01*
X769376Y675724D01*
X769043Y674391D01*
X768210Y673391D01*
X766710Y672890D01*
X762710D01*
G01X779976Y668724D02*
X773310D01*
Y678724D01*
X779976D01*
G01X777310Y673891D02*
X773310D01*
G01X788576Y674057D02*
X789243Y674557D01*
X789743Y675390D01*
X790076Y676557D01*
X789743Y677557D01*
X789076Y678224D01*
X787910Y678724D01*
X783410D01*
Y668724D01*
X788910D01*
X790076Y669391D01*
X790743Y670391D01*
X791076Y671557D01*
X790743Y672724D01*
X789743Y673724D01*
X788576Y674057D01*
X783410D01*
G01X805110Y668724D02*
Y678724D01*
X809110D01*
X810443Y678224D01*
X811443Y677057D01*
X811776Y675724D01*
X811443Y674391D01*
X810610Y673391D01*
X809110Y672890D01*
X805110D01*
G01X814710Y668724D02*
Y678724D01*
X819043Y670391D01*
X823376Y678724D01*
Y668724D01*
G01X833310Y677891D02*
X832310Y678391D01*
X831143Y678724D01*
X829810D01*
X828309Y678224D01*
X827143Y677391D01*
X826310Y676391D01*
X825643Y674724D01*
X825476Y673224D01*
X825810Y671724D01*
X826310Y670724D01*
X827310Y669724D01*
X828476Y669057D01*
X829643Y668724D01*
X830810D01*
X831976Y669057D01*
X832976Y669557D01*
X833810Y670224D01*
G01X847510Y668724D02*
Y678724D01*
X851510D01*
X852843Y678224D01*
X853843Y677057D01*
X854176Y675724D01*
X853843Y674391D01*
X853010Y673391D01*
X851510Y672890D01*
X847510D01*
G01X857276Y678724D02*
X861443Y668724D01*
X865610Y678724D01*
G01X872043D02*
Y668724D01*
G01X868210Y678724D02*
X875876D01*
G01X661312Y814510D02*
X661187Y814260D01*
X661104Y813968D01*
Y813635D01*
X661229Y813260D01*
X661437Y812968D01*
X661687Y812760D01*
X662104Y812593D01*
X662479Y812551D01*
X662854Y812635D01*
X663104Y812760D01*
X663354Y813010D01*
X663521Y813301D01*
X663604Y813593D01*
Y813885D01*
X663521Y814176D01*
X663396Y814426D01*
X663229Y814635D01*
G01X663604Y816693D02*
X661104D01*
X661604Y816193D01*
G01X663604D02*
Y817193D01*
G01X662562Y819001D02*
X662271Y819293D01*
X662104Y819543D01*
X662021Y819876D01*
X662104Y820168D01*
X662271Y820376D01*
X662521Y820543D01*
X662812Y820585D01*
X663062Y820543D01*
X663312Y820376D01*
X663521Y820126D01*
X663604Y819835D01*
X663521Y819501D01*
X663271Y819210D01*
X662896Y819043D01*
X662479Y819001D01*
X661937Y819085D01*
X661646Y819210D01*
X661354Y819418D01*
X661146Y819710D01*
X661104Y820001D01*
X661187Y820293D01*
X661396Y820501D01*
G01X663604Y822893D02*
X661104D01*
X661604Y822393D01*
G01X663604D02*
Y823393D01*
G01X657312Y814510D02*
X657187Y814260D01*
X657104Y813968D01*
Y813635D01*
X657229Y813260D01*
X657437Y812968D01*
X657687Y812760D01*
X658104Y812593D01*
X658479Y812551D01*
X658854Y812635D01*
X659104Y812760D01*
X659354Y813010D01*
X659521Y813301D01*
X659604Y813593D01*
Y813885D01*
X659521Y814176D01*
X659396Y814426D01*
X659229Y814635D01*
G01X659604Y816693D02*
X657104D01*
X657604Y816193D01*
G01X659604D02*
Y817193D01*
G01X658562Y819001D02*
X658271Y819293D01*
X658104Y819543D01*
X658021Y819876D01*
X658104Y820168D01*
X658271Y820376D01*
X658521Y820543D01*
X658812Y820585D01*
X659062Y820543D01*
X659312Y820376D01*
X659521Y820126D01*
X659604Y819835D01*
X659521Y819501D01*
X659271Y819210D01*
X658896Y819043D01*
X658479Y819001D01*
X657937Y819085D01*
X657646Y819210D01*
X657354Y819418D01*
X657146Y819710D01*
X657104Y820001D01*
X657187Y820293D01*
X657396Y820501D01*
G01X657104Y822893D02*
X657187Y822560D01*
X657396Y822310D01*
X657646Y822143D01*
X657979Y822018D01*
X658354Y821976D01*
X658729Y822018D01*
X659062Y822143D01*
X659312Y822310D01*
X659521Y822560D01*
X659604Y822893D01*
X659521Y823226D01*
X659312Y823476D01*
X659062Y823643D01*
X658729Y823768D01*
X658354Y823810D01*
X657979Y823768D01*
X657646Y823643D01*
X657396Y823476D01*
X657187Y823226D01*
X657104Y822893D01*
G01X669910Y814510D02*
X669785Y814260D01*
X669702Y813968D01*
Y813635D01*
X669827Y813260D01*
X670035Y812968D01*
X670285Y812760D01*
X670702Y812593D01*
X671077Y812551D01*
X671452Y812635D01*
X671702Y812760D01*
X671952Y813010D01*
X672119Y813301D01*
X672202Y813593D01*
Y813885D01*
X672119Y814176D01*
X671994Y814426D01*
X671827Y814635D01*
G01X672202Y816693D02*
X669702D01*
X670202Y816193D01*
G01X672202D02*
Y817193D01*
G01Y820293D02*
X669702D01*
X671494Y818751D01*
Y820835D01*
G01X669702Y822893D02*
X669785Y822560D01*
X669994Y822310D01*
X670244Y822143D01*
X670577Y822018D01*
X670952Y821976D01*
X671327Y822018D01*
X671660Y822143D01*
X671910Y822310D01*
X672119Y822560D01*
X672202Y822893D01*
X672119Y823226D01*
X671910Y823476D01*
X671660Y823643D01*
X671327Y823768D01*
X670952Y823810D01*
X670577Y823768D01*
X670244Y823643D01*
X669994Y823476D01*
X669785Y823226D01*
X669702Y822893D01*
G01X646422Y819346D02*
X646297Y819096D01*
X646214Y818804D01*
Y818471D01*
X646339Y818096D01*
X646547Y817804D01*
X646797Y817596D01*
X647214Y817429D01*
X647589Y817387D01*
X647964Y817471D01*
X648214Y817596D01*
X648464Y817846D01*
X648631Y818137D01*
X648714Y818429D01*
Y818721D01*
X648631Y819012D01*
X648506Y819262D01*
X648339Y819471D01*
G01X648714Y822029D02*
X646214D01*
X648006Y820487D01*
Y822571D01*
G01X648714Y824629D02*
X646214D01*
X646714Y824129D01*
G01X648714D02*
Y825129D01*
G01Y828229D02*
X646214D01*
X648006Y826687D01*
Y828771D01*
G01X646214Y830829D02*
X646297Y830496D01*
X646506Y830246D01*
X646756Y830079D01*
X647089Y829954D01*
X647464Y829912D01*
X647839Y829954D01*
X648172Y830079D01*
X648422Y830246D01*
X648631Y830496D01*
X648714Y830829D01*
X648631Y831162D01*
X648422Y831412D01*
X648172Y831579D01*
X647839Y831704D01*
X647464Y831746D01*
X647089Y831704D01*
X646756Y831579D01*
X646506Y831412D01*
X646297Y831162D01*
X646214Y830829D01*
G01X705320Y-5793D02*
X702820D01*
Y-4752D01*
X702945Y-4418D01*
X703112Y-4210D01*
X703445Y-4127D01*
X703778Y-4210D01*
X703987Y-4460D01*
X704112Y-4752D01*
Y-5793D01*
G01Y-4752D02*
X705320Y-4127D01*
G01X703237Y-2652D02*
X702987Y-2402D01*
X702862Y-2110D01*
X702820Y-1777D01*
X702903Y-1360D01*
X703112Y-1068D01*
X703362Y-985D01*
X703612Y-1027D01*
X703820Y-1193D01*
X704237Y-2027D01*
X704528Y-2402D01*
X704945Y-2652D01*
X705320Y-2735D01*
Y-985D01*
G01X705028Y532D02*
X705237Y823D01*
X705320Y1157D01*
X705237Y1490D01*
X704987Y1782D01*
X704612Y1990D01*
X704237Y2073D01*
X703778D01*
X703403Y1990D01*
X703070Y1782D01*
X702903Y1532D01*
X702820Y1240D01*
X702903Y907D01*
X703070Y657D01*
X703320Y490D01*
X703653Y407D01*
X703945Y490D01*
X704237Y698D01*
X704403Y948D01*
X704445Y1240D01*
X704362Y1573D01*
X704153Y1823D01*
X703778Y2073D01*
G01X704945Y3423D02*
X705153Y3673D01*
X705278Y3965D01*
X705320Y4340D01*
X705237Y4715D01*
X705070Y5007D01*
X704778Y5215D01*
X704445Y5257D01*
X704112Y5173D01*
X703903Y4965D01*
X703737Y4673D01*
X703695Y4382D01*
X703737Y4090D01*
X703903Y3715D01*
X702820Y3840D01*
Y4965D01*
G01X705320Y7940D02*
X702820D01*
X704612Y6398D01*
Y8482D01*
G01X701200Y-5863D02*
X698700D01*
Y-4822D01*
X698825Y-4488D01*
X698992Y-4280D01*
X699325Y-4197D01*
X699658Y-4280D01*
X699867Y-4530D01*
X699992Y-4822D01*
Y-5863D01*
G01Y-4822D02*
X701200Y-4197D01*
G01X699117Y-2722D02*
X698867Y-2472D01*
X698742Y-2180D01*
X698700Y-1847D01*
X698783Y-1430D01*
X698992Y-1138D01*
X699242Y-1055D01*
X699492Y-1097D01*
X699700Y-1263D01*
X700117Y-2097D01*
X700408Y-2472D01*
X700825Y-2722D01*
X701200Y-2805D01*
Y-1055D01*
G01X700908Y462D02*
X701117Y753D01*
X701200Y1087D01*
X701117Y1420D01*
X700867Y1712D01*
X700492Y1920D01*
X700117Y2003D01*
X699658D01*
X699283Y1920D01*
X698950Y1712D01*
X698783Y1462D01*
X698700Y1170D01*
X698783Y837D01*
X698950Y587D01*
X699200Y420D01*
X699533Y337D01*
X699825Y420D01*
X700117Y628D01*
X700283Y878D01*
X700325Y1170D01*
X700242Y1503D01*
X700033Y1753D01*
X699658Y2003D01*
G01X700825Y3353D02*
X701033Y3603D01*
X701158Y3895D01*
X701200Y4270D01*
X701117Y4645D01*
X700950Y4937D01*
X700658Y5145D01*
X700325Y5187D01*
X699992Y5103D01*
X699783Y4895D01*
X699617Y4603D01*
X699575Y4312D01*
X699617Y4020D01*
X699783Y3645D01*
X698700Y3770D01*
Y4895D01*
G01X701200Y7370D02*
X698700D01*
X699200Y6870D01*
G01X701200D02*
Y7870D01*
G01X700117Y10400D02*
Y12900D01*
X701158D01*
X701492Y12775D01*
X701700Y12608D01*
X701783Y12275D01*
X701700Y11942D01*
X701450Y11733D01*
X701158Y11608D01*
X700117D01*
G01X701158D02*
X701783Y10400D01*
G01X704550D02*
Y12900D01*
X703008Y11108D01*
X705092D01*
G01X706442Y10692D02*
X706733Y10483D01*
X707067Y10400D01*
X707400Y10483D01*
X707692Y10733D01*
X707900Y11108D01*
X707983Y11483D01*
Y11942D01*
X707900Y12317D01*
X707692Y12650D01*
X707442Y12817D01*
X707150Y12900D01*
X706817Y12817D01*
X706567Y12650D01*
X706400Y12400D01*
X706317Y12067D01*
X706400Y11775D01*
X706608Y11483D01*
X706858Y11317D01*
X707150Y11275D01*
X707483Y11358D01*
X707733Y11567D01*
X707983Y11942D01*
G01X709458Y11442D02*
X709750Y11733D01*
X710000Y11900D01*
X710333Y11983D01*
X710625Y11900D01*
X710833Y11733D01*
X711000Y11483D01*
X711042Y11192D01*
X711000Y10942D01*
X710833Y10692D01*
X710583Y10483D01*
X710292Y10400D01*
X709958Y10483D01*
X709667Y10733D01*
X709500Y11108D01*
X709458Y11525D01*
X709542Y12067D01*
X709667Y12358D01*
X709875Y12650D01*
X710167Y12858D01*
X710458Y12900D01*
X710750Y12817D01*
X710958Y12608D01*
G01X696334Y31017D02*
X693834D01*
Y32058D01*
X693959Y32392D01*
X694126Y32600D01*
X694459Y32683D01*
X694792Y32600D01*
X695001Y32350D01*
X695126Y32058D01*
Y31017D01*
G01Y32058D02*
X696334Y32683D01*
G01Y34867D02*
X695792Y34950D01*
X695334Y35075D01*
X694917Y35242D01*
X694459Y35450D01*
X693834Y35783D01*
Y34117D01*
G01X696334Y38050D02*
X693834D01*
X694334Y37550D01*
G01X696334D02*
Y38550D01*
G01Y41067D02*
X695792Y41150D01*
X695334Y41275D01*
X694917Y41442D01*
X694459Y41650D01*
X693834Y41983D01*
Y40317D01*
G01X694917Y15300D02*
Y17800D01*
X695958D01*
X696292Y17675D01*
X696500Y17508D01*
X696583Y17175D01*
X696500Y16842D01*
X696250Y16633D01*
X695958Y16508D01*
X694917D01*
G01X695958D02*
X696583Y15300D01*
G01X698767D02*
X698850Y15842D01*
X698975Y16300D01*
X699142Y16717D01*
X699350Y17175D01*
X699683Y17800D01*
X698017D01*
G01X701950Y15300D02*
Y17800D01*
X701450Y17300D01*
G01Y15300D02*
X702450D01*
G01X704258Y16342D02*
X704550Y16633D01*
X704800Y16800D01*
X705133Y16883D01*
X705425Y16800D01*
X705633Y16633D01*
X705800Y16383D01*
X705842Y16092D01*
X705800Y15842D01*
X705633Y15592D01*
X705383Y15383D01*
X705092Y15300D01*
X704758Y15383D01*
X704467Y15633D01*
X704300Y16008D01*
X704258Y16425D01*
X704342Y16967D01*
X704467Y17258D01*
X704675Y17550D01*
X704967Y17758D01*
X705258Y17800D01*
X705550Y17717D01*
X705758Y17508D01*
G01X700267Y34959D02*
X700017Y35084D01*
X699725Y35167D01*
X699392D01*
X699017Y35042D01*
X698725Y34834D01*
X698517Y34584D01*
X698350Y34167D01*
X698308Y33792D01*
X698392Y33417D01*
X698517Y33167D01*
X698767Y32917D01*
X699058Y32750D01*
X699350Y32667D01*
X699642D01*
X699933Y32750D01*
X700183Y32875D01*
X700392Y33042D01*
G01X701658Y34750D02*
X701908Y35000D01*
X702200Y35125D01*
X702533Y35167D01*
X702950Y35084D01*
X703242Y34875D01*
X703325Y34625D01*
X703283Y34375D01*
X703117Y34167D01*
X702283Y33750D01*
X701908Y33459D01*
X701658Y33042D01*
X701575Y32667D01*
X703325D01*
G01X704758Y33709D02*
X705050Y34000D01*
X705300Y34167D01*
X705633Y34250D01*
X705925Y34167D01*
X706133Y34000D01*
X706300Y33750D01*
X706342Y33459D01*
X706300Y33209D01*
X706133Y32959D01*
X705883Y32750D01*
X705592Y32667D01*
X705258Y32750D01*
X704967Y33000D01*
X704800Y33375D01*
X704758Y33792D01*
X704842Y34334D01*
X704967Y34625D01*
X705175Y34917D01*
X705467Y35125D01*
X705758Y35167D01*
X706050Y35084D01*
X706258Y34875D01*
G01X707942Y32959D02*
X708233Y32750D01*
X708567Y32667D01*
X708900Y32750D01*
X709192Y33000D01*
X709400Y33375D01*
X709483Y33750D01*
Y34209D01*
X709400Y34584D01*
X709192Y34917D01*
X708942Y35084D01*
X708650Y35167D01*
X708317Y35084D01*
X708067Y34917D01*
X707900Y34667D01*
X707817Y34334D01*
X707900Y34042D01*
X708108Y33750D01*
X708358Y33584D01*
X708650Y33542D01*
X708983Y33625D01*
X709233Y33834D01*
X709483Y34209D01*
G01X696325Y58600D02*
X696658Y58392D01*
X697033Y58267D01*
X697367D01*
X697700Y58392D01*
X697950Y58600D01*
X698075Y58892D01*
X697992Y59184D01*
X697783Y59434D01*
X697408Y59600D01*
X696908Y59684D01*
X696617Y59850D01*
X696492Y60142D01*
X696575Y60434D01*
X696783Y60642D01*
X697075Y60767D01*
X697367D01*
X697658Y60684D01*
X697908Y60475D01*
G01X699467Y58267D02*
Y60767D01*
X700508D01*
X700842Y60642D01*
X701050Y60475D01*
X701133Y60142D01*
X701050Y59809D01*
X700800Y59600D01*
X700508Y59475D01*
X699467D01*
G01X700508D02*
X701133Y58267D01*
G01X703317D02*
X703400Y58809D01*
X703525Y59267D01*
X703692Y59684D01*
X703900Y60142D01*
X704233Y60767D01*
X702567D01*
G01X706500Y58267D02*
Y60767D01*
X706000Y60267D01*
G01Y58267D02*
X707000D01*
G01X709600D02*
X709892Y58309D01*
X710225Y58434D01*
X710433Y58642D01*
X710517Y58934D01*
X710433Y59225D01*
X710183Y59475D01*
X709808Y59600D01*
X709392D01*
X709142Y59684D01*
X708933Y59892D01*
X708850Y60184D01*
X708975Y60475D01*
X709267Y60684D01*
X709600Y60767D01*
X709933Y60684D01*
X710225Y60475D01*
X710350Y60184D01*
X710267Y59892D01*
X710058Y59684D01*
X709808Y59600D01*
X709392D01*
X709017Y59475D01*
X708767Y59225D01*
X708683Y58934D01*
X708767Y58642D01*
X708975Y58434D01*
X709308Y58309D01*
X709600Y58267D01*
G01X699017Y44167D02*
Y46667D01*
X700058D01*
X700392Y46542D01*
X700600Y46375D01*
X700683Y46042D01*
X700600Y45709D01*
X700350Y45500D01*
X700058Y45375D01*
X699017D01*
G01X700058D02*
X700683Y44167D01*
G01X702033Y44542D02*
X702283Y44334D01*
X702575Y44209D01*
X702950Y44167D01*
X703325Y44250D01*
X703617Y44417D01*
X703825Y44709D01*
X703867Y45042D01*
X703783Y45375D01*
X703575Y45584D01*
X703283Y45750D01*
X702992Y45792D01*
X702700Y45750D01*
X702325Y45584D01*
X702450Y46667D01*
X703575D01*
G01X705133Y44667D02*
X705383Y44375D01*
X705717Y44209D01*
X706092Y44167D01*
X706425Y44209D01*
X706758Y44417D01*
X706967Y44667D01*
X707008Y44917D01*
X706925Y45209D01*
X706633Y45417D01*
X706342Y45500D01*
X705967D01*
G01X706342D02*
X706592Y45625D01*
X706800Y45834D01*
X706883Y46084D01*
X706800Y46334D01*
X706592Y46542D01*
X706217Y46667D01*
X705842Y46625D01*
X705467Y46459D01*
G01X708358Y46250D02*
X708608Y46500D01*
X708900Y46625D01*
X709233Y46667D01*
X709650Y46584D01*
X709942Y46375D01*
X710025Y46125D01*
X709983Y45875D01*
X709817Y45667D01*
X708983Y45250D01*
X708608Y44959D01*
X708358Y44542D01*
X708275Y44167D01*
X710025D01*
G01X693467Y48167D02*
Y50667D01*
X694508D01*
X694842Y50542D01*
X695050Y50375D01*
X695133Y50042D01*
X695050Y49709D01*
X694800Y49500D01*
X694508Y49375D01*
X693467D01*
G01X694508D02*
X695133Y48167D01*
G01X696608Y50250D02*
X696858Y50500D01*
X697150Y50625D01*
X697483Y50667D01*
X697900Y50584D01*
X698192Y50375D01*
X698275Y50125D01*
X698233Y49875D01*
X698067Y49667D01*
X697233Y49250D01*
X696858Y48959D01*
X696608Y48542D01*
X696525Y48167D01*
X698275D01*
G01X699792Y48459D02*
X700083Y48250D01*
X700417Y48167D01*
X700750Y48250D01*
X701042Y48500D01*
X701250Y48875D01*
X701333Y49250D01*
Y49709D01*
X701250Y50084D01*
X701042Y50417D01*
X700792Y50584D01*
X700500Y50667D01*
X700167Y50584D01*
X699917Y50417D01*
X699750Y50167D01*
X699667Y49834D01*
X699750Y49542D01*
X699958Y49250D01*
X700208Y49084D01*
X700500Y49042D01*
X700833Y49125D01*
X701083Y49334D01*
X701333Y49709D01*
G01X702683Y48542D02*
X702933Y48334D01*
X703225Y48209D01*
X703600Y48167D01*
X703975Y48250D01*
X704267Y48417D01*
X704475Y48709D01*
X704517Y49042D01*
X704433Y49375D01*
X704225Y49584D01*
X703933Y49750D01*
X703642Y49792D01*
X703350Y49750D01*
X702975Y49584D01*
X703100Y50667D01*
X704225D01*
G01X705783Y48542D02*
X706033Y48334D01*
X706325Y48209D01*
X706700Y48167D01*
X707075Y48250D01*
X707367Y48417D01*
X707575Y48709D01*
X707617Y49042D01*
X707533Y49375D01*
X707325Y49584D01*
X707033Y49750D01*
X706742Y49792D01*
X706450Y49750D01*
X706075Y49584D01*
X706200Y50667D01*
X707325D01*
G01X696267Y64900D02*
Y62400D01*
X697933D01*
G01X701033D02*
X699367D01*
Y64900D01*
X701033D01*
G01X700367Y63692D02*
X699367D01*
G01X702383Y62400D02*
Y64900D01*
X703217D01*
X703550Y64775D01*
X703800Y64608D01*
X704008Y64358D01*
X704175Y64067D01*
X704217Y63650D01*
X704175Y63233D01*
X704008Y62942D01*
X703800Y62692D01*
X703550Y62525D01*
X703217Y62400D01*
X702383D01*
G01X706400D02*
Y64900D01*
X705900Y64400D01*
G01Y62400D02*
X706900D01*
G01X709500D02*
X709792Y62442D01*
X710125Y62567D01*
X710333Y62775D01*
X710417Y63067D01*
X710333Y63358D01*
X710083Y63608D01*
X709708Y63733D01*
X709292D01*
X709042Y63817D01*
X708833Y64025D01*
X708750Y64317D01*
X708875Y64608D01*
X709167Y64817D01*
X709500Y64900D01*
X709833Y64817D01*
X710125Y64608D01*
X710250Y64317D01*
X710167Y64025D01*
X709958Y63817D01*
X709708Y63733D01*
X709292D01*
X708917Y63608D01*
X708667Y63358D01*
X708583Y63067D01*
X708667Y62775D01*
X708875Y62567D01*
X709208Y62442D01*
X709500Y62400D01*
G01X700467Y98959D02*
X700217Y99084D01*
X699925Y99167D01*
X699592D01*
X699217Y99042D01*
X698925Y98834D01*
X698717Y98584D01*
X698550Y98167D01*
X698508Y97792D01*
X698592Y97417D01*
X698717Y97167D01*
X698967Y96917D01*
X699258Y96750D01*
X699550Y96667D01*
X699842D01*
X700133Y96750D01*
X700383Y96875D01*
X700592Y97042D01*
G01X703150Y96667D02*
Y99167D01*
X701608Y97375D01*
X703692D01*
G01X705750Y96667D02*
Y99167D01*
X705250Y98667D01*
G01Y96667D02*
X706250D01*
G01X708850D02*
Y99167D01*
X708350Y98667D01*
G01Y96667D02*
X709350D01*
G01X699367Y84259D02*
X699117Y84384D01*
X698825Y84467D01*
X698492D01*
X698117Y84342D01*
X697825Y84134D01*
X697617Y83884D01*
X697450Y83467D01*
X697408Y83092D01*
X697492Y82717D01*
X697617Y82467D01*
X697867Y82217D01*
X698158Y82050D01*
X698450Y81967D01*
X698742D01*
X699033Y82050D01*
X699283Y82175D01*
X699492Y82342D01*
G01X702050Y81967D02*
Y84467D01*
X700508Y82675D01*
X702592D01*
G01X704650Y81967D02*
Y84467D01*
X704150Y83967D01*
G01Y81967D02*
X705150D01*
G01X707750Y84467D02*
X707417Y84384D01*
X707167Y84175D01*
X707000Y83925D01*
X706875Y83592D01*
X706833Y83217D01*
X706875Y82842D01*
X707000Y82509D01*
X707167Y82259D01*
X707417Y82050D01*
X707750Y81967D01*
X708083Y82050D01*
X708333Y82259D01*
X708500Y82509D01*
X708625Y82842D01*
X708667Y83217D01*
X708625Y83592D01*
X708500Y83925D01*
X708333Y84175D01*
X708083Y84384D01*
X707750Y84467D01*
G01X706467Y135759D02*
X706217Y135884D01*
X705925Y135967D01*
X705592D01*
X705217Y135842D01*
X704925Y135634D01*
X704717Y135384D01*
X704550Y134967D01*
X704508Y134592D01*
X704592Y134217D01*
X704717Y133967D01*
X704967Y133717D01*
X705258Y133550D01*
X705550Y133467D01*
X705842D01*
X706133Y133550D01*
X706383Y133675D01*
X706592Y133842D01*
G01X709150Y133467D02*
Y135967D01*
X707608Y134175D01*
X709692D01*
G01X711750Y135967D02*
X711417Y135884D01*
X711167Y135675D01*
X711000Y135425D01*
X710875Y135092D01*
X710833Y134717D01*
X710875Y134342D01*
X711000Y134009D01*
X711167Y133759D01*
X711417Y133550D01*
X711750Y133467D01*
X712083Y133550D01*
X712333Y133759D01*
X712500Y134009D01*
X712625Y134342D01*
X712667Y134717D01*
X712625Y135092D01*
X712500Y135425D01*
X712333Y135675D01*
X712083Y135884D01*
X711750Y135967D01*
G01X714142Y133759D02*
X714433Y133550D01*
X714767Y133467D01*
X715100Y133550D01*
X715392Y133800D01*
X715600Y134175D01*
X715683Y134550D01*
Y135009D01*
X715600Y135384D01*
X715392Y135717D01*
X715142Y135884D01*
X714850Y135967D01*
X714517Y135884D01*
X714267Y135717D01*
X714100Y135467D01*
X714017Y135134D01*
X714100Y134842D01*
X714308Y134550D01*
X714558Y134384D01*
X714850Y134342D01*
X715183Y134425D01*
X715433Y134634D01*
X715683Y135009D01*
G01X706467Y131559D02*
X706217Y131684D01*
X705925Y131767D01*
X705592D01*
X705217Y131642D01*
X704925Y131434D01*
X704717Y131184D01*
X704550Y130767D01*
X704508Y130392D01*
X704592Y130017D01*
X704717Y129767D01*
X704967Y129517D01*
X705258Y129350D01*
X705550Y129267D01*
X705842D01*
X706133Y129350D01*
X706383Y129475D01*
X706592Y129642D01*
G01X709150Y129267D02*
Y131767D01*
X707608Y129975D01*
X709692D01*
G01X711750Y131767D02*
X711417Y131684D01*
X711167Y131475D01*
X711000Y131225D01*
X710875Y130892D01*
X710833Y130517D01*
X710875Y130142D01*
X711000Y129809D01*
X711167Y129559D01*
X711417Y129350D01*
X711750Y129267D01*
X712083Y129350D01*
X712333Y129559D01*
X712500Y129809D01*
X712625Y130142D01*
X712667Y130517D01*
X712625Y130892D01*
X712500Y131225D01*
X712333Y131475D01*
X712083Y131684D01*
X711750Y131767D01*
G01X714850Y129267D02*
X715142Y129309D01*
X715475Y129434D01*
X715683Y129642D01*
X715767Y129934D01*
X715683Y130225D01*
X715433Y130475D01*
X715058Y130600D01*
X714642D01*
X714392Y130684D01*
X714183Y130892D01*
X714100Y131184D01*
X714225Y131475D01*
X714517Y131684D01*
X714850Y131767D01*
X715183Y131684D01*
X715475Y131475D01*
X715600Y131184D01*
X715517Y130892D01*
X715308Y130684D01*
X715058Y130600D01*
X714642D01*
X714267Y130475D01*
X714017Y130225D01*
X713933Y129934D01*
X714017Y129642D01*
X714225Y129434D01*
X714558Y129309D01*
X714850Y129267D01*
G01X706667Y144059D02*
X706417Y144184D01*
X706125Y144267D01*
X705792D01*
X705417Y144142D01*
X705125Y143934D01*
X704917Y143684D01*
X704750Y143267D01*
X704708Y142892D01*
X704792Y142517D01*
X704917Y142267D01*
X705167Y142017D01*
X705458Y141850D01*
X705750Y141767D01*
X706042D01*
X706333Y141850D01*
X706583Y141975D01*
X706792Y142142D01*
G01X709350Y141767D02*
Y144267D01*
X707808Y142475D01*
X709892D01*
G01X711950Y144267D02*
X711617Y144184D01*
X711367Y143975D01*
X711200Y143725D01*
X711075Y143392D01*
X711033Y143017D01*
X711075Y142642D01*
X711200Y142309D01*
X711367Y142059D01*
X711617Y141850D01*
X711950Y141767D01*
X712283Y141850D01*
X712533Y142059D01*
X712700Y142309D01*
X712825Y142642D01*
X712867Y143017D01*
X712825Y143392D01*
X712700Y143725D01*
X712533Y143975D01*
X712283Y144184D01*
X711950Y144267D01*
G01X714967Y141767D02*
X715050Y142309D01*
X715175Y142767D01*
X715342Y143184D01*
X715550Y143642D01*
X715883Y144267D01*
X714217D01*
G01X706567Y139859D02*
X706317Y139984D01*
X706025Y140067D01*
X705692D01*
X705317Y139942D01*
X705025Y139734D01*
X704817Y139484D01*
X704650Y139067D01*
X704608Y138692D01*
X704692Y138317D01*
X704817Y138067D01*
X705067Y137817D01*
X705358Y137650D01*
X705650Y137567D01*
X705942D01*
X706233Y137650D01*
X706483Y137775D01*
X706692Y137942D01*
G01X709250Y137567D02*
Y140067D01*
X707708Y138275D01*
X709792D01*
G01X711850Y140067D02*
X711517Y139984D01*
X711267Y139775D01*
X711100Y139525D01*
X710975Y139192D01*
X710933Y138817D01*
X710975Y138442D01*
X711100Y138109D01*
X711267Y137859D01*
X711517Y137650D01*
X711850Y137567D01*
X712183Y137650D01*
X712433Y137859D01*
X712600Y138109D01*
X712725Y138442D01*
X712767Y138817D01*
X712725Y139192D01*
X712600Y139525D01*
X712433Y139775D01*
X712183Y139984D01*
X711850Y140067D01*
G01X714158Y138609D02*
X714450Y138900D01*
X714700Y139067D01*
X715033Y139150D01*
X715325Y139067D01*
X715533Y138900D01*
X715700Y138650D01*
X715742Y138359D01*
X715700Y138109D01*
X715533Y137859D01*
X715283Y137650D01*
X714992Y137567D01*
X714658Y137650D01*
X714367Y137900D01*
X714200Y138275D01*
X714158Y138692D01*
X714242Y139234D01*
X714367Y139525D01*
X714575Y139817D01*
X714867Y140025D01*
X715158Y140067D01*
X715450Y139984D01*
X715658Y139775D01*
G01X706567Y122759D02*
X706317Y122884D01*
X706025Y122967D01*
X705692D01*
X705317Y122842D01*
X705025Y122634D01*
X704817Y122384D01*
X704650Y121967D01*
X704608Y121592D01*
X704692Y121217D01*
X704817Y120967D01*
X705067Y120717D01*
X705358Y120550D01*
X705650Y120467D01*
X705942D01*
X706233Y120550D01*
X706483Y120675D01*
X706692Y120842D01*
G01X709250Y120467D02*
Y122967D01*
X707708Y121175D01*
X709792D01*
G01X711850Y122967D02*
X711517Y122884D01*
X711267Y122675D01*
X711100Y122425D01*
X710975Y122092D01*
X710933Y121717D01*
X710975Y121342D01*
X711100Y121009D01*
X711267Y120759D01*
X711517Y120550D01*
X711850Y120467D01*
X712183Y120550D01*
X712433Y120759D01*
X712600Y121009D01*
X712725Y121342D01*
X712767Y121717D01*
X712725Y122092D01*
X712600Y122425D01*
X712433Y122675D01*
X712183Y122884D01*
X711850Y122967D01*
G01X714033Y120842D02*
X714283Y120634D01*
X714575Y120509D01*
X714950Y120467D01*
X715325Y120550D01*
X715617Y120717D01*
X715825Y121009D01*
X715867Y121342D01*
X715783Y121675D01*
X715575Y121884D01*
X715283Y122050D01*
X714992Y122092D01*
X714700Y122050D01*
X714325Y121884D01*
X714450Y122967D01*
X715575D01*
G01X706467Y127559D02*
X706217Y127684D01*
X705925Y127767D01*
X705592D01*
X705217Y127642D01*
X704925Y127434D01*
X704717Y127184D01*
X704550Y126767D01*
X704508Y126392D01*
X704592Y126017D01*
X704717Y125767D01*
X704967Y125517D01*
X705258Y125350D01*
X705550Y125267D01*
X705842D01*
X706133Y125350D01*
X706383Y125475D01*
X706592Y125642D01*
G01X709150Y125267D02*
Y127767D01*
X707608Y125975D01*
X709692D01*
G01X711750Y127767D02*
X711417Y127684D01*
X711167Y127475D01*
X711000Y127225D01*
X710875Y126892D01*
X710833Y126517D01*
X710875Y126142D01*
X711000Y125809D01*
X711167Y125559D01*
X711417Y125350D01*
X711750Y125267D01*
X712083Y125350D01*
X712333Y125559D01*
X712500Y125809D01*
X712625Y126142D01*
X712667Y126517D01*
X712625Y126892D01*
X712500Y127225D01*
X712333Y127475D01*
X712083Y127684D01*
X711750Y127767D01*
G01X715350Y125267D02*
Y127767D01*
X713808Y125975D01*
X715892D01*
G01X706667Y152159D02*
X706417Y152284D01*
X706125Y152367D01*
X705792D01*
X705417Y152242D01*
X705125Y152034D01*
X704917Y151784D01*
X704750Y151367D01*
X704708Y150992D01*
X704792Y150617D01*
X704917Y150367D01*
X705167Y150117D01*
X705458Y149950D01*
X705750Y149867D01*
X706042D01*
X706333Y149950D01*
X706583Y150075D01*
X706792Y150242D01*
G01X709350Y149867D02*
Y152367D01*
X707808Y150575D01*
X709892D01*
G01X711950Y152367D02*
X711617Y152284D01*
X711367Y152075D01*
X711200Y151825D01*
X711075Y151492D01*
X711033Y151117D01*
X711075Y150742D01*
X711200Y150409D01*
X711367Y150159D01*
X711617Y149950D01*
X711950Y149867D01*
X712283Y149950D01*
X712533Y150159D01*
X712700Y150409D01*
X712825Y150742D01*
X712867Y151117D01*
X712825Y151492D01*
X712700Y151825D01*
X712533Y152075D01*
X712283Y152284D01*
X711950Y152367D01*
G01X714133Y150367D02*
X714383Y150075D01*
X714717Y149909D01*
X715092Y149867D01*
X715425Y149909D01*
X715758Y150117D01*
X715967Y150367D01*
X716008Y150617D01*
X715925Y150909D01*
X715633Y151117D01*
X715342Y151200D01*
X714967D01*
G01X715342D02*
X715592Y151325D01*
X715800Y151534D01*
X715883Y151784D01*
X715800Y152034D01*
X715592Y152242D01*
X715217Y152367D01*
X714842Y152325D01*
X714467Y152159D01*
G01X706567Y148059D02*
X706317Y148184D01*
X706025Y148267D01*
X705692D01*
X705317Y148142D01*
X705025Y147934D01*
X704817Y147684D01*
X704650Y147267D01*
X704608Y146892D01*
X704692Y146517D01*
X704817Y146267D01*
X705067Y146017D01*
X705358Y145850D01*
X705650Y145767D01*
X705942D01*
X706233Y145850D01*
X706483Y145975D01*
X706692Y146142D01*
G01X709250Y145767D02*
Y148267D01*
X707708Y146475D01*
X709792D01*
G01X711850Y148267D02*
X711517Y148184D01*
X711267Y147975D01*
X711100Y147725D01*
X710975Y147392D01*
X710933Y147017D01*
X710975Y146642D01*
X711100Y146309D01*
X711267Y146059D01*
X711517Y145850D01*
X711850Y145767D01*
X712183Y145850D01*
X712433Y146059D01*
X712600Y146309D01*
X712725Y146642D01*
X712767Y147017D01*
X712725Y147392D01*
X712600Y147725D01*
X712433Y147975D01*
X712183Y148184D01*
X711850Y148267D01*
G01X714158Y147850D02*
X714408Y148100D01*
X714700Y148225D01*
X715033Y148267D01*
X715450Y148184D01*
X715742Y147975D01*
X715825Y147725D01*
X715783Y147475D01*
X715617Y147267D01*
X714783Y146850D01*
X714408Y146559D01*
X714158Y146142D01*
X714075Y145767D01*
X715825D01*
G01X695339Y233318D02*
Y191918D01*
G01D02*
X744039D01*
G01X686517Y185667D02*
Y188167D01*
X687558D01*
X687892Y188042D01*
X688100Y187875D01*
X688183Y187542D01*
X688100Y187209D01*
X687850Y187000D01*
X687558Y186875D01*
X686517D01*
G01X687558D02*
X688183Y185667D01*
G01X689658Y186709D02*
X689950Y187000D01*
X690200Y187167D01*
X690533Y187250D01*
X690825Y187167D01*
X691033Y187000D01*
X691200Y186750D01*
X691242Y186459D01*
X691200Y186209D01*
X691033Y185959D01*
X690783Y185750D01*
X690492Y185667D01*
X690158Y185750D01*
X689867Y186000D01*
X689700Y186375D01*
X689658Y186792D01*
X689742Y187334D01*
X689867Y187625D01*
X690075Y187917D01*
X690367Y188125D01*
X690658Y188167D01*
X690950Y188084D01*
X691158Y187875D01*
G01X693550Y188167D02*
X693217Y188084D01*
X692967Y187875D01*
X692800Y187625D01*
X692675Y187292D01*
X692633Y186917D01*
X692675Y186542D01*
X692800Y186209D01*
X692967Y185959D01*
X693217Y185750D01*
X693550Y185667D01*
X693883Y185750D01*
X694133Y185959D01*
X694300Y186209D01*
X694425Y186542D01*
X694467Y186917D01*
X694425Y187292D01*
X694300Y187625D01*
X694133Y187875D01*
X693883Y188084D01*
X693550Y188167D01*
G01X696650Y185667D02*
X696942Y185709D01*
X697275Y185834D01*
X697483Y186042D01*
X697567Y186334D01*
X697483Y186625D01*
X697233Y186875D01*
X696858Y187000D01*
X696442D01*
X696192Y187084D01*
X695983Y187292D01*
X695900Y187584D01*
X696025Y187875D01*
X696317Y188084D01*
X696650Y188167D01*
X696983Y188084D01*
X697275Y187875D01*
X697400Y187584D01*
X697317Y187292D01*
X697108Y187084D01*
X696858Y187000D01*
X696442D01*
X696067Y186875D01*
X695817Y186625D01*
X695733Y186334D01*
X695817Y186042D01*
X696025Y185834D01*
X696358Y185709D01*
X696650Y185667D01*
G01X672517Y186667D02*
Y189167D01*
X673558D01*
X673892Y189042D01*
X674100Y188875D01*
X674183Y188542D01*
X674100Y188209D01*
X673850Y188000D01*
X673558Y187875D01*
X672517D01*
G01X673558D02*
X674183Y186667D01*
G01X675533Y187042D02*
X675783Y186834D01*
X676075Y186709D01*
X676450Y186667D01*
X676825Y186750D01*
X677117Y186917D01*
X677325Y187209D01*
X677367Y187542D01*
X677283Y187875D01*
X677075Y188084D01*
X676783Y188250D01*
X676492Y188292D01*
X676200Y188250D01*
X675825Y188084D01*
X675950Y189167D01*
X677075D01*
G01X678633Y187042D02*
X678883Y186834D01*
X679175Y186709D01*
X679550Y186667D01*
X679925Y186750D01*
X680217Y186917D01*
X680425Y187209D01*
X680467Y187542D01*
X680383Y187875D01*
X680175Y188084D01*
X679883Y188250D01*
X679592Y188292D01*
X679300Y188250D01*
X678925Y188084D01*
X679050Y189167D01*
X680175D01*
G01X682650Y186667D02*
X682942Y186709D01*
X683275Y186834D01*
X683483Y187042D01*
X683567Y187334D01*
X683483Y187625D01*
X683233Y187875D01*
X682858Y188000D01*
X682442D01*
X682192Y188084D01*
X681983Y188292D01*
X681900Y188584D01*
X682025Y188875D01*
X682317Y189084D01*
X682650Y189167D01*
X682983Y189084D01*
X683275Y188875D01*
X683400Y188584D01*
X683317Y188292D01*
X683108Y188084D01*
X682858Y188000D01*
X682442D01*
X682067Y187875D01*
X681817Y187625D01*
X681733Y187334D01*
X681817Y187042D01*
X682025Y186834D01*
X682358Y186709D01*
X682650Y186667D01*
G01X693334Y177400D02*
X693292Y177067D01*
X693126Y176775D01*
X692876Y176525D01*
X692584Y176358D01*
X692251Y176275D01*
X691917D01*
X691584Y176358D01*
X691292Y176525D01*
X691042Y176775D01*
X690876Y177067D01*
X690834Y177400D01*
X690876Y177733D01*
X691042Y178025D01*
X691292Y178275D01*
X691584Y178442D01*
X691917Y178525D01*
X692251D01*
X692584Y178442D01*
X692876Y178275D01*
X693126Y178025D01*
X693292Y177733D01*
X693334Y177400D01*
G01X692667Y177733D02*
X693334Y178233D01*
G01X692834Y179583D02*
X693126Y179833D01*
X693292Y180167D01*
X693334Y180542D01*
X693292Y180875D01*
X693084Y181208D01*
X692834Y181417D01*
X692584Y181458D01*
X692292Y181375D01*
X692084Y181083D01*
X692001Y180792D01*
Y180417D01*
G01Y180792D02*
X691876Y181042D01*
X691667Y181250D01*
X691417Y181333D01*
X691167Y181250D01*
X690959Y181042D01*
X690834Y180667D01*
X690876Y180292D01*
X691042Y179917D01*
G01X691251Y182808D02*
X691001Y183058D01*
X690876Y183350D01*
X690834Y183683D01*
X690917Y184100D01*
X691126Y184392D01*
X691376Y184475D01*
X691626Y184433D01*
X691834Y184267D01*
X692251Y183433D01*
X692542Y183058D01*
X692959Y182808D01*
X693334Y182725D01*
Y184475D01*
G01X694381Y208192D02*
X681381D01*
G01D02*
Y194192D01*
G01D02*
X694381D01*
G01D02*
Y208192D01*
G01X679334Y177400D02*
X679292Y177067D01*
X679126Y176775D01*
X678876Y176525D01*
X678584Y176358D01*
X678251Y176275D01*
X677917D01*
X677584Y176358D01*
X677292Y176525D01*
X677042Y176775D01*
X676876Y177067D01*
X676834Y177400D01*
X676876Y177733D01*
X677042Y178025D01*
X677292Y178275D01*
X677584Y178442D01*
X677917Y178525D01*
X678251D01*
X678584Y178442D01*
X678876Y178275D01*
X679126Y178025D01*
X679292Y177733D01*
X679334Y177400D01*
G01X678667Y177733D02*
X679334Y178233D01*
G01X678834Y179583D02*
X679126Y179833D01*
X679292Y180167D01*
X679334Y180542D01*
X679292Y180875D01*
X679084Y181208D01*
X678834Y181417D01*
X678584Y181458D01*
X678292Y181375D01*
X678084Y181083D01*
X678001Y180792D01*
Y180417D01*
G01Y180792D02*
X677876Y181042D01*
X677667Y181250D01*
X677417Y181333D01*
X677167Y181250D01*
X676959Y181042D01*
X676834Y180667D01*
X676876Y180292D01*
X677042Y179917D01*
G01X678959Y182683D02*
X679167Y182933D01*
X679292Y183225D01*
X679334Y183600D01*
X679251Y183975D01*
X679084Y184267D01*
X678792Y184475D01*
X678459Y184517D01*
X678126Y184433D01*
X677917Y184225D01*
X677751Y183933D01*
X677709Y183642D01*
X677751Y183350D01*
X677917Y182975D01*
X676834Y183100D01*
Y184225D01*
G01X680381Y194192D02*
Y208192D01*
G01X690734Y220817D02*
X688234D01*
Y221817D01*
X688359Y222150D01*
X688651Y222400D01*
X688984Y222483D01*
X689317Y222400D01*
X689567Y222192D01*
X689692Y221817D01*
Y220817D01*
G01X688234Y224750D02*
X690734D01*
G01X688234Y223792D02*
Y225708D01*
G01X688442Y228767D02*
X688317Y228517D01*
X688234Y228225D01*
Y227892D01*
X688359Y227517D01*
X688567Y227225D01*
X688817Y227017D01*
X689234Y226850D01*
X689609Y226808D01*
X689984Y226892D01*
X690234Y227017D01*
X690484Y227267D01*
X690651Y227558D01*
X690734Y227850D01*
Y228142D01*
X690651Y228433D01*
X690526Y228683D01*
X690359Y228892D01*
G01X690734Y230950D02*
X690692Y231242D01*
X690567Y231575D01*
X690359Y231783D01*
X690067Y231867D01*
X689776Y231783D01*
X689526Y231533D01*
X689401Y231158D01*
Y230742D01*
X689317Y230492D01*
X689109Y230283D01*
X688817Y230200D01*
X688526Y230325D01*
X688317Y230617D01*
X688234Y230950D01*
X688317Y231283D01*
X688526Y231575D01*
X688817Y231700D01*
X689109Y231617D01*
X689317Y231408D01*
X689401Y231158D01*
Y230742D01*
X689526Y230367D01*
X689776Y230117D01*
X690067Y230033D01*
X690359Y230117D01*
X690567Y230325D01*
X690692Y230658D01*
X690734Y230950D01*
G01X683763Y231608D02*
Y220408D01*
G01X744039Y233318D02*
X695339D01*
G01X694600Y210200D02*
Y214200D01*
X687200D01*
G01X683200Y210000D02*
Y214000D01*
X675800D01*
G01X683763Y247608D02*
Y258808D01*
G01X683837Y259492D02*
Y270692D01*
G01Y297892D02*
Y286692D01*
G01X700054Y300892D02*
Y303392D01*
X701054D01*
X701387Y303267D01*
X701637Y302975D01*
X701720Y302642D01*
X701637Y302309D01*
X701429Y302059D01*
X701054Y301934D01*
X700054D01*
G01X704237Y302142D02*
X705070D01*
Y301392D01*
X704820Y301142D01*
X704529Y300975D01*
X704112Y300892D01*
X703695Y300975D01*
X703404Y301142D01*
X703154Y301392D01*
X702987Y301684D01*
X702904Y302017D01*
Y302309D01*
X702987Y302559D01*
X703154Y302850D01*
X703404Y303100D01*
X703654Y303267D01*
X703987Y303392D01*
X704279D01*
X704612Y303309D01*
X704862Y303142D01*
G01X706295Y302975D02*
X706545Y303225D01*
X706837Y303350D01*
X707170Y303392D01*
X707587Y303309D01*
X707879Y303100D01*
X707962Y302850D01*
X707920Y302600D01*
X707754Y302392D01*
X706920Y301975D01*
X706545Y301684D01*
X706295Y301267D01*
X706212Y300892D01*
X707962D01*
G01X710187D02*
Y303392D01*
X709687Y302892D01*
G01Y300892D02*
X710687D01*
G01X700054Y304892D02*
Y307392D01*
X701054D01*
X701387Y307267D01*
X701637Y306975D01*
X701720Y306642D01*
X701637Y306309D01*
X701429Y306059D01*
X701054Y305934D01*
X700054D01*
G01X704237Y306142D02*
X705070D01*
Y305392D01*
X704820Y305142D01*
X704529Y304975D01*
X704112Y304892D01*
X703695Y304975D01*
X703404Y305142D01*
X703154Y305392D01*
X702987Y305684D01*
X702904Y306017D01*
Y306309D01*
X702987Y306559D01*
X703154Y306850D01*
X703404Y307100D01*
X703654Y307267D01*
X703987Y307392D01*
X704279D01*
X704612Y307309D01*
X704862Y307142D01*
G01X707087Y304892D02*
Y307392D01*
X706587Y306892D01*
G01Y304892D02*
X707587D01*
G01X709395Y305934D02*
X709687Y306225D01*
X709937Y306392D01*
X710270Y306475D01*
X710562Y306392D01*
X710770Y306225D01*
X710937Y305975D01*
X710979Y305684D01*
X710937Y305434D01*
X710770Y305184D01*
X710520Y304975D01*
X710229Y304892D01*
X709895Y304975D01*
X709604Y305225D01*
X709437Y305600D01*
X709395Y306017D01*
X709479Y306559D01*
X709604Y306850D01*
X709812Y307142D01*
X710104Y307350D01*
X710395Y307392D01*
X710687Y307309D01*
X710895Y307100D01*
G01X700054Y308892D02*
Y311392D01*
X701054D01*
X701387Y311267D01*
X701637Y310975D01*
X701720Y310642D01*
X701637Y310309D01*
X701429Y310059D01*
X701054Y309934D01*
X700054D01*
G01X704237Y310142D02*
X705070D01*
Y309392D01*
X704820Y309142D01*
X704529Y308975D01*
X704112Y308892D01*
X703695Y308975D01*
X703404Y309142D01*
X703154Y309392D01*
X702987Y309684D01*
X702904Y310017D01*
Y310309D01*
X702987Y310559D01*
X703154Y310850D01*
X703404Y311100D01*
X703654Y311267D01*
X703987Y311392D01*
X704279D01*
X704612Y311309D01*
X704862Y311142D01*
G01X707087Y308892D02*
Y311392D01*
X706587Y310892D01*
G01Y308892D02*
X707587D01*
G01X709270Y309267D02*
X709520Y309059D01*
X709812Y308934D01*
X710187Y308892D01*
X710562Y308975D01*
X710854Y309142D01*
X711062Y309434D01*
X711104Y309767D01*
X711020Y310100D01*
X710812Y310309D01*
X710520Y310475D01*
X710229Y310517D01*
X709937Y310475D01*
X709562Y310309D01*
X709687Y311392D01*
X710812D01*
G01X684267Y344500D02*
Y347000D01*
X685308D01*
X685642Y346875D01*
X685850Y346708D01*
X685933Y346375D01*
X685850Y346042D01*
X685600Y345833D01*
X685308Y345708D01*
X684267D01*
G01X685308D02*
X685933Y344500D01*
G01X688700D02*
Y347000D01*
X687158Y345208D01*
X689242D01*
G01X690383Y344875D02*
X690633Y344667D01*
X690925Y344542D01*
X691300Y344500D01*
X691675Y344583D01*
X691967Y344750D01*
X692175Y345042D01*
X692217Y345375D01*
X692133Y345708D01*
X691925Y345917D01*
X691633Y346083D01*
X691342Y346125D01*
X691050Y346083D01*
X690675Y345917D01*
X690800Y347000D01*
X691925D01*
G01X700054Y324892D02*
Y327392D01*
X701054D01*
X701387Y327267D01*
X701637Y326975D01*
X701720Y326642D01*
X701637Y326309D01*
X701429Y326059D01*
X701054Y325934D01*
X700054D01*
G01X704237Y326142D02*
X705070D01*
Y325392D01*
X704820Y325142D01*
X704529Y324975D01*
X704112Y324892D01*
X703695Y324975D01*
X703404Y325142D01*
X703154Y325392D01*
X702987Y325684D01*
X702904Y326017D01*
Y326309D01*
X702987Y326559D01*
X703154Y326850D01*
X703404Y327100D01*
X703654Y327267D01*
X703987Y327392D01*
X704279D01*
X704612Y327309D01*
X704862Y327142D01*
G01X706295Y326975D02*
X706545Y327225D01*
X706837Y327350D01*
X707170Y327392D01*
X707587Y327309D01*
X707879Y327100D01*
X707962Y326850D01*
X707920Y326600D01*
X707754Y326392D01*
X706920Y325975D01*
X706545Y325684D01*
X706295Y325267D01*
X706212Y324892D01*
X707962D01*
G01X710187Y327392D02*
X709854Y327309D01*
X709604Y327100D01*
X709437Y326850D01*
X709312Y326517D01*
X709270Y326142D01*
X709312Y325767D01*
X709437Y325434D01*
X709604Y325184D01*
X709854Y324975D01*
X710187Y324892D01*
X710520Y324975D01*
X710770Y325184D01*
X710937Y325434D01*
X711062Y325767D01*
X711104Y326142D01*
X711062Y326517D01*
X710937Y326850D01*
X710770Y327100D01*
X710520Y327309D01*
X710187Y327392D01*
G01X700054Y328892D02*
Y331392D01*
X701054D01*
X701387Y331267D01*
X701637Y330975D01*
X701720Y330642D01*
X701637Y330309D01*
X701429Y330059D01*
X701054Y329934D01*
X700054D01*
G01X704237Y330142D02*
X705070D01*
Y329392D01*
X704820Y329142D01*
X704529Y328975D01*
X704112Y328892D01*
X703695Y328975D01*
X703404Y329142D01*
X703154Y329392D01*
X702987Y329684D01*
X702904Y330017D01*
Y330309D01*
X702987Y330559D01*
X703154Y330850D01*
X703404Y331100D01*
X703654Y331267D01*
X703987Y331392D01*
X704279D01*
X704612Y331309D01*
X704862Y331142D01*
G01X707087Y328892D02*
Y331392D01*
X706587Y330892D01*
G01Y328892D02*
X707587D01*
G01X709479Y329184D02*
X709770Y328975D01*
X710104Y328892D01*
X710437Y328975D01*
X710729Y329225D01*
X710937Y329600D01*
X711020Y329975D01*
Y330434D01*
X710937Y330809D01*
X710729Y331142D01*
X710479Y331309D01*
X710187Y331392D01*
X709854Y331309D01*
X709604Y331142D01*
X709437Y330892D01*
X709354Y330559D01*
X709437Y330267D01*
X709645Y329975D01*
X709895Y329809D01*
X710187Y329767D01*
X710520Y329850D01*
X710770Y330059D01*
X711020Y330434D01*
G01X700054Y312892D02*
Y315392D01*
X701054D01*
X701387Y315267D01*
X701637Y314975D01*
X701720Y314642D01*
X701637Y314309D01*
X701429Y314059D01*
X701054Y313934D01*
X700054D01*
G01X704237Y314142D02*
X705070D01*
Y313392D01*
X704820Y313142D01*
X704529Y312975D01*
X704112Y312892D01*
X703695Y312975D01*
X703404Y313142D01*
X703154Y313392D01*
X702987Y313684D01*
X702904Y314017D01*
Y314309D01*
X702987Y314559D01*
X703154Y314850D01*
X703404Y315100D01*
X703654Y315267D01*
X703987Y315392D01*
X704279D01*
X704612Y315309D01*
X704862Y315142D01*
G01X707087Y312892D02*
Y315392D01*
X706587Y314892D01*
G01Y312892D02*
X707587D01*
G01X710687D02*
Y315392D01*
X709145Y313600D01*
X711229D01*
G01X700054Y316892D02*
Y319392D01*
X701054D01*
X701387Y319267D01*
X701637Y318975D01*
X701720Y318642D01*
X701637Y318309D01*
X701429Y318059D01*
X701054Y317934D01*
X700054D01*
G01X704237Y318142D02*
X705070D01*
Y317392D01*
X704820Y317142D01*
X704529Y316975D01*
X704112Y316892D01*
X703695Y316975D01*
X703404Y317142D01*
X703154Y317392D01*
X702987Y317684D01*
X702904Y318017D01*
Y318309D01*
X702987Y318559D01*
X703154Y318850D01*
X703404Y319100D01*
X703654Y319267D01*
X703987Y319392D01*
X704279D01*
X704612Y319309D01*
X704862Y319142D01*
G01X707087Y316892D02*
Y319392D01*
X706587Y318892D01*
G01Y316892D02*
X707587D01*
G01X709270Y317392D02*
X709520Y317100D01*
X709854Y316934D01*
X710229Y316892D01*
X710562Y316934D01*
X710895Y317142D01*
X711104Y317392D01*
X711145Y317642D01*
X711062Y317934D01*
X710770Y318142D01*
X710479Y318225D01*
X710104D01*
G01X710479D02*
X710729Y318350D01*
X710937Y318559D01*
X711020Y318809D01*
X710937Y319059D01*
X710729Y319267D01*
X710354Y319392D01*
X709979Y319350D01*
X709604Y319184D01*
G01X695834Y323117D02*
X693334D01*
Y324117D01*
X693459Y324450D01*
X693751Y324700D01*
X694084Y324783D01*
X694417Y324700D01*
X694667Y324492D01*
X694792Y324117D01*
Y323117D01*
G01X694584Y327300D02*
Y328133D01*
X695334D01*
X695584Y327883D01*
X695751Y327592D01*
X695834Y327175D01*
X695751Y326758D01*
X695584Y326467D01*
X695334Y326217D01*
X695042Y326050D01*
X694709Y325967D01*
X694417D01*
X694167Y326050D01*
X693876Y326217D01*
X693626Y326467D01*
X693459Y326717D01*
X693334Y327050D01*
Y327342D01*
X693417Y327675D01*
X693584Y327925D01*
G01X695334Y329233D02*
X695626Y329483D01*
X695792Y329817D01*
X695834Y330192D01*
X695792Y330525D01*
X695584Y330858D01*
X695334Y331067D01*
X695084Y331108D01*
X694792Y331025D01*
X694584Y330733D01*
X694501Y330442D01*
Y330067D01*
G01Y330442D02*
X694376Y330692D01*
X694167Y330900D01*
X693917Y330983D01*
X693667Y330900D01*
X693459Y330692D01*
X693334Y330317D01*
X693376Y329942D01*
X693542Y329567D01*
G01X693751Y332458D02*
X693501Y332708D01*
X693376Y333000D01*
X693334Y333333D01*
X693417Y333750D01*
X693626Y334042D01*
X693876Y334125D01*
X694126Y334083D01*
X694334Y333917D01*
X694751Y333083D01*
X695042Y332708D01*
X695459Y332458D01*
X695834Y332375D01*
Y334125D01*
G01X687534Y323417D02*
X685034D01*
Y324417D01*
X685159Y324750D01*
X685451Y325000D01*
X685784Y325083D01*
X686117Y325000D01*
X686367Y324792D01*
X686492Y324417D01*
Y323417D01*
G01X686284Y327600D02*
Y328433D01*
X687034D01*
X687284Y328183D01*
X687451Y327892D01*
X687534Y327475D01*
X687451Y327058D01*
X687284Y326767D01*
X687034Y326517D01*
X686742Y326350D01*
X686409Y326267D01*
X686117D01*
X685867Y326350D01*
X685576Y326517D01*
X685326Y326767D01*
X685159Y327017D01*
X685034Y327350D01*
Y327642D01*
X685117Y327975D01*
X685284Y328225D01*
G01X687034Y329533D02*
X687326Y329783D01*
X687492Y330117D01*
X687534Y330492D01*
X687492Y330825D01*
X687284Y331158D01*
X687034Y331367D01*
X686784Y331408D01*
X686492Y331325D01*
X686284Y331033D01*
X686201Y330742D01*
Y330367D01*
G01Y330742D02*
X686076Y330992D01*
X685867Y331200D01*
X685617Y331283D01*
X685367Y331200D01*
X685159Y330992D01*
X685034Y330617D01*
X685076Y330242D01*
X685242Y329867D01*
G01X687534Y333550D02*
X685034D01*
X685534Y333050D01*
G01X687534D02*
Y334050D01*
G01X691734Y323217D02*
X689234D01*
Y324217D01*
X689359Y324550D01*
X689651Y324800D01*
X689984Y324883D01*
X690317Y324800D01*
X690567Y324592D01*
X690692Y324217D01*
Y323217D01*
G01X690484Y327400D02*
Y328233D01*
X691234D01*
X691484Y327983D01*
X691651Y327692D01*
X691734Y327275D01*
X691651Y326858D01*
X691484Y326567D01*
X691234Y326317D01*
X690942Y326150D01*
X690609Y326067D01*
X690317D01*
X690067Y326150D01*
X689776Y326317D01*
X689526Y326567D01*
X689359Y326817D01*
X689234Y327150D01*
Y327442D01*
X689317Y327775D01*
X689484Y328025D01*
G01X691234Y329333D02*
X691526Y329583D01*
X691692Y329917D01*
X691734Y330292D01*
X691692Y330625D01*
X691484Y330958D01*
X691234Y331167D01*
X690984Y331208D01*
X690692Y331125D01*
X690484Y330833D01*
X690401Y330542D01*
Y330167D01*
G01Y330542D02*
X690276Y330792D01*
X690067Y331000D01*
X689817Y331083D01*
X689567Y331000D01*
X689359Y330792D01*
X689234Y330417D01*
X689276Y330042D01*
X689442Y329667D01*
G01X689234Y333350D02*
X689317Y333017D01*
X689526Y332767D01*
X689776Y332600D01*
X690109Y332475D01*
X690484Y332433D01*
X690859Y332475D01*
X691192Y332600D01*
X691442Y332767D01*
X691651Y333017D01*
X691734Y333350D01*
X691651Y333683D01*
X691442Y333933D01*
X691192Y334100D01*
X690859Y334225D01*
X690484Y334267D01*
X690109Y334225D01*
X689776Y334100D01*
X689526Y333933D01*
X689317Y333683D01*
X689234Y333350D01*
G01X700054Y320892D02*
Y323392D01*
X701054D01*
X701387Y323267D01*
X701637Y322975D01*
X701720Y322642D01*
X701637Y322309D01*
X701429Y322059D01*
X701054Y321934D01*
X700054D01*
G01X704237Y322142D02*
X705070D01*
Y321392D01*
X704820Y321142D01*
X704529Y320975D01*
X704112Y320892D01*
X703695Y320975D01*
X703404Y321142D01*
X703154Y321392D01*
X702987Y321684D01*
X702904Y322017D01*
Y322309D01*
X702987Y322559D01*
X703154Y322850D01*
X703404Y323100D01*
X703654Y323267D01*
X703987Y323392D01*
X704279D01*
X704612Y323309D01*
X704862Y323142D01*
G01X706295Y322975D02*
X706545Y323225D01*
X706837Y323350D01*
X707170Y323392D01*
X707587Y323309D01*
X707879Y323100D01*
X707962Y322850D01*
X707920Y322600D01*
X707754Y322392D01*
X706920Y321975D01*
X706545Y321684D01*
X706295Y321267D01*
X706212Y320892D01*
X707962D01*
G01X710187D02*
X710479Y320934D01*
X710812Y321059D01*
X711020Y321267D01*
X711104Y321559D01*
X711020Y321850D01*
X710770Y322100D01*
X710395Y322225D01*
X709979D01*
X709729Y322309D01*
X709520Y322517D01*
X709437Y322809D01*
X709562Y323100D01*
X709854Y323309D01*
X710187Y323392D01*
X710520Y323309D01*
X710812Y323100D01*
X710937Y322809D01*
X710854Y322517D01*
X710645Y322309D01*
X710395Y322225D01*
X709979D01*
X709604Y322100D01*
X709354Y321850D01*
X709270Y321559D01*
X709354Y321267D01*
X709562Y321059D01*
X709895Y320934D01*
X710187Y320892D01*
G01X697674Y367186D02*
Y364686D01*
G01X696716Y367186D02*
X698632D01*
G01X699941Y364686D02*
Y367186D01*
X700941D01*
X701274Y367061D01*
X701524Y366769D01*
X701607Y366436D01*
X701524Y366103D01*
X701316Y365853D01*
X700941Y365728D01*
X699941D01*
G01X703791Y364686D02*
X703874Y365228D01*
X703999Y365686D01*
X704166Y366103D01*
X704374Y366561D01*
X704707Y367186D01*
X703041D01*
G01X706182Y365728D02*
X706474Y366019D01*
X706724Y366186D01*
X707057Y366269D01*
X707349Y366186D01*
X707557Y366019D01*
X707724Y365769D01*
X707766Y365478D01*
X707724Y365228D01*
X707557Y364978D01*
X707307Y364769D01*
X707016Y364686D01*
X706682Y364769D01*
X706391Y365019D01*
X706224Y365394D01*
X706182Y365811D01*
X706266Y366353D01*
X706391Y366644D01*
X706599Y366936D01*
X706891Y367144D01*
X707182Y367186D01*
X707474Y367103D01*
X707682Y366894D01*
G01X685850Y363200D02*
Y360700D01*
G01X684892Y363200D02*
X686808D01*
G01X688117Y360700D02*
Y363200D01*
X689117D01*
X689450Y363075D01*
X689700Y362783D01*
X689783Y362450D01*
X689700Y362117D01*
X689492Y361867D01*
X689117Y361742D01*
X688117D01*
G01X691967Y360700D02*
X692050Y361242D01*
X692175Y361700D01*
X692342Y362117D01*
X692550Y362575D01*
X692883Y363200D01*
X691217D01*
G01X694233Y361075D02*
X694483Y360867D01*
X694775Y360742D01*
X695150Y360700D01*
X695525Y360783D01*
X695817Y360950D01*
X696025Y361242D01*
X696067Y361575D01*
X695983Y361908D01*
X695775Y362117D01*
X695483Y362283D01*
X695192Y362325D01*
X694900Y362283D01*
X694525Y362117D01*
X694650Y363200D01*
X695775D01*
G01X685850Y371000D02*
Y368500D01*
G01X684892Y371000D02*
X686808D01*
G01X688117Y368500D02*
Y371000D01*
X689117D01*
X689450Y370875D01*
X689700Y370583D01*
X689783Y370250D01*
X689700Y369917D01*
X689492Y369667D01*
X689117Y369542D01*
X688117D01*
G01X691967Y368500D02*
X692050Y369042D01*
X692175Y369500D01*
X692342Y369917D01*
X692550Y370375D01*
X692883Y371000D01*
X691217D01*
G01X695650Y368500D02*
Y371000D01*
X694108Y369208D01*
X696192D01*
G01X685950Y350500D02*
Y348000D01*
G01X684992Y350500D02*
X686908D01*
G01X688217Y348000D02*
Y350500D01*
X689217D01*
X689550Y350375D01*
X689800Y350083D01*
X689883Y349750D01*
X689800Y349417D01*
X689592Y349167D01*
X689217Y349042D01*
X688217D01*
G01X692067Y348000D02*
X692150Y348542D01*
X692275Y349000D01*
X692442Y349417D01*
X692650Y349875D01*
X692983Y350500D01*
X691317D01*
G01X695250Y348000D02*
Y350500D01*
X694750Y350000D01*
G01Y348000D02*
X695750D01*
G01X685067Y372500D02*
Y375000D01*
X686108D01*
X686442Y374875D01*
X686650Y374708D01*
X686733Y374375D01*
X686650Y374042D01*
X686400Y373833D01*
X686108Y373708D01*
X685067D01*
G01X686108D02*
X686733Y372500D01*
G01X688083Y372875D02*
X688333Y372667D01*
X688625Y372542D01*
X689000Y372500D01*
X689375Y372583D01*
X689667Y372750D01*
X689875Y373042D01*
X689917Y373375D01*
X689833Y373708D01*
X689625Y373917D01*
X689333Y374083D01*
X689042Y374125D01*
X688750Y374083D01*
X688375Y373917D01*
X688500Y375000D01*
X689625D01*
G01X691392Y372792D02*
X691683Y372583D01*
X692017Y372500D01*
X692350Y372583D01*
X692642Y372833D01*
X692850Y373208D01*
X692933Y373583D01*
Y374042D01*
X692850Y374417D01*
X692642Y374750D01*
X692392Y374917D01*
X692100Y375000D01*
X691767Y374917D01*
X691517Y374750D01*
X691350Y374500D01*
X691267Y374167D01*
X691350Y373875D01*
X691558Y373583D01*
X691808Y373417D01*
X692100Y373375D01*
X692433Y373458D01*
X692683Y373667D01*
X692933Y374042D01*
G01X673910Y814510D02*
X673785Y814260D01*
X673702Y813968D01*
Y813635D01*
X673827Y813260D01*
X674035Y812968D01*
X674285Y812760D01*
X674702Y812593D01*
X675077Y812551D01*
X675452Y812635D01*
X675702Y812760D01*
X675952Y813010D01*
X676119Y813301D01*
X676202Y813593D01*
Y813885D01*
X676119Y814176D01*
X675994Y814426D01*
X675827Y814635D01*
G01X676202Y816693D02*
X673702D01*
X674202Y816193D01*
G01X676202D02*
Y817193D01*
G01Y820293D02*
X673702D01*
X675494Y818751D01*
Y820835D01*
G01X676202Y822893D02*
X673702D01*
X674202Y822393D01*
G01X676202D02*
Y823393D01*
G01X686509Y814510D02*
X686384Y814260D01*
X686301Y813968D01*
Y813635D01*
X686426Y813260D01*
X686634Y812968D01*
X686884Y812760D01*
X687301Y812593D01*
X687676Y812551D01*
X688051Y812635D01*
X688301Y812760D01*
X688551Y813010D01*
X688718Y813301D01*
X688801Y813593D01*
Y813885D01*
X688718Y814176D01*
X688593Y814426D01*
X688426Y814635D01*
G01X688801Y816693D02*
X686301D01*
X686801Y816193D01*
G01X688801D02*
Y817193D01*
G01X688301Y818876D02*
X688593Y819126D01*
X688759Y819460D01*
X688801Y819835D01*
X688759Y820168D01*
X688551Y820501D01*
X688301Y820710D01*
X688051Y820751D01*
X687759Y820668D01*
X687551Y820376D01*
X687468Y820085D01*
Y819710D01*
G01Y820085D02*
X687343Y820335D01*
X687134Y820543D01*
X686884Y820626D01*
X686634Y820543D01*
X686426Y820335D01*
X686301Y819960D01*
X686343Y819585D01*
X686509Y819210D01*
G01X688509Y822185D02*
X688718Y822476D01*
X688801Y822810D01*
X688718Y823143D01*
X688468Y823435D01*
X688093Y823643D01*
X687718Y823726D01*
X687259D01*
X686884Y823643D01*
X686551Y823435D01*
X686384Y823185D01*
X686301Y822893D01*
X686384Y822560D01*
X686551Y822310D01*
X686801Y822143D01*
X687134Y822060D01*
X687426Y822143D01*
X687718Y822351D01*
X687884Y822601D01*
X687926Y822893D01*
X687843Y823226D01*
X687634Y823476D01*
X687259Y823726D01*
G01X682509Y814510D02*
X682384Y814260D01*
X682301Y813968D01*
Y813635D01*
X682426Y813260D01*
X682634Y812968D01*
X682884Y812760D01*
X683301Y812593D01*
X683676Y812551D01*
X684051Y812635D01*
X684301Y812760D01*
X684551Y813010D01*
X684718Y813301D01*
X684801Y813593D01*
Y813885D01*
X684718Y814176D01*
X684593Y814426D01*
X684426Y814635D01*
G01X684801Y816693D02*
X682301D01*
X682801Y816193D01*
G01X684801D02*
Y817193D01*
G01X684301Y818876D02*
X684593Y819126D01*
X684759Y819460D01*
X684801Y819835D01*
X684759Y820168D01*
X684551Y820501D01*
X684301Y820710D01*
X684051Y820751D01*
X683759Y820668D01*
X683551Y820376D01*
X683468Y820085D01*
Y819710D01*
G01Y820085D02*
X683343Y820335D01*
X683134Y820543D01*
X682884Y820626D01*
X682634Y820543D01*
X682426Y820335D01*
X682301Y819960D01*
X682343Y819585D01*
X682509Y819210D01*
G01X684801Y822893D02*
X684759Y823185D01*
X684634Y823518D01*
X684426Y823726D01*
X684134Y823810D01*
X683843Y823726D01*
X683593Y823476D01*
X683468Y823101D01*
Y822685D01*
X683384Y822435D01*
X683176Y822226D01*
X682884Y822143D01*
X682593Y822268D01*
X682384Y822560D01*
X682301Y822893D01*
X682384Y823226D01*
X682593Y823518D01*
X682884Y823643D01*
X683176Y823560D01*
X683384Y823351D01*
X683468Y823101D01*
Y822685D01*
X683593Y822310D01*
X683843Y822060D01*
X684134Y821976D01*
X684426Y822060D01*
X684634Y822268D01*
X684759Y822601D01*
X684801Y822893D01*
G01X699107Y814510D02*
X698982Y814260D01*
X698899Y813968D01*
Y813635D01*
X699024Y813260D01*
X699232Y812968D01*
X699482Y812760D01*
X699899Y812593D01*
X700274Y812551D01*
X700649Y812635D01*
X700899Y812760D01*
X701149Y813010D01*
X701316Y813301D01*
X701399Y813593D01*
Y813885D01*
X701316Y814176D01*
X701191Y814426D01*
X701024Y814635D01*
G01X701399Y816693D02*
X698899D01*
X699399Y816193D01*
G01X701399D02*
Y817193D01*
G01X700899Y818876D02*
X701191Y819126D01*
X701357Y819460D01*
X701399Y819835D01*
X701357Y820168D01*
X701149Y820501D01*
X700899Y820710D01*
X700649Y820751D01*
X700357Y820668D01*
X700149Y820376D01*
X700066Y820085D01*
Y819710D01*
G01Y820085D02*
X699941Y820335D01*
X699732Y820543D01*
X699482Y820626D01*
X699232Y820543D01*
X699024Y820335D01*
X698899Y819960D01*
X698941Y819585D01*
X699107Y819210D01*
G01X701399Y822810D02*
X700857Y822893D01*
X700399Y823018D01*
X699982Y823185D01*
X699524Y823393D01*
X698899Y823726D01*
Y822060D01*
G01X695107Y814510D02*
X694982Y814260D01*
X694899Y813968D01*
Y813635D01*
X695024Y813260D01*
X695232Y812968D01*
X695482Y812760D01*
X695899Y812593D01*
X696274Y812551D01*
X696649Y812635D01*
X696899Y812760D01*
X697149Y813010D01*
X697316Y813301D01*
X697399Y813593D01*
Y813885D01*
X697316Y814176D01*
X697191Y814426D01*
X697024Y814635D01*
G01X697399Y816693D02*
X694899D01*
X695399Y816193D01*
G01X697399D02*
Y817193D01*
G01X695316Y819001D02*
X695066Y819251D01*
X694941Y819543D01*
X694899Y819876D01*
X694982Y820293D01*
X695191Y820585D01*
X695441Y820668D01*
X695691Y820626D01*
X695899Y820460D01*
X696316Y819626D01*
X696607Y819251D01*
X697024Y819001D01*
X697399Y818918D01*
Y820668D01*
G01Y822893D02*
X697357Y823185D01*
X697232Y823518D01*
X697024Y823726D01*
X696732Y823810D01*
X696441Y823726D01*
X696191Y823476D01*
X696066Y823101D01*
Y822685D01*
X695982Y822435D01*
X695774Y822226D01*
X695482Y822143D01*
X695191Y822268D01*
X694982Y822560D01*
X694899Y822893D01*
X694982Y823226D01*
X695191Y823518D01*
X695482Y823643D01*
X695774Y823560D01*
X695982Y823351D01*
X696066Y823101D01*
Y822685D01*
X696191Y822310D01*
X696441Y822060D01*
X696732Y821976D01*
X697024Y822060D01*
X697232Y822268D01*
X697357Y822601D01*
X697399Y822893D01*
G01X720302Y8724D02*
X716302D01*
Y1324D01*
G01X727913Y380D02*
Y4380D01*
X720513D01*
G01X709460Y-5703D02*
X706960D01*
Y-4662D01*
X707085Y-4328D01*
X707252Y-4120D01*
X707585Y-4037D01*
X707918Y-4120D01*
X708127Y-4370D01*
X708252Y-4662D01*
Y-5703D01*
G01Y-4662D02*
X709460Y-4037D01*
G01X707377Y-2562D02*
X707127Y-2312D01*
X707002Y-2020D01*
X706960Y-1687D01*
X707043Y-1270D01*
X707252Y-978D01*
X707502Y-895D01*
X707752Y-937D01*
X707960Y-1103D01*
X708377Y-1937D01*
X708668Y-2312D01*
X709085Y-2562D01*
X709460Y-2645D01*
Y-895D01*
G01X709168Y622D02*
X709377Y913D01*
X709460Y1247D01*
X709377Y1580D01*
X709127Y1872D01*
X708752Y2080D01*
X708377Y2163D01*
X707918D01*
X707543Y2080D01*
X707210Y1872D01*
X707043Y1622D01*
X706960Y1330D01*
X707043Y997D01*
X707210Y747D01*
X707460Y580D01*
X707793Y497D01*
X708085Y580D01*
X708377Y788D01*
X708543Y1038D01*
X708585Y1330D01*
X708502Y1663D01*
X708293Y1913D01*
X707918Y2163D01*
G01X708960Y3513D02*
X709252Y3763D01*
X709418Y4097D01*
X709460Y4472D01*
X709418Y4805D01*
X709210Y5138D01*
X708960Y5347D01*
X708710Y5388D01*
X708418Y5305D01*
X708210Y5013D01*
X708127Y4722D01*
Y4347D01*
G01Y4722D02*
X708002Y4972D01*
X707793Y5180D01*
X707543Y5263D01*
X707293Y5180D01*
X707085Y4972D01*
X706960Y4597D01*
X707002Y4222D01*
X707168Y3847D01*
G01X709085Y6613D02*
X709293Y6863D01*
X709418Y7155D01*
X709460Y7530D01*
X709377Y7905D01*
X709210Y8197D01*
X708918Y8405D01*
X708585Y8447D01*
X708252Y8363D01*
X708043Y8155D01*
X707877Y7863D01*
X707835Y7572D01*
X707877Y7280D01*
X708043Y6905D01*
X706960Y7030D01*
Y8155D01*
G01X730752Y-12208D02*
X731085Y-12416D01*
X731460Y-12541D01*
X731794D01*
X732127Y-12416D01*
X732377Y-12208D01*
X732502Y-11916D01*
X732419Y-11624D01*
X732210Y-11374D01*
X731835Y-11208D01*
X731335Y-11124D01*
X731044Y-10958D01*
X730919Y-10666D01*
X731002Y-10374D01*
X731210Y-10166D01*
X731502Y-10041D01*
X731794D01*
X732085Y-10124D01*
X732335Y-10333D01*
G01X733894Y-10041D02*
Y-12541D01*
X735560D01*
G01X738660D02*
X736994D01*
Y-10041D01*
X738660D01*
G01X737994Y-11249D02*
X736994D01*
G01X740010Y-12541D02*
Y-10041D01*
X740844D01*
X741177Y-10166D01*
X741427Y-10333D01*
X741635Y-10583D01*
X741802Y-10874D01*
X741844Y-11291D01*
X741802Y-11708D01*
X741635Y-11999D01*
X741427Y-12249D01*
X741177Y-12416D01*
X740844Y-12541D01*
X740010D01*
G01X743235Y-10458D02*
X743485Y-10208D01*
X743777Y-10083D01*
X744110Y-10041D01*
X744527Y-10124D01*
X744819Y-10333D01*
X744902Y-10583D01*
X744860Y-10833D01*
X744694Y-11041D01*
X743860Y-11458D01*
X743485Y-11749D01*
X743235Y-12166D01*
X743152Y-12541D01*
X744902D01*
G01X747127D02*
X747419Y-12499D01*
X747752Y-12374D01*
X747960Y-12166D01*
X748044Y-11874D01*
X747960Y-11583D01*
X747710Y-11333D01*
X747335Y-11208D01*
X746919D01*
X746669Y-11124D01*
X746460Y-10916D01*
X746377Y-10624D01*
X746502Y-10333D01*
X746794Y-10124D01*
X747127Y-10041D01*
X747460Y-10124D01*
X747752Y-10333D01*
X747877Y-10624D01*
X747794Y-10916D01*
X747585Y-11124D01*
X747335Y-11208D01*
X746919D01*
X746544Y-11333D01*
X746294Y-11583D01*
X746210Y-11874D01*
X746294Y-12166D01*
X746502Y-12374D01*
X746835Y-12499D01*
X747127Y-12541D01*
G01X726163Y-6250D02*
X715363D01*
Y-1050D01*
X726163D01*
Y-6250D01*
G01X730132Y6506D02*
Y-6494D01*
G01D02*
X744132D01*
G01Y6506D02*
X730132D01*
G01X716834Y33983D02*
X718626D01*
X719001Y34150D01*
X719251Y34483D01*
X719334Y34900D01*
X719251Y35317D01*
X719001Y35650D01*
X718626Y35817D01*
X716834D01*
G01X718834Y37083D02*
X719126Y37333D01*
X719292Y37667D01*
X719334Y38042D01*
X719292Y38375D01*
X719084Y38708D01*
X718834Y38917D01*
X718584Y38958D01*
X718292Y38875D01*
X718084Y38583D01*
X718001Y38292D01*
Y37917D01*
G01Y38292D02*
X717876Y38542D01*
X717667Y38750D01*
X717417Y38833D01*
X717167Y38750D01*
X716959Y38542D01*
X716834Y38167D01*
X716876Y37792D01*
X717042Y37417D01*
G01X719334Y41100D02*
X719292Y41392D01*
X719167Y41725D01*
X718959Y41933D01*
X718667Y42017D01*
X718376Y41933D01*
X718126Y41683D01*
X718001Y41308D01*
Y40892D01*
X717917Y40642D01*
X717709Y40433D01*
X717417Y40350D01*
X717126Y40475D01*
X716917Y40767D01*
X716834Y41100D01*
X716917Y41433D01*
X717126Y41725D01*
X717417Y41850D01*
X717709Y41767D01*
X717917Y41558D01*
X718001Y41308D01*
Y40892D01*
X718126Y40517D01*
X718376Y40267D01*
X718667Y40183D01*
X718959Y40267D01*
X719167Y40475D01*
X719292Y40808D01*
X719334Y41100D01*
G01X731100Y16000D02*
Y12000D01*
X738500D01*
G01X738463Y29882D02*
Y33882D01*
X731063D01*
G01X714334Y34017D02*
X711834D01*
Y35058D01*
X711959Y35392D01*
X712126Y35600D01*
X712459Y35683D01*
X712792Y35600D01*
X713001Y35350D01*
X713126Y35058D01*
Y34017D01*
G01Y35058D02*
X714334Y35683D01*
G01X713959Y37033D02*
X714167Y37283D01*
X714292Y37575D01*
X714334Y37950D01*
X714251Y38325D01*
X714084Y38617D01*
X713792Y38825D01*
X713459Y38867D01*
X713126Y38783D01*
X712917Y38575D01*
X712751Y38283D01*
X712709Y37992D01*
X712751Y37700D01*
X712917Y37325D01*
X711834Y37450D01*
Y38575D01*
G01X712251Y40258D02*
X712001Y40508D01*
X711876Y40800D01*
X711834Y41133D01*
X711917Y41550D01*
X712126Y41842D01*
X712376Y41925D01*
X712626Y41883D01*
X712834Y41717D01*
X713251Y40883D01*
X713542Y40508D01*
X713959Y40258D01*
X714334Y40175D01*
Y41925D01*
G01X714042Y43442D02*
X714251Y43733D01*
X714334Y44067D01*
X714251Y44400D01*
X714001Y44692D01*
X713626Y44900D01*
X713251Y44983D01*
X712792D01*
X712417Y44900D01*
X712084Y44692D01*
X711917Y44442D01*
X711834Y44150D01*
X711917Y43817D01*
X712084Y43567D01*
X712334Y43400D01*
X712667Y43317D01*
X712959Y43400D01*
X713251Y43608D01*
X713417Y43858D01*
X713459Y44150D01*
X713376Y44483D01*
X713167Y44733D01*
X712792Y44983D01*
G01X738500Y29700D02*
X734500D01*
Y22300D01*
G01X715375Y29902D02*
X711375D01*
Y22502D01*
G01X722705Y12964D02*
Y16964D01*
X715305D01*
G01X726359Y26613D02*
Y30613D01*
X718959D01*
G01X726820Y20440D02*
X722820D01*
Y13040D01*
G01X722700Y20370D02*
X718700D01*
Y12970D01*
G01X730960Y20530D02*
X726960D01*
Y13130D01*
G01X709334Y20517D02*
X706834D01*
Y21558D01*
X706959Y21892D01*
X707126Y22100D01*
X707459Y22183D01*
X707792Y22100D01*
X708001Y21850D01*
X708126Y21558D01*
Y20517D01*
G01Y21558D02*
X709334Y22183D01*
G01X709042Y23742D02*
X709251Y24033D01*
X709334Y24367D01*
X709251Y24700D01*
X709001Y24992D01*
X708626Y25200D01*
X708251Y25283D01*
X707792D01*
X707417Y25200D01*
X707084Y24992D01*
X706917Y24742D01*
X706834Y24450D01*
X706917Y24117D01*
X707084Y23867D01*
X707334Y23700D01*
X707667Y23617D01*
X707959Y23700D01*
X708251Y23908D01*
X708417Y24158D01*
X708459Y24450D01*
X708376Y24783D01*
X708167Y25033D01*
X707792Y25283D01*
G01X709334Y28050D02*
X706834D01*
X708626Y26508D01*
Y28592D01*
G01X708834Y29733D02*
X709126Y29983D01*
X709292Y30317D01*
X709334Y30692D01*
X709292Y31025D01*
X709084Y31358D01*
X708834Y31567D01*
X708584Y31608D01*
X708292Y31525D01*
X708084Y31233D01*
X708001Y30942D01*
Y30567D01*
G01Y30942D02*
X707876Y31192D01*
X707667Y31400D01*
X707417Y31483D01*
X707167Y31400D01*
X706959Y31192D01*
X706834Y30817D01*
X706876Y30442D01*
X707042Y30067D01*
G01X736500Y51000D02*
Y38000D01*
G01D02*
X750500D01*
G01X727858Y75783D02*
X728108Y76033D01*
X728400Y76158D01*
X728733Y76200D01*
X729150Y76117D01*
X729442Y75908D01*
X729525Y75658D01*
X729483Y75408D01*
X729317Y75200D01*
X728483Y74783D01*
X728108Y74492D01*
X727858Y74075D01*
X727775Y73700D01*
X729525D01*
G01X731125Y75367D02*
X732375Y73700D01*
G01Y75367D02*
X731125Y73700D01*
G01X734850D02*
X735142Y73742D01*
X735475Y73867D01*
X735683Y74075D01*
X735767Y74367D01*
X735683Y74658D01*
X735433Y74908D01*
X735058Y75033D01*
X734642D01*
X734392Y75117D01*
X734183Y75325D01*
X734100Y75617D01*
X734225Y75908D01*
X734517Y76117D01*
X734850Y76200D01*
X735183Y76117D01*
X735475Y75908D01*
X735600Y75617D01*
X735517Y75325D01*
X735308Y75117D01*
X735058Y75033D01*
X734642D01*
X734267Y74908D01*
X734017Y74658D01*
X733933Y74367D01*
X734017Y74075D01*
X734225Y73867D01*
X734558Y73742D01*
X734850Y73700D01*
G01X706150Y73500D02*
Y76000D01*
X705650Y75500D01*
G01Y73500D02*
X706650D01*
G01X708375D02*
X710125Y76000D01*
G01X708375D02*
X710125Y73500D01*
G01X712350D02*
Y76000D01*
X711850Y75500D01*
G01Y73500D02*
X712850D01*
G01X714658Y74542D02*
X714950Y74833D01*
X715200Y75000D01*
X715533Y75083D01*
X715825Y75000D01*
X716033Y74833D01*
X716200Y74583D01*
X716242Y74292D01*
X716200Y74042D01*
X716033Y73792D01*
X715783Y73583D01*
X715492Y73500D01*
X715158Y73583D01*
X714867Y73833D01*
X714700Y74208D01*
X714658Y74625D01*
X714742Y75167D01*
X714867Y75458D01*
X715075Y75750D01*
X715367Y75958D01*
X715658Y76000D01*
X715950Y75917D01*
X716158Y75708D01*
G01X740330Y61910D02*
Y65910D01*
X732930D01*
G01X719700Y62000D02*
Y66000D01*
X712300D01*
G01X735390Y51147D02*
X732890D01*
Y52188D01*
X733015Y52522D01*
X733182Y52730D01*
X733515Y52813D01*
X733848Y52730D01*
X734057Y52480D01*
X734182Y52188D01*
Y51147D01*
G01Y52188D02*
X735390Y52813D01*
G01X733307Y54288D02*
X733057Y54538D01*
X732932Y54830D01*
X732890Y55163D01*
X732973Y55580D01*
X733182Y55872D01*
X733432Y55955D01*
X733682Y55913D01*
X733890Y55747D01*
X734307Y54913D01*
X734598Y54538D01*
X735015Y54288D01*
X735390Y54205D01*
Y55955D01*
G01X735015Y57263D02*
X735223Y57513D01*
X735348Y57805D01*
X735390Y58180D01*
X735307Y58555D01*
X735140Y58847D01*
X734848Y59055D01*
X734515Y59097D01*
X734182Y59013D01*
X733973Y58805D01*
X733807Y58513D01*
X733765Y58222D01*
X733807Y57930D01*
X733973Y57555D01*
X732890Y57680D01*
Y58805D01*
G01X733307Y60488D02*
X733057Y60738D01*
X732932Y61030D01*
X732890Y61363D01*
X732973Y61780D01*
X733182Y62072D01*
X733432Y62155D01*
X733682Y62113D01*
X733890Y61947D01*
X734307Y61113D01*
X734598Y60738D01*
X735015Y60488D01*
X735390Y60405D01*
Y62155D01*
G01X722890Y54430D02*
X726890D01*
Y61830D01*
G01X731340Y51157D02*
X728840D01*
Y52198D01*
X728965Y52532D01*
X729132Y52740D01*
X729465Y52823D01*
X729798Y52740D01*
X730007Y52490D01*
X730132Y52198D01*
Y51157D01*
G01Y52198D02*
X731340Y52823D01*
G01X729257Y54298D02*
X729007Y54548D01*
X728882Y54840D01*
X728840Y55173D01*
X728923Y55590D01*
X729132Y55882D01*
X729382Y55965D01*
X729632Y55923D01*
X729840Y55757D01*
X730257Y54923D01*
X730548Y54548D01*
X730965Y54298D01*
X731340Y54215D01*
Y55965D01*
G01Y58190D02*
X728840D01*
X729340Y57690D01*
G01X731340D02*
Y58690D01*
G01Y61290D02*
X728840D01*
X729340Y60790D01*
G01X731340D02*
Y61790D01*
G01X722840Y61840D02*
X718840D01*
Y54440D01*
G01X721127Y46360D02*
Y48860D01*
X722168D01*
X722502Y48735D01*
X722710Y48568D01*
X722793Y48235D01*
X722710Y47902D01*
X722460Y47693D01*
X722168Y47568D01*
X721127D01*
G01X722168D02*
X722793Y46360D01*
G01X724143Y46860D02*
X724393Y46568D01*
X724727Y46402D01*
X725102Y46360D01*
X725435Y46402D01*
X725768Y46610D01*
X725977Y46860D01*
X726018Y47110D01*
X725935Y47402D01*
X725643Y47610D01*
X725352Y47693D01*
X724977D01*
G01X725352D02*
X725602Y47818D01*
X725810Y48027D01*
X725893Y48277D01*
X725810Y48527D01*
X725602Y48735D01*
X725227Y48860D01*
X724852Y48818D01*
X724477Y48652D01*
G01X728160Y48860D02*
X727827Y48777D01*
X727577Y48568D01*
X727410Y48318D01*
X727285Y47985D01*
X727243Y47610D01*
X727285Y47235D01*
X727410Y46902D01*
X727577Y46652D01*
X727827Y46443D01*
X728160Y46360D01*
X728493Y46443D01*
X728743Y46652D01*
X728910Y46902D01*
X729035Y47235D01*
X729077Y47610D01*
X729035Y47985D01*
X728910Y48318D01*
X728743Y48568D01*
X728493Y48777D01*
X728160Y48860D01*
G01X731760Y46360D02*
Y48860D01*
X730218Y47068D01*
X732302D01*
G01X718810Y53860D02*
Y57860D01*
X711410D01*
G01X721127Y42296D02*
Y44796D01*
X722168D01*
X722502Y44671D01*
X722710Y44504D01*
X722793Y44171D01*
X722710Y43838D01*
X722460Y43629D01*
X722168Y43504D01*
X721127D01*
G01X722168D02*
X722793Y42296D01*
G01X724268Y44379D02*
X724518Y44629D01*
X724810Y44754D01*
X725143Y44796D01*
X725560Y44713D01*
X725852Y44504D01*
X725935Y44254D01*
X725893Y44004D01*
X725727Y43796D01*
X724893Y43379D01*
X724518Y43088D01*
X724268Y42671D01*
X724185Y42296D01*
X725935D01*
G01X727452Y42588D02*
X727743Y42379D01*
X728077Y42296D01*
X728410Y42379D01*
X728702Y42629D01*
X728910Y43004D01*
X728993Y43379D01*
Y43838D01*
X728910Y44213D01*
X728702Y44546D01*
X728452Y44713D01*
X728160Y44796D01*
X727827Y44713D01*
X727577Y44546D01*
X727410Y44296D01*
X727327Y43963D01*
X727410Y43671D01*
X727618Y43379D01*
X727868Y43213D01*
X728160Y43171D01*
X728493Y43254D01*
X728743Y43463D01*
X728993Y43838D01*
G01X730468Y44379D02*
X730718Y44629D01*
X731010Y44754D01*
X731343Y44796D01*
X731760Y44713D01*
X732052Y44504D01*
X732135Y44254D01*
X732093Y44004D01*
X731927Y43796D01*
X731093Y43379D01*
X730718Y43088D01*
X730468Y42671D01*
X730385Y42296D01*
X732135D01*
G01X718810Y49796D02*
Y53796D01*
X711410D01*
G01X725309Y71498D02*
X736109D01*
Y66298D01*
X725309D01*
Y71498D01*
G01X705624D02*
X716424D01*
Y66298D01*
X705624D01*
Y71498D01*
G01X739400Y52166D02*
X739067Y52208D01*
X738775Y52374D01*
X738525Y52624D01*
X738358Y52916D01*
X738275Y53249D01*
Y53583D01*
X738358Y53916D01*
X738525Y54208D01*
X738775Y54458D01*
X739067Y54624D01*
X739400Y54666D01*
X739733Y54624D01*
X740025Y54458D01*
X740275Y54208D01*
X740442Y53916D01*
X740525Y53583D01*
Y53249D01*
X740442Y52916D01*
X740275Y52624D01*
X740025Y52374D01*
X739733Y52208D01*
X739400Y52166D01*
G01X739733Y52833D02*
X740233Y52166D01*
G01X742500D02*
Y54666D01*
X742000Y54166D01*
G01Y52166D02*
X743000D01*
G01X744683Y52666D02*
X744933Y52374D01*
X745267Y52208D01*
X745642Y52166D01*
X745975Y52208D01*
X746308Y52416D01*
X746517Y52666D01*
X746558Y52916D01*
X746475Y53208D01*
X746183Y53416D01*
X745892Y53499D01*
X745517D01*
G01X745892D02*
X746142Y53624D01*
X746350Y53833D01*
X746433Y54083D01*
X746350Y54333D01*
X746142Y54541D01*
X745767Y54666D01*
X745392Y54624D01*
X745017Y54458D01*
G01X750500Y51000D02*
X736500D01*
G01X725825Y80400D02*
X726158Y80192D01*
X726533Y80067D01*
X726867D01*
X727200Y80192D01*
X727450Y80400D01*
X727575Y80692D01*
X727492Y80984D01*
X727283Y81234D01*
X726908Y81400D01*
X726408Y81484D01*
X726117Y81650D01*
X725992Y81942D01*
X726075Y82234D01*
X726283Y82442D01*
X726575Y82567D01*
X726867D01*
X727158Y82484D01*
X727408Y82275D01*
G01X728967Y80067D02*
Y82567D01*
X730008D01*
X730342Y82442D01*
X730550Y82275D01*
X730633Y81942D01*
X730550Y81609D01*
X730300Y81400D01*
X730008Y81275D01*
X728967D01*
G01X730008D02*
X730633Y80067D01*
G01X732817D02*
X732900Y80609D01*
X733025Y81067D01*
X733192Y81484D01*
X733400Y81942D01*
X733733Y82567D01*
X732067D01*
G01X736000Y80067D02*
Y82567D01*
X735500Y82067D01*
G01Y80067D02*
X736500D01*
G01X738392Y80359D02*
X738683Y80150D01*
X739017Y80067D01*
X739350Y80150D01*
X739642Y80400D01*
X739850Y80775D01*
X739933Y81150D01*
Y81609D01*
X739850Y81984D01*
X739642Y82317D01*
X739392Y82484D01*
X739100Y82567D01*
X738767Y82484D01*
X738517Y82317D01*
X738350Y82067D01*
X738267Y81734D01*
X738350Y81442D01*
X738558Y81150D01*
X738808Y80984D01*
X739100Y80942D01*
X739433Y81025D01*
X739683Y81234D01*
X739933Y81609D01*
G01X733380Y111410D02*
Y107410D01*
X740780D01*
G01X725167Y87000D02*
Y84500D01*
X726833D01*
G01X729933D02*
X728267D01*
Y87000D01*
X729933D01*
G01X729267Y85792D02*
X728267D01*
G01X731283Y84500D02*
Y87000D01*
X732117D01*
X732450Y86875D01*
X732700Y86708D01*
X732908Y86458D01*
X733075Y86167D01*
X733117Y85750D01*
X733075Y85333D01*
X732908Y85042D01*
X732700Y84792D01*
X732450Y84625D01*
X732117Y84500D01*
X731283D01*
G01X735300D02*
Y87000D01*
X734800Y86500D01*
G01Y84500D02*
X735800D01*
G01X737692Y84792D02*
X737983Y84583D01*
X738317Y84500D01*
X738650Y84583D01*
X738942Y84833D01*
X739150Y85208D01*
X739233Y85583D01*
Y86042D01*
X739150Y86417D01*
X738942Y86750D01*
X738692Y86917D01*
X738400Y87000D01*
X738067Y86917D01*
X737817Y86750D01*
X737650Y86500D01*
X737567Y86167D01*
X737650Y85875D01*
X737858Y85583D01*
X738108Y85417D01*
X738400Y85375D01*
X738733Y85458D01*
X738983Y85667D01*
X739233Y86042D01*
G01X726117Y134020D02*
Y136520D01*
X727158D01*
X727492Y136395D01*
X727700Y136228D01*
X727783Y135895D01*
X727700Y135562D01*
X727450Y135353D01*
X727158Y135228D01*
X726117D01*
G01X727158D02*
X727783Y134020D01*
G01X729258Y135062D02*
X729550Y135353D01*
X729800Y135520D01*
X730133Y135603D01*
X730425Y135520D01*
X730633Y135353D01*
X730800Y135103D01*
X730842Y134812D01*
X730800Y134562D01*
X730633Y134312D01*
X730383Y134103D01*
X730092Y134020D01*
X729758Y134103D01*
X729467Y134353D01*
X729300Y134728D01*
X729258Y135145D01*
X729342Y135687D01*
X729467Y135978D01*
X729675Y136270D01*
X729967Y136478D01*
X730258Y136520D01*
X730550Y136437D01*
X730758Y136228D01*
G01X732358Y135062D02*
X732650Y135353D01*
X732900Y135520D01*
X733233Y135603D01*
X733525Y135520D01*
X733733Y135353D01*
X733900Y135103D01*
X733942Y134812D01*
X733900Y134562D01*
X733733Y134312D01*
X733483Y134103D01*
X733192Y134020D01*
X732858Y134103D01*
X732567Y134353D01*
X732400Y134728D01*
X732358Y135145D01*
X732442Y135687D01*
X732567Y135978D01*
X732775Y136270D01*
X733067Y136478D01*
X733358Y136520D01*
X733650Y136437D01*
X733858Y136228D01*
G01X735458Y135062D02*
X735750Y135353D01*
X736000Y135520D01*
X736333Y135603D01*
X736625Y135520D01*
X736833Y135353D01*
X737000Y135103D01*
X737042Y134812D01*
X737000Y134562D01*
X736833Y134312D01*
X736583Y134103D01*
X736292Y134020D01*
X735958Y134103D01*
X735667Y134353D01*
X735500Y134728D01*
X735458Y135145D01*
X735542Y135687D01*
X735667Y135978D01*
X735875Y136270D01*
X736167Y136478D01*
X736458Y136520D01*
X736750Y136437D01*
X736958Y136228D01*
G01X733400Y116020D02*
Y112020D01*
X740800D01*
G01X726097Y129410D02*
Y131910D01*
X727138D01*
X727472Y131785D01*
X727680Y131618D01*
X727763Y131285D01*
X727680Y130952D01*
X727430Y130743D01*
X727138Y130618D01*
X726097D01*
G01X727138D02*
X727763Y129410D01*
G01X729238Y130452D02*
X729530Y130743D01*
X729780Y130910D01*
X730113Y130993D01*
X730405Y130910D01*
X730613Y130743D01*
X730780Y130493D01*
X730822Y130202D01*
X730780Y129952D01*
X730613Y129702D01*
X730363Y129493D01*
X730072Y129410D01*
X729738Y129493D01*
X729447Y129743D01*
X729280Y130118D01*
X729238Y130535D01*
X729322Y131077D01*
X729447Y131368D01*
X729655Y131660D01*
X729947Y131868D01*
X730238Y131910D01*
X730530Y131827D01*
X730738Y131618D01*
G01X732213Y129910D02*
X732463Y129618D01*
X732797Y129452D01*
X733172Y129410D01*
X733505Y129452D01*
X733838Y129660D01*
X734047Y129910D01*
X734088Y130160D01*
X734005Y130452D01*
X733713Y130660D01*
X733422Y130743D01*
X733047D01*
G01X733422D02*
X733672Y130868D01*
X733880Y131077D01*
X733963Y131327D01*
X733880Y131577D01*
X733672Y131785D01*
X733297Y131910D01*
X732922Y131868D01*
X732547Y131702D01*
G01X735438Y131493D02*
X735688Y131743D01*
X735980Y131868D01*
X736313Y131910D01*
X736730Y131827D01*
X737022Y131618D01*
X737105Y131368D01*
X737063Y131118D01*
X736897Y130910D01*
X736063Y130493D01*
X735688Y130202D01*
X735438Y129785D01*
X735355Y129410D01*
X737105D01*
G01X729467Y122092D02*
X729217Y122217D01*
X728925Y122300D01*
X728592D01*
X728217Y122175D01*
X727925Y121967D01*
X727717Y121717D01*
X727550Y121300D01*
X727508Y120925D01*
X727592Y120550D01*
X727717Y120300D01*
X727967Y120050D01*
X728258Y119883D01*
X728550Y119800D01*
X728842D01*
X729133Y119883D01*
X729383Y120008D01*
X729592Y120175D01*
G01X731650Y119800D02*
Y122300D01*
X731150Y121800D01*
G01Y119800D02*
X732150D01*
G01X735250D02*
Y122300D01*
X733708Y120508D01*
X735792D01*
G01X736933Y120300D02*
X737183Y120008D01*
X737517Y119842D01*
X737892Y119800D01*
X738225Y119842D01*
X738558Y120050D01*
X738767Y120300D01*
X738808Y120550D01*
X738725Y120842D01*
X738433Y121050D01*
X738142Y121133D01*
X737767D01*
G01X738142D02*
X738392Y121258D01*
X738600Y121467D01*
X738683Y121717D01*
X738600Y121967D01*
X738392Y122175D01*
X738017Y122300D01*
X737642Y122258D01*
X737267Y122092D01*
G01X729267Y126459D02*
X729017Y126584D01*
X728725Y126667D01*
X728392D01*
X728017Y126542D01*
X727725Y126334D01*
X727517Y126084D01*
X727350Y125667D01*
X727308Y125292D01*
X727392Y124917D01*
X727517Y124667D01*
X727767Y124417D01*
X728058Y124250D01*
X728350Y124167D01*
X728642D01*
X728933Y124250D01*
X729183Y124375D01*
X729392Y124542D01*
G01X731450Y124167D02*
Y126667D01*
X730950Y126167D01*
G01Y124167D02*
X731950D01*
G01X735050D02*
Y126667D01*
X733508Y124875D01*
X735592D01*
G01X736858Y126250D02*
X737108Y126500D01*
X737400Y126625D01*
X737733Y126667D01*
X738150Y126584D01*
X738442Y126375D01*
X738525Y126125D01*
X738483Y125875D01*
X738317Y125667D01*
X737483Y125250D01*
X737108Y124959D01*
X736858Y124542D01*
X736775Y124167D01*
X738525D01*
G01X719006Y189324D02*
Y186824D01*
X720672D01*
G01X722147Y188907D02*
X722397Y189157D01*
X722689Y189282D01*
X723022Y189324D01*
X723439Y189241D01*
X723731Y189032D01*
X723814Y188782D01*
X723772Y188532D01*
X723606Y188324D01*
X722772Y187907D01*
X722397Y187616D01*
X722147Y187199D01*
X722064Y186824D01*
X723814D01*
G01X715210Y302663D02*
X715085Y302413D01*
X715002Y302121D01*
Y301788D01*
X715127Y301413D01*
X715335Y301121D01*
X715585Y300913D01*
X716002Y300746D01*
X716377Y300704D01*
X716752Y300788D01*
X717002Y300913D01*
X717252Y301163D01*
X717419Y301454D01*
X717502Y301746D01*
Y302038D01*
X717419Y302329D01*
X717294Y302579D01*
X717127Y302788D01*
G01Y303929D02*
X717335Y304179D01*
X717460Y304471D01*
X717502Y304846D01*
X717419Y305221D01*
X717252Y305513D01*
X716960Y305721D01*
X716627Y305763D01*
X716294Y305679D01*
X716085Y305471D01*
X715919Y305179D01*
X715877Y304888D01*
X715919Y304596D01*
X716085Y304221D01*
X715002Y304346D01*
Y305471D01*
G01X717127Y307029D02*
X717335Y307279D01*
X717460Y307571D01*
X717502Y307946D01*
X717419Y308321D01*
X717252Y308613D01*
X716960Y308821D01*
X716627Y308863D01*
X716294Y308779D01*
X716085Y308571D01*
X715919Y308279D01*
X715877Y307988D01*
X715919Y307696D01*
X716085Y307321D01*
X715002Y307446D01*
Y308571D01*
G01X717502Y311046D02*
X717460Y311338D01*
X717335Y311671D01*
X717127Y311879D01*
X716835Y311963D01*
X716544Y311879D01*
X716294Y311629D01*
X716169Y311254D01*
Y310838D01*
X716085Y310588D01*
X715877Y310379D01*
X715585Y310296D01*
X715294Y310421D01*
X715085Y310713D01*
X715002Y311046D01*
X715085Y311379D01*
X715294Y311671D01*
X715585Y311796D01*
X715877Y311713D01*
X716085Y311504D01*
X716169Y311254D01*
Y310838D01*
X716294Y310463D01*
X716544Y310213D01*
X716835Y310129D01*
X717127Y310213D01*
X717335Y310421D01*
X717460Y310754D01*
X717502Y311046D01*
G01X719210Y302663D02*
X719085Y302413D01*
X719002Y302121D01*
Y301788D01*
X719127Y301413D01*
X719335Y301121D01*
X719585Y300913D01*
X720002Y300746D01*
X720377Y300704D01*
X720752Y300788D01*
X721002Y300913D01*
X721252Y301163D01*
X721419Y301454D01*
X721502Y301746D01*
Y302038D01*
X721419Y302329D01*
X721294Y302579D01*
X721127Y302788D01*
G01Y303929D02*
X721335Y304179D01*
X721460Y304471D01*
X721502Y304846D01*
X721419Y305221D01*
X721252Y305513D01*
X720960Y305721D01*
X720627Y305763D01*
X720294Y305679D01*
X720085Y305471D01*
X719919Y305179D01*
X719877Y304888D01*
X719919Y304596D01*
X720085Y304221D01*
X719002Y304346D01*
Y305471D01*
G01X721127Y307029D02*
X721335Y307279D01*
X721460Y307571D01*
X721502Y307946D01*
X721419Y308321D01*
X721252Y308613D01*
X720960Y308821D01*
X720627Y308863D01*
X720294Y308779D01*
X720085Y308571D01*
X719919Y308279D01*
X719877Y307988D01*
X719919Y307696D01*
X720085Y307321D01*
X719002Y307446D01*
Y308571D01*
G01X721502Y311546D02*
X719002D01*
X720794Y310004D01*
Y312088D01*
G01X723210Y302663D02*
X723085Y302413D01*
X723002Y302121D01*
Y301788D01*
X723127Y301413D01*
X723335Y301121D01*
X723585Y300913D01*
X724002Y300746D01*
X724377Y300704D01*
X724752Y300788D01*
X725002Y300913D01*
X725252Y301163D01*
X725419Y301454D01*
X725502Y301746D01*
Y302038D01*
X725419Y302329D01*
X725294Y302579D01*
X725127Y302788D01*
G01Y303929D02*
X725335Y304179D01*
X725460Y304471D01*
X725502Y304846D01*
X725419Y305221D01*
X725252Y305513D01*
X724960Y305721D01*
X724627Y305763D01*
X724294Y305679D01*
X724085Y305471D01*
X723919Y305179D01*
X723877Y304888D01*
X723919Y304596D01*
X724085Y304221D01*
X723002Y304346D01*
Y305471D01*
G01X725127Y307029D02*
X725335Y307279D01*
X725460Y307571D01*
X725502Y307946D01*
X725419Y308321D01*
X725252Y308613D01*
X724960Y308821D01*
X724627Y308863D01*
X724294Y308779D01*
X724085Y308571D01*
X723919Y308279D01*
X723877Y307988D01*
X723919Y307696D01*
X724085Y307321D01*
X723002Y307446D01*
Y308571D01*
G01X725002Y310129D02*
X725294Y310379D01*
X725460Y310713D01*
X725502Y311088D01*
X725460Y311421D01*
X725252Y311754D01*
X725002Y311963D01*
X724752Y312004D01*
X724460Y311921D01*
X724252Y311629D01*
X724169Y311338D01*
Y310963D01*
G01Y311338D02*
X724044Y311588D01*
X723835Y311796D01*
X723585Y311879D01*
X723335Y311796D01*
X723127Y311588D01*
X723002Y311213D01*
X723044Y310838D01*
X723210Y310463D01*
G01X727210Y302663D02*
X727085Y302413D01*
X727002Y302121D01*
Y301788D01*
X727127Y301413D01*
X727335Y301121D01*
X727585Y300913D01*
X728002Y300746D01*
X728377Y300704D01*
X728752Y300788D01*
X729002Y300913D01*
X729252Y301163D01*
X729419Y301454D01*
X729502Y301746D01*
Y302038D01*
X729419Y302329D01*
X729294Y302579D01*
X729127Y302788D01*
G01Y303929D02*
X729335Y304179D01*
X729460Y304471D01*
X729502Y304846D01*
X729419Y305221D01*
X729252Y305513D01*
X728960Y305721D01*
X728627Y305763D01*
X728294Y305679D01*
X728085Y305471D01*
X727919Y305179D01*
X727877Y304888D01*
X727919Y304596D01*
X728085Y304221D01*
X727002Y304346D01*
Y305471D01*
G01X729127Y307029D02*
X729335Y307279D01*
X729460Y307571D01*
X729502Y307946D01*
X729419Y308321D01*
X729252Y308613D01*
X728960Y308821D01*
X728627Y308863D01*
X728294Y308779D01*
X728085Y308571D01*
X727919Y308279D01*
X727877Y307988D01*
X727919Y307696D01*
X728085Y307321D01*
X727002Y307446D01*
Y308571D01*
G01X727419Y310254D02*
X727169Y310504D01*
X727044Y310796D01*
X727002Y311129D01*
X727085Y311546D01*
X727294Y311838D01*
X727544Y311921D01*
X727794Y311879D01*
X728002Y311713D01*
X728419Y310879D01*
X728710Y310504D01*
X729127Y310254D01*
X729502Y310171D01*
Y311921D01*
G01X731210Y302663D02*
X731085Y302413D01*
X731002Y302121D01*
Y301788D01*
X731127Y301413D01*
X731335Y301121D01*
X731585Y300913D01*
X732002Y300746D01*
X732377Y300704D01*
X732752Y300788D01*
X733002Y300913D01*
X733252Y301163D01*
X733419Y301454D01*
X733502Y301746D01*
Y302038D01*
X733419Y302329D01*
X733294Y302579D01*
X733127Y302788D01*
G01Y303929D02*
X733335Y304179D01*
X733460Y304471D01*
X733502Y304846D01*
X733419Y305221D01*
X733252Y305513D01*
X732960Y305721D01*
X732627Y305763D01*
X732294Y305679D01*
X732085Y305471D01*
X731919Y305179D01*
X731877Y304888D01*
X731919Y304596D01*
X732085Y304221D01*
X731002Y304346D01*
Y305471D01*
G01X733502Y308446D02*
X731002D01*
X732794Y306904D01*
Y308988D01*
G01X733210Y310338D02*
X733419Y310629D01*
X733502Y310963D01*
X733419Y311296D01*
X733169Y311588D01*
X732794Y311796D01*
X732419Y311879D01*
X731960D01*
X731585Y311796D01*
X731252Y311588D01*
X731085Y311338D01*
X731002Y311046D01*
X731085Y310713D01*
X731252Y310463D01*
X731502Y310296D01*
X731835Y310213D01*
X732127Y310296D01*
X732419Y310504D01*
X732585Y310754D01*
X732627Y311046D01*
X732544Y311379D01*
X732335Y311629D01*
X731960Y311879D01*
G01X709400Y429300D02*
X758500D01*
Y392200D01*
X709400D01*
Y429300D01*
G01X714408Y397954D02*
X711908D01*
Y398954D01*
X712033Y399287D01*
X712325Y399537D01*
X712658Y399620D01*
X712991Y399537D01*
X713241Y399329D01*
X713366Y398954D01*
Y397954D01*
G01X714408Y401887D02*
X714366Y401554D01*
X714200Y401262D01*
X713950Y401012D01*
X713658Y400845D01*
X713325Y400762D01*
X712991D01*
X712658Y400845D01*
X712366Y401012D01*
X712116Y401262D01*
X711950Y401554D01*
X711908Y401887D01*
X711950Y402220D01*
X712116Y402512D01*
X712366Y402762D01*
X712658Y402929D01*
X712991Y403012D01*
X713325D01*
X713658Y402929D01*
X713950Y402762D01*
X714200Y402512D01*
X714366Y402220D01*
X714408Y401887D01*
G01X713741Y402220D02*
X714408Y402720D01*
G01Y404987D02*
X711908D01*
X712408Y404487D01*
G01X714408D02*
Y405487D01*
G01X714116Y407379D02*
X714325Y407670D01*
X714408Y408004D01*
X714325Y408337D01*
X714075Y408629D01*
X713700Y408837D01*
X713325Y408920D01*
X712866D01*
X712491Y408837D01*
X712158Y408629D01*
X711991Y408379D01*
X711908Y408087D01*
X711991Y407754D01*
X712158Y407504D01*
X712408Y407337D01*
X712741Y407254D01*
X713033Y407337D01*
X713325Y407545D01*
X713491Y407795D01*
X713533Y408087D01*
X713450Y408420D01*
X713241Y408670D01*
X712866Y408920D01*
G01X714963Y411025D02*
X712463D01*
Y412025D01*
X712588Y412358D01*
X712880Y412608D01*
X713213Y412691D01*
X713546Y412608D01*
X713796Y412400D01*
X713921Y412025D01*
Y411025D01*
G01X714630Y414083D02*
X714838Y414416D01*
X714963Y414791D01*
Y415125D01*
X714838Y415458D01*
X714630Y415708D01*
X714338Y415833D01*
X714046Y415750D01*
X713796Y415541D01*
X713630Y415166D01*
X713546Y414666D01*
X713380Y414375D01*
X713088Y414250D01*
X712796Y414333D01*
X712588Y414541D01*
X712463Y414833D01*
Y415125D01*
X712546Y415416D01*
X712755Y415666D01*
G01X714963Y417225D02*
X712463D01*
Y418225D01*
X712588Y418558D01*
X712880Y418808D01*
X713213Y418891D01*
X713546Y418808D01*
X713796Y418600D01*
X713921Y418225D01*
Y417225D01*
G01X714463Y420241D02*
X714755Y420491D01*
X714921Y420825D01*
X714963Y421200D01*
X714921Y421533D01*
X714713Y421866D01*
X714463Y422075D01*
X714213Y422116D01*
X713921Y422033D01*
X713713Y421741D01*
X713630Y421450D01*
Y421075D01*
G01Y421450D02*
X713505Y421700D01*
X713296Y421908D01*
X713046Y421991D01*
X712796Y421908D01*
X712588Y421700D01*
X712463Y421325D01*
X712505Y420950D01*
X712671Y420575D01*
G01X726330Y402608D02*
Y405108D01*
X727330D01*
X727663Y404983D01*
X727913Y404691D01*
X727996Y404358D01*
X727913Y404025D01*
X727705Y403775D01*
X727330Y403650D01*
X726330D01*
G01X729430Y402608D02*
Y405108D01*
X730471D01*
X730805Y404983D01*
X731013Y404816D01*
X731096Y404483D01*
X731013Y404150D01*
X730763Y403941D01*
X730471Y403816D01*
X729430D01*
G01X730471D02*
X731096Y402608D01*
G01X733363D02*
Y405108D01*
X732863Y404608D01*
G01Y402608D02*
X733863D01*
G01X735671Y403650D02*
X735963Y403941D01*
X736213Y404108D01*
X736546Y404191D01*
X736838Y404108D01*
X737046Y403941D01*
X737213Y403691D01*
X737255Y403400D01*
X737213Y403150D01*
X737046Y402900D01*
X736796Y402691D01*
X736505Y402608D01*
X736171Y402691D01*
X735880Y402941D01*
X735713Y403316D01*
X735671Y403733D01*
X735755Y404275D01*
X735880Y404566D01*
X736088Y404858D01*
X736380Y405066D01*
X736671Y405108D01*
X736963Y405025D01*
X737171Y404816D01*
G01X739563Y402608D02*
X739855Y402650D01*
X740188Y402775D01*
X740396Y402983D01*
X740480Y403275D01*
X740396Y403566D01*
X740146Y403816D01*
X739771Y403941D01*
X739355D01*
X739105Y404025D01*
X738896Y404233D01*
X738813Y404525D01*
X738938Y404816D01*
X739230Y405025D01*
X739563Y405108D01*
X739896Y405025D01*
X740188Y404816D01*
X740313Y404525D01*
X740230Y404233D01*
X740021Y404025D01*
X739771Y403941D01*
X739355D01*
X738980Y403816D01*
X738730Y403566D01*
X738646Y403275D01*
X738730Y402983D01*
X738938Y402775D01*
X739271Y402650D01*
X739563Y402608D01*
G01X732930Y394108D02*
Y396608D01*
X733930D01*
X734263Y396483D01*
X734513Y396191D01*
X734596Y395858D01*
X734513Y395525D01*
X734305Y395275D01*
X733930Y395150D01*
X732930D01*
G01X736030Y394108D02*
Y396608D01*
X737071D01*
X737405Y396483D01*
X737613Y396316D01*
X737696Y395983D01*
X737613Y395650D01*
X737363Y395441D01*
X737071Y395316D01*
X736030D01*
G01X737071D02*
X737696Y394108D01*
G01X739963D02*
Y396608D01*
X739463Y396108D01*
G01Y394108D02*
X740463D01*
G01X743063D02*
X743355Y394150D01*
X743688Y394275D01*
X743896Y394483D01*
X743980Y394775D01*
X743896Y395066D01*
X743646Y395316D01*
X743271Y395441D01*
X742855D01*
X742605Y395525D01*
X742396Y395733D01*
X742313Y396025D01*
X742438Y396316D01*
X742730Y396525D01*
X743063Y396608D01*
X743396Y396525D01*
X743688Y396316D01*
X743813Y396025D01*
X743730Y395733D01*
X743521Y395525D01*
X743271Y395441D01*
X742855D01*
X742480Y395316D01*
X742230Y395066D01*
X742146Y394775D01*
X742230Y394483D01*
X742438Y394275D01*
X742771Y394150D01*
X743063Y394108D01*
G01X746163Y396608D02*
X745830Y396525D01*
X745580Y396316D01*
X745413Y396066D01*
X745288Y395733D01*
X745246Y395358D01*
X745288Y394983D01*
X745413Y394650D01*
X745580Y394400D01*
X745830Y394191D01*
X746163Y394108D01*
X746496Y394191D01*
X746746Y394400D01*
X746913Y394650D01*
X747038Y394983D01*
X747080Y395358D01*
X747038Y395733D01*
X746913Y396066D01*
X746746Y396316D01*
X746496Y396525D01*
X746163Y396608D01*
G01X716567Y398000D02*
Y400500D01*
X717567D01*
X717900Y400375D01*
X718150Y400083D01*
X718233Y399750D01*
X718150Y399417D01*
X717942Y399167D01*
X717567Y399042D01*
X716567D01*
G01X719667Y398000D02*
Y400500D01*
X720708D01*
X721042Y400375D01*
X721250Y400208D01*
X721333Y399875D01*
X721250Y399542D01*
X721000Y399333D01*
X720708Y399208D01*
X719667D01*
G01X720708D02*
X721333Y398000D01*
G01X723600D02*
Y400500D01*
X723100Y400000D01*
G01Y398000D02*
X724100D01*
G01X726617D02*
X726700Y398542D01*
X726825Y399000D01*
X726992Y399417D01*
X727200Y399875D01*
X727533Y400500D01*
X725867D01*
G01X729092Y398292D02*
X729383Y398083D01*
X729717Y398000D01*
X730050Y398083D01*
X730342Y398333D01*
X730550Y398708D01*
X730633Y399083D01*
Y399542D01*
X730550Y399917D01*
X730342Y400250D01*
X730092Y400417D01*
X729800Y400500D01*
X729467Y400417D01*
X729217Y400250D01*
X729050Y400000D01*
X728967Y399667D01*
X729050Y399375D01*
X729258Y399083D01*
X729508Y398917D01*
X729800Y398875D01*
X730133Y398958D01*
X730383Y399167D01*
X730633Y399542D01*
G01X733863Y410575D02*
X731363D01*
Y411575D01*
X731488Y411908D01*
X731780Y412158D01*
X732113Y412241D01*
X732446Y412158D01*
X732696Y411950D01*
X732821Y411575D01*
Y410575D01*
G01X733863Y413675D02*
X731363D01*
Y414716D01*
X731488Y415050D01*
X731655Y415258D01*
X731988Y415341D01*
X732321Y415258D01*
X732530Y415008D01*
X732655Y414716D01*
Y413675D01*
G01Y414716D02*
X733863Y415341D01*
G01Y417608D02*
X731363D01*
X731863Y417108D01*
G01X733863D02*
Y418108D01*
G01Y420625D02*
X733321Y420708D01*
X732863Y420833D01*
X732446Y421000D01*
X731988Y421208D01*
X731363Y421541D01*
Y419875D01*
G01X733863Y423808D02*
X733821Y424100D01*
X733696Y424433D01*
X733488Y424641D01*
X733196Y424725D01*
X732905Y424641D01*
X732655Y424391D01*
X732530Y424016D01*
Y423600D01*
X732446Y423350D01*
X732238Y423141D01*
X731946Y423058D01*
X731655Y423183D01*
X731446Y423475D01*
X731363Y423808D01*
X731446Y424141D01*
X731655Y424433D01*
X731946Y424558D01*
X732238Y424475D01*
X732446Y424266D01*
X732530Y424016D01*
Y423600D01*
X732655Y423225D01*
X732905Y422975D01*
X733196Y422891D01*
X733488Y422975D01*
X733696Y423183D01*
X733821Y423516D01*
X733863Y423808D01*
G01X737863Y410575D02*
X735363D01*
Y411575D01*
X735488Y411908D01*
X735780Y412158D01*
X736113Y412241D01*
X736446Y412158D01*
X736696Y411950D01*
X736821Y411575D01*
Y410575D01*
G01X737863Y413675D02*
X735363D01*
Y414716D01*
X735488Y415050D01*
X735655Y415258D01*
X735988Y415341D01*
X736321Y415258D01*
X736530Y415008D01*
X736655Y414716D01*
Y413675D01*
G01Y414716D02*
X737863Y415341D01*
G01Y417608D02*
X735363D01*
X735863Y417108D01*
G01X737863D02*
Y418108D01*
G01Y420625D02*
X737321Y420708D01*
X736863Y420833D01*
X736446Y421000D01*
X735988Y421208D01*
X735363Y421541D01*
Y419875D01*
G01X736821Y423016D02*
X736530Y423308D01*
X736363Y423558D01*
X736280Y423891D01*
X736363Y424183D01*
X736530Y424391D01*
X736780Y424558D01*
X737071Y424600D01*
X737321Y424558D01*
X737571Y424391D01*
X737780Y424141D01*
X737863Y423850D01*
X737780Y423516D01*
X737530Y423225D01*
X737155Y423058D01*
X736738Y423016D01*
X736196Y423100D01*
X735905Y423225D01*
X735613Y423433D01*
X735405Y423725D01*
X735363Y424016D01*
X735446Y424308D01*
X735655Y424516D01*
G01X726330Y406608D02*
Y409108D01*
X727330D01*
X727663Y408983D01*
X727913Y408691D01*
X727996Y408358D01*
X727913Y408025D01*
X727705Y407775D01*
X727330Y407650D01*
X726330D01*
G01X731180Y408900D02*
X730930Y409025D01*
X730638Y409108D01*
X730305D01*
X729930Y408983D01*
X729638Y408775D01*
X729430Y408525D01*
X729263Y408108D01*
X729221Y407733D01*
X729305Y407358D01*
X729430Y407108D01*
X729680Y406858D01*
X729971Y406691D01*
X730263Y406608D01*
X730555D01*
X730846Y406691D01*
X731096Y406816D01*
X731305Y406983D01*
G01X732571Y408691D02*
X732821Y408941D01*
X733113Y409066D01*
X733446Y409108D01*
X733863Y409025D01*
X734155Y408816D01*
X734238Y408566D01*
X734196Y408316D01*
X734030Y408108D01*
X733196Y407691D01*
X732821Y407400D01*
X732571Y406983D01*
X732488Y406608D01*
X734238D01*
G01X736463Y409108D02*
X736130Y409025D01*
X735880Y408816D01*
X735713Y408566D01*
X735588Y408233D01*
X735546Y407858D01*
X735588Y407483D01*
X735713Y407150D01*
X735880Y406900D01*
X736130Y406691D01*
X736463Y406608D01*
X736796Y406691D01*
X737046Y406900D01*
X737213Y407150D01*
X737338Y407483D01*
X737380Y407858D01*
X737338Y408233D01*
X737213Y408566D01*
X737046Y408816D01*
X736796Y409025D01*
X736463Y409108D01*
G01X738646Y407108D02*
X738896Y406816D01*
X739230Y406650D01*
X739605Y406608D01*
X739938Y406650D01*
X740271Y406858D01*
X740480Y407108D01*
X740521Y407358D01*
X740438Y407650D01*
X740146Y407858D01*
X739855Y407941D01*
X739480D01*
G01X739855D02*
X740105Y408066D01*
X740313Y408275D01*
X740396Y408525D01*
X740313Y408775D01*
X740105Y408983D01*
X739730Y409108D01*
X739355Y409066D01*
X738980Y408900D01*
G01X729863Y410575D02*
X727363D01*
Y411575D01*
X727488Y411908D01*
X727780Y412158D01*
X728113Y412241D01*
X728446Y412158D01*
X728696Y411950D01*
X728821Y411575D01*
Y410575D01*
G01X727571Y415425D02*
X727446Y415175D01*
X727363Y414883D01*
Y414550D01*
X727488Y414175D01*
X727696Y413883D01*
X727946Y413675D01*
X728363Y413508D01*
X728738Y413466D01*
X729113Y413550D01*
X729363Y413675D01*
X729613Y413925D01*
X729780Y414216D01*
X729863Y414508D01*
Y414800D01*
X729780Y415091D01*
X729655Y415341D01*
X729488Y415550D01*
G01X727780Y416816D02*
X727530Y417066D01*
X727405Y417358D01*
X727363Y417691D01*
X727446Y418108D01*
X727655Y418400D01*
X727905Y418483D01*
X728155Y418441D01*
X728363Y418275D01*
X728780Y417441D01*
X729071Y417066D01*
X729488Y416816D01*
X729863Y416733D01*
Y418483D01*
G01X727363Y420708D02*
X727446Y420375D01*
X727655Y420125D01*
X727905Y419958D01*
X728238Y419833D01*
X728613Y419791D01*
X728988Y419833D01*
X729321Y419958D01*
X729571Y420125D01*
X729780Y420375D01*
X729863Y420708D01*
X729780Y421041D01*
X729571Y421291D01*
X729321Y421458D01*
X728988Y421583D01*
X728613Y421625D01*
X728238Y421583D01*
X727905Y421458D01*
X727655Y421291D01*
X727446Y421041D01*
X727363Y420708D01*
G01X729863Y424308D02*
X727363D01*
X729155Y422766D01*
Y424850D01*
G01X736230Y400400D02*
X735980Y400525D01*
X735688Y400608D01*
X735355D01*
X734980Y400483D01*
X734688Y400275D01*
X734480Y400025D01*
X734313Y399608D01*
X734271Y399233D01*
X734355Y398858D01*
X734480Y398608D01*
X734730Y398358D01*
X735021Y398191D01*
X735313Y398108D01*
X735605D01*
X735896Y398191D01*
X736146Y398316D01*
X736355Y398483D01*
G01X737621Y400191D02*
X737871Y400441D01*
X738163Y400566D01*
X738496Y400608D01*
X738913Y400525D01*
X739205Y400316D01*
X739288Y400066D01*
X739246Y399816D01*
X739080Y399608D01*
X738246Y399191D01*
X737871Y398900D01*
X737621Y398483D01*
X737538Y398108D01*
X739288D01*
G01X740721Y399150D02*
X741013Y399441D01*
X741263Y399608D01*
X741596Y399691D01*
X741888Y399608D01*
X742096Y399441D01*
X742263Y399191D01*
X742305Y398900D01*
X742263Y398650D01*
X742096Y398400D01*
X741846Y398191D01*
X741555Y398108D01*
X741221Y398191D01*
X740930Y398441D01*
X740763Y398816D01*
X740721Y399233D01*
X740805Y399775D01*
X740930Y400066D01*
X741138Y400358D01*
X741430Y400566D01*
X741721Y400608D01*
X742013Y400525D01*
X742221Y400316D01*
G01X744613Y398108D02*
X744905Y398150D01*
X745238Y398275D01*
X745446Y398483D01*
X745530Y398775D01*
X745446Y399066D01*
X745196Y399316D01*
X744821Y399441D01*
X744405D01*
X744155Y399525D01*
X743946Y399733D01*
X743863Y400025D01*
X743988Y400316D01*
X744280Y400525D01*
X744613Y400608D01*
X744946Y400525D01*
X745238Y400316D01*
X745363Y400025D01*
X745280Y399733D01*
X745071Y399525D01*
X744821Y399441D01*
X744405D01*
X744030Y399316D01*
X743780Y399066D01*
X743696Y398775D01*
X743780Y398483D01*
X743988Y398275D01*
X744321Y398150D01*
X744613Y398108D01*
G01X727330Y425608D02*
Y428108D01*
X728330D01*
X728663Y427983D01*
X728913Y427691D01*
X728996Y427358D01*
X728913Y427025D01*
X728705Y426775D01*
X728330Y426650D01*
X727330D01*
G01X730430Y425608D02*
Y428108D01*
X731471D01*
X731805Y427983D01*
X732013Y427816D01*
X732096Y427483D01*
X732013Y427150D01*
X731763Y426941D01*
X731471Y426816D01*
X730430D01*
G01X731471D02*
X732096Y425608D01*
G01X733571Y426650D02*
X733863Y426941D01*
X734113Y427108D01*
X734446Y427191D01*
X734738Y427108D01*
X734946Y426941D01*
X735113Y426691D01*
X735155Y426400D01*
X735113Y426150D01*
X734946Y425900D01*
X734696Y425691D01*
X734405Y425608D01*
X734071Y425691D01*
X733780Y425941D01*
X733613Y426316D01*
X733571Y426733D01*
X733655Y427275D01*
X733780Y427566D01*
X733988Y427858D01*
X734280Y428066D01*
X734571Y428108D01*
X734863Y428025D01*
X735071Y427816D01*
G01X736671Y427691D02*
X736921Y427941D01*
X737213Y428066D01*
X737546Y428108D01*
X737963Y428025D01*
X738255Y427816D01*
X738338Y427566D01*
X738296Y427316D01*
X738130Y427108D01*
X737296Y426691D01*
X736921Y426400D01*
X736671Y425983D01*
X736588Y425608D01*
X738338D01*
G01X740563D02*
X740855Y425650D01*
X741188Y425775D01*
X741396Y425983D01*
X741480Y426275D01*
X741396Y426566D01*
X741146Y426816D01*
X740771Y426941D01*
X740355D01*
X740105Y427025D01*
X739896Y427233D01*
X739813Y427525D01*
X739938Y427816D01*
X740230Y428025D01*
X740563Y428108D01*
X740896Y428025D01*
X741188Y427816D01*
X741313Y427525D01*
X741230Y427233D01*
X741021Y427025D01*
X740771Y426941D01*
X740355D01*
X739980Y426816D01*
X739730Y426566D01*
X739646Y426275D01*
X739730Y425983D01*
X739938Y425775D01*
X740271Y425650D01*
X740563Y425608D01*
G01X723480Y816633D02*
X723355Y816383D01*
X723272Y816091D01*
Y815758D01*
X723397Y815383D01*
X723605Y815091D01*
X723855Y814883D01*
X724272Y814716D01*
X724647Y814674D01*
X725022Y814758D01*
X725272Y814883D01*
X725522Y815133D01*
X725689Y815424D01*
X725772Y815716D01*
Y816008D01*
X725689Y816299D01*
X725564Y816549D01*
X725397Y816758D01*
G01X725772Y818816D02*
X723272D01*
X723772Y818316D01*
G01X725772D02*
Y819316D01*
G01X723689Y821124D02*
X723439Y821374D01*
X723314Y821666D01*
X723272Y821999D01*
X723355Y822416D01*
X723564Y822708D01*
X723814Y822791D01*
X724064Y822749D01*
X724272Y822583D01*
X724689Y821749D01*
X724980Y821374D01*
X725397Y821124D01*
X725772Y821041D01*
Y822791D01*
G01Y824933D02*
X725230Y825016D01*
X724772Y825141D01*
X724355Y825308D01*
X723897Y825516D01*
X723272Y825849D01*
Y824183D01*
G01X727480Y816633D02*
X727355Y816383D01*
X727272Y816091D01*
Y815758D01*
X727397Y815383D01*
X727605Y815091D01*
X727855Y814883D01*
X728272Y814716D01*
X728647Y814674D01*
X729022Y814758D01*
X729272Y814883D01*
X729522Y815133D01*
X729689Y815424D01*
X729772Y815716D01*
Y816008D01*
X729689Y816299D01*
X729564Y816549D01*
X729397Y816758D01*
G01X729772Y818816D02*
X727272D01*
X727772Y818316D01*
G01X729772D02*
Y819316D01*
G01X727689Y821124D02*
X727439Y821374D01*
X727314Y821666D01*
X727272Y821999D01*
X727355Y822416D01*
X727564Y822708D01*
X727814Y822791D01*
X728064Y822749D01*
X728272Y822583D01*
X728689Y821749D01*
X728980Y821374D01*
X729397Y821124D01*
X729772Y821041D01*
Y822791D01*
G01X728730Y824224D02*
X728439Y824516D01*
X728272Y824766D01*
X728189Y825099D01*
X728272Y825391D01*
X728439Y825599D01*
X728689Y825766D01*
X728980Y825808D01*
X729230Y825766D01*
X729480Y825599D01*
X729689Y825349D01*
X729772Y825058D01*
X729689Y824724D01*
X729439Y824433D01*
X729064Y824266D01*
X728647Y824224D01*
X728105Y824308D01*
X727814Y824433D01*
X727522Y824641D01*
X727314Y824933D01*
X727272Y825224D01*
X727355Y825516D01*
X727564Y825724D01*
G01X736078Y816633D02*
X735953Y816383D01*
X735870Y816091D01*
Y815758D01*
X735995Y815383D01*
X736203Y815091D01*
X736453Y814883D01*
X736870Y814716D01*
X737245Y814674D01*
X737620Y814758D01*
X737870Y814883D01*
X738120Y815133D01*
X738287Y815424D01*
X738370Y815716D01*
Y816008D01*
X738287Y816299D01*
X738162Y816549D01*
X737995Y816758D01*
G01X738370Y818816D02*
X735870D01*
X736370Y818316D01*
G01X738370D02*
Y819316D01*
G01X736287Y821124D02*
X736037Y821374D01*
X735912Y821666D01*
X735870Y821999D01*
X735953Y822416D01*
X736162Y822708D01*
X736412Y822791D01*
X736662Y822749D01*
X736870Y822583D01*
X737287Y821749D01*
X737578Y821374D01*
X737995Y821124D01*
X738370Y821041D01*
Y822791D01*
G01X737995Y824099D02*
X738203Y824349D01*
X738328Y824641D01*
X738370Y825016D01*
X738287Y825391D01*
X738120Y825683D01*
X737828Y825891D01*
X737495Y825933D01*
X737162Y825849D01*
X736953Y825641D01*
X736787Y825349D01*
X736745Y825058D01*
X736787Y824766D01*
X736953Y824391D01*
X735870Y824516D01*
Y825641D01*
G01X709479Y856708D02*
X710312D01*
Y855958D01*
X710062Y855708D01*
X709771Y855541D01*
X709354Y855458D01*
X708937Y855541D01*
X708646Y855708D01*
X708396Y855958D01*
X708229Y856250D01*
X708146Y856583D01*
Y856875D01*
X708229Y857125D01*
X708396Y857416D01*
X708646Y857666D01*
X708896Y857833D01*
X709229Y857958D01*
X709521D01*
X709854Y857875D01*
X710104Y857708D01*
G01X711537Y855458D02*
Y857958D01*
X713121D01*
G01X712537Y856750D02*
X711537D01*
G01X714721Y855750D02*
X715012Y855541D01*
X715346Y855458D01*
X715679Y855541D01*
X715971Y855791D01*
X716179Y856166D01*
X716262Y856541D01*
Y857000D01*
X716179Y857375D01*
X715971Y857708D01*
X715721Y857875D01*
X715429Y857958D01*
X715096Y857875D01*
X714846Y857708D01*
X714679Y857458D01*
X714596Y857125D01*
X714679Y856833D01*
X714887Y856541D01*
X715137Y856375D01*
X715429Y856333D01*
X715762Y856416D01*
X716012Y856625D01*
X716262Y857000D01*
G01X748046Y-4866D02*
X745546D01*
Y-3825D01*
X745671Y-3491D01*
X745838Y-3283D01*
X746171Y-3200D01*
X746504Y-3283D01*
X746713Y-3533D01*
X746838Y-3825D01*
Y-4866D01*
G01Y-3825D02*
X748046Y-3200D01*
G01X747004Y-1725D02*
X746713Y-1433D01*
X746546Y-1183D01*
X746463Y-850D01*
X746546Y-558D01*
X746713Y-350D01*
X746963Y-183D01*
X747254Y-141D01*
X747504Y-183D01*
X747754Y-350D01*
X747963Y-600D01*
X748046Y-891D01*
X747963Y-1225D01*
X747713Y-1516D01*
X747338Y-1683D01*
X746921Y-1725D01*
X746379Y-1641D01*
X746088Y-1516D01*
X745796Y-1308D01*
X745588Y-1016D01*
X745546Y-725D01*
X745629Y-433D01*
X745838Y-225D01*
G01X748046Y2084D02*
X747504Y2167D01*
X747046Y2292D01*
X746629Y2459D01*
X746171Y2667D01*
X745546Y3000D01*
Y1334D01*
G01X748046Y5267D02*
X745546D01*
X746046Y4767D01*
G01X748046D02*
Y5767D01*
G01X752093Y-5013D02*
X749593D01*
Y-3972D01*
X749718Y-3638D01*
X749885Y-3430D01*
X750218Y-3347D01*
X750551Y-3430D01*
X750760Y-3680D01*
X750885Y-3972D01*
Y-5013D01*
G01Y-3972D02*
X752093Y-3347D01*
G01X751051Y-1872D02*
X750760Y-1580D01*
X750593Y-1330D01*
X750510Y-997D01*
X750593Y-705D01*
X750760Y-497D01*
X751010Y-330D01*
X751301Y-288D01*
X751551Y-330D01*
X751801Y-497D01*
X752010Y-747D01*
X752093Y-1038D01*
X752010Y-1372D01*
X751760Y-1663D01*
X751385Y-1830D01*
X750968Y-1872D01*
X750426Y-1788D01*
X750135Y-1663D01*
X749843Y-1455D01*
X749635Y-1163D01*
X749593Y-872D01*
X749676Y-580D01*
X749885Y-372D01*
G01X752093Y1937D02*
X751551Y2020D01*
X751093Y2145D01*
X750676Y2312D01*
X750218Y2520D01*
X749593Y2853D01*
Y1187D01*
G01Y5120D02*
X749676Y4787D01*
X749885Y4537D01*
X750135Y4370D01*
X750468Y4245D01*
X750843Y4203D01*
X751218Y4245D01*
X751551Y4370D01*
X751801Y4537D01*
X752010Y4787D01*
X752093Y5120D01*
X752010Y5453D01*
X751801Y5703D01*
X751551Y5870D01*
X751218Y5995D01*
X750843Y6037D01*
X750468Y5995D01*
X750135Y5870D01*
X749885Y5703D01*
X749676Y5453D01*
X749593Y5120D01*
G01X764017Y-7833D02*
Y-10333D01*
X765683D01*
G01X768783D02*
X767117D01*
Y-7833D01*
X768783D01*
G01X768117Y-9041D02*
X767117D01*
G01X770133Y-10333D02*
Y-7833D01*
X770967D01*
X771300Y-7958D01*
X771550Y-8125D01*
X771758Y-8375D01*
X771925Y-8666D01*
X771967Y-9083D01*
X771925Y-9500D01*
X771758Y-9791D01*
X771550Y-10041D01*
X771300Y-10208D01*
X770967Y-10333D01*
X770133D01*
G01X774650D02*
Y-7833D01*
X773108Y-9625D01*
X775192D01*
G01X778529Y-3650D02*
X774648D01*
G02X765509I-4570J1902D01*
G01X761629D01*
Y3650D01*
X778529D01*
Y-3650D01*
G01X756360Y-4102D02*
X756318Y-4435D01*
X756152Y-4727D01*
X755902Y-4977D01*
X755610Y-5144D01*
X755277Y-5227D01*
X754943D01*
X754610Y-5144D01*
X754318Y-4977D01*
X754068Y-4727D01*
X753902Y-4435D01*
X753860Y-4102D01*
X753902Y-3769D01*
X754068Y-3477D01*
X754318Y-3227D01*
X754610Y-3060D01*
X754943Y-2977D01*
X755277D01*
X755610Y-3060D01*
X755902Y-3227D01*
X756152Y-3477D01*
X756318Y-3769D01*
X756360Y-4102D01*
G01X755693Y-3769D02*
X756360Y-3269D01*
G01X754277Y-1794D02*
X754027Y-1544D01*
X753902Y-1252D01*
X753860Y-919D01*
X753943Y-502D01*
X754152Y-210D01*
X754402Y-127D01*
X754652Y-169D01*
X754860Y-335D01*
X755277Y-1169D01*
X755568Y-1544D01*
X755985Y-1794D01*
X756360Y-1877D01*
Y-127D01*
G01Y2098D02*
X753860D01*
X754360Y1598D01*
G01X756360D02*
Y2598D01*
G01X744132Y-6494D02*
Y6506D01*
G01X758517Y7166D02*
X758725Y6916D01*
X758975Y6749D01*
X759267Y6666D01*
X759600Y6749D01*
X759850Y6916D01*
X760100Y7166D01*
X760183Y7499D01*
Y9166D01*
G01X761617Y6666D02*
Y9166D01*
X762617D01*
X762950Y9041D01*
X763200Y8749D01*
X763283Y8416D01*
X763200Y8083D01*
X762992Y7833D01*
X762617Y7708D01*
X761617D01*
G01X765550Y6666D02*
Y9166D01*
X765050Y8666D01*
G01Y6666D02*
X766050D01*
G01X767858Y8749D02*
X768108Y8999D01*
X768400Y9124D01*
X768733Y9166D01*
X769150Y9083D01*
X769442Y8874D01*
X769525Y8624D01*
X769483Y8374D01*
X769317Y8166D01*
X768483Y7749D01*
X768108Y7458D01*
X767858Y7041D01*
X767775Y6666D01*
X769525D01*
G01X765947Y34599D02*
X766197Y34849D01*
X766489Y34974D01*
X766822Y35016D01*
X767239Y34933D01*
X767531Y34724D01*
X767614Y34474D01*
X767572Y34224D01*
X767406Y34016D01*
X766572Y33599D01*
X766197Y33308D01*
X765947Y32891D01*
X765864Y32516D01*
X767614D01*
G01X769297Y33349D02*
X770381D01*
G01X772022Y33016D02*
X772272Y32724D01*
X772606Y32558D01*
X772981Y32516D01*
X773314Y32558D01*
X773647Y32766D01*
X773856Y33016D01*
X773897Y33266D01*
X773814Y33558D01*
X773522Y33766D01*
X773231Y33849D01*
X772856D01*
G01X773231D02*
X773481Y33974D01*
X773689Y34183D01*
X773772Y34433D01*
X773689Y34683D01*
X773481Y34891D01*
X773106Y35016D01*
X772731Y34974D01*
X772356Y34808D01*
G01X778514Y33641D02*
X779847D01*
X779722Y33933D01*
X779514Y34099D01*
X779222Y34183D01*
X778931Y34141D01*
X778681Y34016D01*
X778514Y33724D01*
X778431Y33474D01*
Y33224D01*
X778514Y32974D01*
X778722Y32724D01*
X778972Y32558D01*
X779264Y32516D01*
X779556Y32599D01*
X779847Y32849D01*
G01X781531Y32516D02*
Y34183D01*
G01Y33766D02*
X781697Y33974D01*
X781947Y34141D01*
X782281Y34183D01*
X782572Y34141D01*
X782822Y33974D01*
X782947Y33683D01*
Y32516D01*
G01X786089D02*
Y34183D01*
G01Y33891D02*
X785922Y34058D01*
X785672Y34141D01*
X785381Y34183D01*
X785089Y34099D01*
X784839Y33933D01*
X784672Y33683D01*
X784589Y33349D01*
X784672Y33016D01*
X784839Y32766D01*
X785089Y32599D01*
X785381Y32516D01*
X785672Y32558D01*
X785922Y32683D01*
X786089Y32849D01*
G01X787689Y32516D02*
Y35016D01*
G01Y33766D02*
X787897Y34016D01*
X788147Y34141D01*
X788397Y34183D01*
X788772Y34099D01*
X789022Y33933D01*
X789189Y33641D01*
Y33308D01*
X789106Y32974D01*
X788939Y32724D01*
X788647Y32558D01*
X788397Y32516D01*
X788147Y32558D01*
X787897Y32683D01*
X787689Y32891D01*
G01X791539Y32516D02*
Y35016D01*
G01X794014Y33641D02*
X795347D01*
X795222Y33933D01*
X795014Y34099D01*
X794722Y34183D01*
X794431Y34141D01*
X794181Y34016D01*
X794014Y33724D01*
X793931Y33474D01*
Y33224D01*
X794014Y32974D01*
X794222Y32724D01*
X794472Y32558D01*
X794764Y32516D01*
X795056Y32599D01*
X795347Y32849D01*
G01X768250Y37500D02*
Y40000D01*
X767750Y39500D01*
G01Y37500D02*
X768750D01*
G01X770808Y38333D02*
X771892D01*
G01X773658Y39583D02*
X773908Y39833D01*
X774200Y39958D01*
X774533Y40000D01*
X774950Y39917D01*
X775242Y39708D01*
X775325Y39458D01*
X775283Y39208D01*
X775117Y39000D01*
X774283Y38583D01*
X773908Y38292D01*
X773658Y37875D01*
X773575Y37500D01*
X775325D01*
G01X781400Y40000D02*
Y37500D01*
G01Y37875D02*
X781233Y37667D01*
X780983Y37542D01*
X780692Y37500D01*
X780358Y37583D01*
X780108Y37792D01*
X779942Y38042D01*
X779900Y38333D01*
X779942Y38625D01*
X780108Y38875D01*
X780358Y39083D01*
X780692Y39167D01*
X780983Y39125D01*
X781192Y39042D01*
X781400Y38875D01*
G01X783750Y39167D02*
Y37500D01*
G01Y39833D02*
X783667Y39875D01*
Y39958D01*
X783750Y40000D01*
X783833Y39958D01*
Y39875D01*
X783750Y39833D01*
G01X786225Y37792D02*
X786433Y37625D01*
X786725Y37500D01*
X786975D01*
X787225Y37583D01*
X787392Y37708D01*
X787475Y37875D01*
X787433Y38125D01*
X787267Y38250D01*
X786517Y38500D01*
X786350Y38792D01*
X786433Y39000D01*
X786600Y39125D01*
X786850Y39167D01*
X787100Y39125D01*
X787350Y39000D01*
G01X790700Y37500D02*
Y39167D01*
G01Y38875D02*
X790533Y39042D01*
X790283Y39125D01*
X789992Y39167D01*
X789700Y39083D01*
X789450Y38917D01*
X789283Y38667D01*
X789200Y38333D01*
X789283Y38000D01*
X789450Y37750D01*
X789700Y37583D01*
X789992Y37500D01*
X790283Y37542D01*
X790533Y37667D01*
X790700Y37833D01*
G01X792300Y37500D02*
Y40000D01*
G01Y38750D02*
X792508Y39000D01*
X792758Y39125D01*
X793008Y39167D01*
X793383Y39083D01*
X793633Y38917D01*
X793800Y38625D01*
Y38292D01*
X793717Y37958D01*
X793550Y37708D01*
X793258Y37542D01*
X793008Y37500D01*
X792758Y37542D01*
X792508Y37667D01*
X792300Y37875D01*
G01X796150Y37500D02*
Y40000D01*
G01X798625Y38625D02*
X799958D01*
X799833Y38917D01*
X799625Y39083D01*
X799333Y39167D01*
X799042Y39125D01*
X798792Y39000D01*
X798625Y38708D01*
X798542Y38458D01*
Y38208D01*
X798625Y37958D01*
X798833Y37708D01*
X799083Y37542D01*
X799375Y37500D01*
X799667Y37583D01*
X799958Y37833D01*
G01X766500Y41000D02*
X802500D01*
Y36000D01*
X766500D01*
Y41000D01*
G01X753200Y36200D02*
Y26200D01*
G01D02*
X739800D01*
G01D02*
Y36200D01*
G01D02*
X753200D01*
G01X758817Y29100D02*
Y31600D01*
X759858D01*
X760192Y31475D01*
X760400Y31308D01*
X760483Y30975D01*
X760400Y30642D01*
X760150Y30433D01*
X759858Y30308D01*
X758817D01*
G01X759858D02*
X760483Y29100D01*
G01X761958Y30142D02*
X762250Y30433D01*
X762500Y30600D01*
X762833Y30683D01*
X763125Y30600D01*
X763333Y30433D01*
X763500Y30183D01*
X763542Y29892D01*
X763500Y29642D01*
X763333Y29392D01*
X763083Y29183D01*
X762792Y29100D01*
X762458Y29183D01*
X762167Y29433D01*
X762000Y29808D01*
X761958Y30225D01*
X762042Y30767D01*
X762167Y31058D01*
X762375Y31350D01*
X762667Y31558D01*
X762958Y31600D01*
X763250Y31517D01*
X763458Y31308D01*
G01X765850Y29100D02*
X766142Y29142D01*
X766475Y29267D01*
X766683Y29475D01*
X766767Y29767D01*
X766683Y30058D01*
X766433Y30308D01*
X766058Y30433D01*
X765642D01*
X765392Y30517D01*
X765183Y30725D01*
X765100Y31017D01*
X765225Y31308D01*
X765517Y31517D01*
X765850Y31600D01*
X766183Y31517D01*
X766475Y31308D01*
X766600Y31017D01*
X766517Y30725D01*
X766308Y30517D01*
X766058Y30433D01*
X765642D01*
X765267Y30308D01*
X765017Y30058D01*
X764933Y29767D01*
X765017Y29475D01*
X765225Y29267D01*
X765558Y29142D01*
X765850Y29100D01*
G01X768033Y29600D02*
X768283Y29308D01*
X768617Y29142D01*
X768992Y29100D01*
X769325Y29142D01*
X769658Y29350D01*
X769867Y29600D01*
X769908Y29850D01*
X769825Y30142D01*
X769533Y30350D01*
X769242Y30433D01*
X768867D01*
G01X769242D02*
X769492Y30558D01*
X769700Y30767D01*
X769783Y31017D01*
X769700Y31267D01*
X769492Y31475D01*
X769117Y31600D01*
X768742Y31558D01*
X768367Y31392D01*
G01X754400Y37100D02*
Y33100D01*
X761800D01*
G01X754400Y28200D02*
Y24200D01*
X761800D01*
G01X744700Y17000D02*
X740700D01*
Y9600D01*
G01X762200Y28200D02*
Y24200D01*
X769600D01*
G01X750500Y38000D02*
Y51000D01*
G01X765500Y38000D02*
Y51000D01*
G01X751500D02*
Y38000D01*
G01D02*
X765500D01*
G01X747000Y10300D02*
X777600D01*
Y22100D01*
X747000D01*
Y10300D01*
G01X748250Y73000D02*
Y75500D01*
X746708Y73708D01*
X748792D01*
G01X750225Y74667D02*
X751475Y73000D01*
G01Y74667D02*
X750225Y73000D01*
G01X754450D02*
Y75500D01*
X752908Y73708D01*
X754992D01*
G01X766875Y42833D02*
X767208Y42625D01*
X767583Y42500D01*
X767917D01*
X768250Y42625D01*
X768500Y42833D01*
X768625Y43125D01*
X768542Y43417D01*
X768333Y43667D01*
X767958Y43833D01*
X767458Y43917D01*
X767167Y44083D01*
X767042Y44375D01*
X767125Y44667D01*
X767333Y44875D01*
X767625Y45000D01*
X767917D01*
X768208Y44917D01*
X768458Y44708D01*
G01X771683Y42500D02*
X770017D01*
Y45000D01*
X771683D01*
G01X771017Y43792D02*
X770017D01*
G01X774867Y44792D02*
X774617Y44917D01*
X774325Y45000D01*
X773992D01*
X773617Y44875D01*
X773325Y44667D01*
X773117Y44417D01*
X772950Y44000D01*
X772908Y43625D01*
X772992Y43250D01*
X773117Y43000D01*
X773367Y42750D01*
X773658Y42583D01*
X773950Y42500D01*
X774242D01*
X774533Y42583D01*
X774783Y42708D01*
X774992Y42875D01*
G01X776133Y45000D02*
Y43208D01*
X776300Y42833D01*
X776633Y42583D01*
X777050Y42500D01*
X777467Y42583D01*
X777800Y42833D01*
X777967Y43208D01*
Y45000D01*
G01X779317Y42500D02*
Y45000D01*
X780358D01*
X780692Y44875D01*
X780900Y44708D01*
X780983Y44375D01*
X780900Y44042D01*
X780650Y43833D01*
X780358Y43708D01*
X779317D01*
G01X780358D02*
X780983Y42500D01*
G01X784083D02*
X782417D01*
Y45000D01*
X784083D01*
G01X783417Y43792D02*
X782417D01*
G01X791300Y45000D02*
X791883Y42500D01*
X792550Y45000D01*
X793217Y42500D01*
X793800Y45000D01*
G01X794817Y42500D02*
Y45000D01*
X795817D01*
X796150Y44875D01*
X796400Y44583D01*
X796483Y44250D01*
X796400Y43917D01*
X796192Y43667D01*
X795817Y43542D01*
X794817D01*
G01X797792Y42500D02*
Y45000D01*
X799708Y42500D01*
Y45000D01*
G01X774000Y51500D02*
X794500D01*
Y46500D01*
X772000D01*
Y51500D01*
X774000D01*
G01X763417Y53300D02*
Y55800D01*
X764458D01*
X764792Y55675D01*
X765000Y55508D01*
X765083Y55175D01*
X765000Y54842D01*
X764750Y54633D01*
X764458Y54508D01*
X763417D01*
G01X764458D02*
X765083Y53300D01*
G01X766433Y53675D02*
X766683Y53467D01*
X766975Y53342D01*
X767350Y53300D01*
X767725Y53383D01*
X768017Y53550D01*
X768225Y53842D01*
X768267Y54175D01*
X768183Y54508D01*
X767975Y54717D01*
X767683Y54883D01*
X767392Y54925D01*
X767100Y54883D01*
X766725Y54717D01*
X766850Y55800D01*
X767975D01*
G01X770950Y53300D02*
Y55800D01*
X769408Y54008D01*
X771492D01*
G01X774050Y53300D02*
Y55800D01*
X772508Y54008D01*
X774592D01*
G01X758000Y51800D02*
Y55800D01*
X750600D01*
G01X746725Y57700D02*
X747058Y57492D01*
X747433Y57367D01*
X747767D01*
X748100Y57492D01*
X748350Y57700D01*
X748475Y57992D01*
X748392Y58284D01*
X748183Y58534D01*
X747808Y58700D01*
X747308Y58784D01*
X747017Y58950D01*
X746892Y59242D01*
X746975Y59534D01*
X747183Y59742D01*
X747475Y59867D01*
X747767D01*
X748058Y59784D01*
X748308Y59575D01*
G01X749867Y57367D02*
Y59867D01*
X750908D01*
X751242Y59742D01*
X751450Y59575D01*
X751533Y59242D01*
X751450Y58909D01*
X751200Y58700D01*
X750908Y58575D01*
X749867D01*
G01X750908D02*
X751533Y57367D01*
G01X753717D02*
X753800Y57909D01*
X753925Y58367D01*
X754092Y58784D01*
X754300Y59242D01*
X754633Y59867D01*
X752967D01*
G01X756900Y57367D02*
Y59867D01*
X756400Y59367D01*
G01Y57367D02*
X757400D01*
G01X759208Y58409D02*
X759500Y58700D01*
X759750Y58867D01*
X760083Y58950D01*
X760375Y58867D01*
X760583Y58700D01*
X760750Y58450D01*
X760792Y58159D01*
X760750Y57909D01*
X760583Y57659D01*
X760333Y57450D01*
X760042Y57367D01*
X759708Y57450D01*
X759417Y57700D01*
X759250Y58075D01*
X759208Y58492D01*
X759292Y59034D01*
X759417Y59325D01*
X759625Y59617D01*
X759917Y59825D01*
X760208Y59867D01*
X760500Y59784D01*
X760708Y59575D01*
G01X751800Y66000D02*
Y62000D01*
X759200D01*
G01X763317Y60200D02*
Y62700D01*
X764358D01*
X764692Y62575D01*
X764900Y62408D01*
X764983Y62075D01*
X764900Y61742D01*
X764650Y61533D01*
X764358Y61408D01*
X763317D01*
G01X764358D02*
X764983Y60200D01*
G01X766333Y60575D02*
X766583Y60367D01*
X766875Y60242D01*
X767250Y60200D01*
X767625Y60283D01*
X767917Y60450D01*
X768125Y60742D01*
X768167Y61075D01*
X768083Y61408D01*
X767875Y61617D01*
X767583Y61783D01*
X767292Y61825D01*
X767000Y61783D01*
X766625Y61617D01*
X766750Y62700D01*
X767875D01*
G01X770267Y60200D02*
X770350Y60742D01*
X770475Y61200D01*
X770642Y61617D01*
X770850Y62075D01*
X771183Y62700D01*
X769517D01*
G01X772658Y62283D02*
X772908Y62533D01*
X773200Y62658D01*
X773533Y62700D01*
X773950Y62617D01*
X774242Y62408D01*
X774325Y62158D01*
X774283Y61908D01*
X774117Y61700D01*
X773283Y61283D01*
X772908Y60992D01*
X772658Y60575D01*
X772575Y60200D01*
X774325D01*
G01X763150Y73900D02*
Y77900D01*
X755750D01*
G01X765500Y76000D02*
Y72000D01*
X772900D01*
G01X744994Y71498D02*
X755794D01*
Y66298D01*
X744994D01*
Y71498D01*
G01X769000Y47850D02*
X768958Y47517D01*
X768792Y47225D01*
X768542Y46975D01*
X768250Y46808D01*
X767917Y46725D01*
X767583D01*
X767250Y46808D01*
X766958Y46975D01*
X766708Y47225D01*
X766542Y47517D01*
X766500Y47850D01*
X766542Y48183D01*
X766708Y48475D01*
X766958Y48725D01*
X767250Y48892D01*
X767583Y48975D01*
X767917D01*
X768250Y48892D01*
X768542Y48725D01*
X768792Y48475D01*
X768958Y48183D01*
X769000Y47850D01*
G01X768333Y48183D02*
X769000Y48683D01*
G01X768708Y50242D02*
X768917Y50533D01*
X769000Y50867D01*
X768917Y51200D01*
X768667Y51492D01*
X768292Y51700D01*
X767917Y51783D01*
X767458D01*
X767083Y51700D01*
X766750Y51492D01*
X766583Y51242D01*
X766500Y50950D01*
X766583Y50617D01*
X766750Y50367D01*
X767000Y50200D01*
X767333Y50117D01*
X767625Y50200D01*
X767917Y50408D01*
X768083Y50658D01*
X768125Y50950D01*
X768042Y51283D01*
X767833Y51533D01*
X767458Y51783D01*
G01X765500Y51000D02*
X751500D01*
G01X740617Y87000D02*
Y89500D01*
X741658D01*
X741992Y89375D01*
X742200Y89208D01*
X742283Y88875D01*
X742200Y88542D01*
X741950Y88333D01*
X741658Y88208D01*
X740617D01*
G01X741658D02*
X742283Y87000D01*
G01X743758Y88042D02*
X744050Y88333D01*
X744300Y88500D01*
X744633Y88583D01*
X744925Y88500D01*
X745133Y88333D01*
X745300Y88083D01*
X745342Y87792D01*
X745300Y87542D01*
X745133Y87292D01*
X744883Y87083D01*
X744592Y87000D01*
X744258Y87083D01*
X743967Y87333D01*
X743800Y87708D01*
X743758Y88125D01*
X743842Y88667D01*
X743967Y88958D01*
X744175Y89250D01*
X744467Y89458D01*
X744758Y89500D01*
X745050Y89417D01*
X745258Y89208D01*
G01X746942Y87292D02*
X747233Y87083D01*
X747567Y87000D01*
X747900Y87083D01*
X748192Y87333D01*
X748400Y87708D01*
X748483Y88083D01*
Y88542D01*
X748400Y88917D01*
X748192Y89250D01*
X747942Y89417D01*
X747650Y89500D01*
X747317Y89417D01*
X747067Y89250D01*
X746900Y89000D01*
X746817Y88667D01*
X746900Y88375D01*
X747108Y88083D01*
X747358Y87917D01*
X747650Y87875D01*
X747983Y87958D01*
X748233Y88167D01*
X748483Y88542D01*
G01X749958Y88042D02*
X750250Y88333D01*
X750500Y88500D01*
X750833Y88583D01*
X751125Y88500D01*
X751333Y88333D01*
X751500Y88083D01*
X751542Y87792D01*
X751500Y87542D01*
X751333Y87292D01*
X751083Y87083D01*
X750792Y87000D01*
X750458Y87083D01*
X750167Y87333D01*
X750000Y87708D01*
X749958Y88125D01*
X750042Y88667D01*
X750167Y88958D01*
X750375Y89250D01*
X750667Y89458D01*
X750958Y89500D01*
X751250Y89417D01*
X751458Y89208D01*
G01X763300Y84500D02*
Y88500D01*
X755900D01*
G01X740617Y91100D02*
Y93600D01*
X741658D01*
X741992Y93475D01*
X742200Y93308D01*
X742283Y92975D01*
X742200Y92642D01*
X741950Y92433D01*
X741658Y92308D01*
X740617D01*
G01X741658D02*
X742283Y91100D01*
G01X744550D02*
X744842Y91142D01*
X745175Y91267D01*
X745383Y91475D01*
X745467Y91767D01*
X745383Y92058D01*
X745133Y92308D01*
X744758Y92433D01*
X744342D01*
X744092Y92517D01*
X743883Y92725D01*
X743800Y93017D01*
X743925Y93308D01*
X744217Y93517D01*
X744550Y93600D01*
X744883Y93517D01*
X745175Y93308D01*
X745300Y93017D01*
X745217Y92725D01*
X745008Y92517D01*
X744758Y92433D01*
X744342D01*
X743967Y92308D01*
X743717Y92058D01*
X743633Y91767D01*
X743717Y91475D01*
X743925Y91267D01*
X744258Y91142D01*
X744550Y91100D01*
G01X746733Y91600D02*
X746983Y91308D01*
X747317Y91142D01*
X747692Y91100D01*
X748025Y91142D01*
X748358Y91350D01*
X748567Y91600D01*
X748608Y91850D01*
X748525Y92142D01*
X748233Y92350D01*
X747942Y92433D01*
X747567D01*
G01X747942D02*
X748192Y92558D01*
X748400Y92767D01*
X748483Y93017D01*
X748400Y93267D01*
X748192Y93475D01*
X747817Y93600D01*
X747442Y93558D01*
X747067Y93392D01*
G01X750750Y91100D02*
X751042Y91142D01*
X751375Y91267D01*
X751583Y91475D01*
X751667Y91767D01*
X751583Y92058D01*
X751333Y92308D01*
X750958Y92433D01*
X750542D01*
X750292Y92517D01*
X750083Y92725D01*
X750000Y93017D01*
X750125Y93308D01*
X750417Y93517D01*
X750750Y93600D01*
X751083Y93517D01*
X751375Y93308D01*
X751500Y93017D01*
X751417Y92725D01*
X751208Y92517D01*
X750958Y92433D01*
X750542D01*
X750167Y92308D01*
X749917Y92058D01*
X749833Y91767D01*
X749917Y91475D01*
X750125Y91267D01*
X750458Y91142D01*
X750750Y91100D01*
G01X763300Y88600D02*
Y92600D01*
X755900D01*
G01X749000Y106917D02*
X746500D01*
Y107958D01*
X746625Y108292D01*
X746792Y108500D01*
X747125Y108583D01*
X747458Y108500D01*
X747667Y108250D01*
X747792Y107958D01*
Y106917D01*
G01Y107958D02*
X749000Y108583D01*
G01Y110850D02*
X748958Y111142D01*
X748833Y111475D01*
X748625Y111683D01*
X748333Y111767D01*
X748042Y111683D01*
X747792Y111433D01*
X747667Y111058D01*
Y110642D01*
X747583Y110392D01*
X747375Y110183D01*
X747083Y110100D01*
X746792Y110225D01*
X746583Y110517D01*
X746500Y110850D01*
X746583Y111183D01*
X746792Y111475D01*
X747083Y111600D01*
X747375Y111517D01*
X747583Y111308D01*
X747667Y111058D01*
Y110642D01*
X747792Y110267D01*
X748042Y110017D01*
X748333Y109933D01*
X748625Y110017D01*
X748833Y110225D01*
X748958Y110558D01*
X749000Y110850D01*
G01X748500Y113033D02*
X748792Y113283D01*
X748958Y113617D01*
X749000Y113992D01*
X748958Y114325D01*
X748750Y114658D01*
X748500Y114867D01*
X748250Y114908D01*
X747958Y114825D01*
X747750Y114533D01*
X747667Y114242D01*
Y113867D01*
G01Y114242D02*
X747542Y114492D01*
X747333Y114700D01*
X747083Y114783D01*
X746833Y114700D01*
X746625Y114492D01*
X746500Y114117D01*
X746542Y113742D01*
X746708Y113367D01*
G01X749000Y116967D02*
X748458Y117050D01*
X748000Y117175D01*
X747583Y117342D01*
X747125Y117550D01*
X746500Y117883D01*
Y116217D01*
G01X771400Y109600D02*
X767400D01*
Y102200D01*
G01X740617Y99300D02*
Y101800D01*
X741658D01*
X741992Y101675D01*
X742200Y101508D01*
X742283Y101175D01*
X742200Y100842D01*
X741950Y100633D01*
X741658Y100508D01*
X740617D01*
G01X741658D02*
X742283Y99300D01*
G01X744550D02*
X744842Y99342D01*
X745175Y99467D01*
X745383Y99675D01*
X745467Y99967D01*
X745383Y100258D01*
X745133Y100508D01*
X744758Y100633D01*
X744342D01*
X744092Y100717D01*
X743883Y100925D01*
X743800Y101217D01*
X743925Y101508D01*
X744217Y101717D01*
X744550Y101800D01*
X744883Y101717D01*
X745175Y101508D01*
X745300Y101217D01*
X745217Y100925D01*
X745008Y100717D01*
X744758Y100633D01*
X744342D01*
X743967Y100508D01*
X743717Y100258D01*
X743633Y99967D01*
X743717Y99675D01*
X743925Y99467D01*
X744258Y99342D01*
X744550Y99300D01*
G01X746733Y99800D02*
X746983Y99508D01*
X747317Y99342D01*
X747692Y99300D01*
X748025Y99342D01*
X748358Y99550D01*
X748567Y99800D01*
X748608Y100050D01*
X748525Y100342D01*
X748233Y100550D01*
X747942Y100633D01*
X747567D01*
G01X747942D02*
X748192Y100758D01*
X748400Y100967D01*
X748483Y101217D01*
X748400Y101467D01*
X748192Y101675D01*
X747817Y101800D01*
X747442Y101758D01*
X747067Y101592D01*
G01X749958Y100342D02*
X750250Y100633D01*
X750500Y100800D01*
X750833Y100883D01*
X751125Y100800D01*
X751333Y100633D01*
X751500Y100383D01*
X751542Y100092D01*
X751500Y99842D01*
X751333Y99592D01*
X751083Y99383D01*
X750792Y99300D01*
X750458Y99383D01*
X750167Y99633D01*
X750000Y100008D01*
X749958Y100425D01*
X750042Y100967D01*
X750167Y101258D01*
X750375Y101550D01*
X750667Y101758D01*
X750958Y101800D01*
X751250Y101717D01*
X751458Y101508D01*
G01X755900Y100800D02*
Y96800D01*
X763300D01*
G01X740617Y95200D02*
Y97700D01*
X741658D01*
X741992Y97575D01*
X742200Y97408D01*
X742283Y97075D01*
X742200Y96742D01*
X741950Y96533D01*
X741658Y96408D01*
X740617D01*
G01X741658D02*
X742283Y95200D01*
G01X744550D02*
X744842Y95242D01*
X745175Y95367D01*
X745383Y95575D01*
X745467Y95867D01*
X745383Y96158D01*
X745133Y96408D01*
X744758Y96533D01*
X744342D01*
X744092Y96617D01*
X743883Y96825D01*
X743800Y97117D01*
X743925Y97408D01*
X744217Y97617D01*
X744550Y97700D01*
X744883Y97617D01*
X745175Y97408D01*
X745300Y97117D01*
X745217Y96825D01*
X745008Y96617D01*
X744758Y96533D01*
X744342D01*
X743967Y96408D01*
X743717Y96158D01*
X743633Y95867D01*
X743717Y95575D01*
X743925Y95367D01*
X744258Y95242D01*
X744550Y95200D01*
G01X746733Y95700D02*
X746983Y95408D01*
X747317Y95242D01*
X747692Y95200D01*
X748025Y95242D01*
X748358Y95450D01*
X748567Y95700D01*
X748608Y95950D01*
X748525Y96242D01*
X748233Y96450D01*
X747942Y96533D01*
X747567D01*
G01X747942D02*
X748192Y96658D01*
X748400Y96867D01*
X748483Y97117D01*
X748400Y97367D01*
X748192Y97575D01*
X747817Y97700D01*
X747442Y97658D01*
X747067Y97492D01*
G01X751250Y95200D02*
Y97700D01*
X749708Y95908D01*
X751792D01*
G01X755900Y96700D02*
Y92700D01*
X763300D01*
G01X744900Y106917D02*
X742400D01*
Y107958D01*
X742525Y108292D01*
X742692Y108500D01*
X743025Y108583D01*
X743358Y108500D01*
X743567Y108250D01*
X743692Y107958D01*
Y106917D01*
G01Y107958D02*
X744900Y108583D01*
G01Y110850D02*
X744858Y111142D01*
X744733Y111475D01*
X744525Y111683D01*
X744233Y111767D01*
X743942Y111683D01*
X743692Y111433D01*
X743567Y111058D01*
Y110642D01*
X743483Y110392D01*
X743275Y110183D01*
X742983Y110100D01*
X742692Y110225D01*
X742483Y110517D01*
X742400Y110850D01*
X742483Y111183D01*
X742692Y111475D01*
X742983Y111600D01*
X743275Y111517D01*
X743483Y111308D01*
X743567Y111058D01*
Y110642D01*
X743692Y110267D01*
X743942Y110017D01*
X744233Y109933D01*
X744525Y110017D01*
X744733Y110225D01*
X744858Y110558D01*
X744900Y110850D01*
G01X744400Y113033D02*
X744692Y113283D01*
X744858Y113617D01*
X744900Y113992D01*
X744858Y114325D01*
X744650Y114658D01*
X744400Y114867D01*
X744150Y114908D01*
X743858Y114825D01*
X743650Y114533D01*
X743567Y114242D01*
Y113867D01*
G01Y114242D02*
X743442Y114492D01*
X743233Y114700D01*
X742983Y114783D01*
X742733Y114700D01*
X742525Y114492D01*
X742400Y114117D01*
X742442Y113742D01*
X742608Y113367D01*
G01X744400Y116133D02*
X744692Y116383D01*
X744858Y116717D01*
X744900Y117092D01*
X744858Y117425D01*
X744650Y117758D01*
X744400Y117967D01*
X744150Y118008D01*
X743858Y117925D01*
X743650Y117633D01*
X743567Y117342D01*
Y116967D01*
G01Y117342D02*
X743442Y117592D01*
X743233Y117800D01*
X742983Y117883D01*
X742733Y117800D01*
X742525Y117592D01*
X742400Y117217D01*
X742442Y116842D01*
X742608Y116467D01*
G01X763300Y102200D02*
X767300D01*
Y109600D01*
G01X740617Y103400D02*
Y105900D01*
X741658D01*
X741992Y105775D01*
X742200Y105608D01*
X742283Y105275D01*
X742200Y104942D01*
X741950Y104733D01*
X741658Y104608D01*
X740617D01*
G01X741658D02*
X742283Y103400D01*
G01X744550D02*
X744842Y103442D01*
X745175Y103567D01*
X745383Y103775D01*
X745467Y104067D01*
X745383Y104358D01*
X745133Y104608D01*
X744758Y104733D01*
X744342D01*
X744092Y104817D01*
X743883Y105025D01*
X743800Y105317D01*
X743925Y105608D01*
X744217Y105817D01*
X744550Y105900D01*
X744883Y105817D01*
X745175Y105608D01*
X745300Y105317D01*
X745217Y105025D01*
X745008Y104817D01*
X744758Y104733D01*
X744342D01*
X743967Y104608D01*
X743717Y104358D01*
X743633Y104067D01*
X743717Y103775D01*
X743925Y103567D01*
X744258Y103442D01*
X744550Y103400D01*
G01X746858Y105483D02*
X747108Y105733D01*
X747400Y105858D01*
X747733Y105900D01*
X748150Y105817D01*
X748442Y105608D01*
X748525Y105358D01*
X748483Y105108D01*
X748317Y104900D01*
X747483Y104483D01*
X747108Y104192D01*
X746858Y103775D01*
X746775Y103400D01*
X748525D01*
G01X751250D02*
Y105900D01*
X749708Y104108D01*
X751792D01*
G01X763300Y100900D02*
Y104900D01*
X755900D01*
G01X740617Y82800D02*
Y85300D01*
X741658D01*
X741992Y85175D01*
X742200Y85008D01*
X742283Y84675D01*
X742200Y84342D01*
X741950Y84133D01*
X741658Y84008D01*
X740617D01*
G01X741658D02*
X742283Y82800D01*
G01X743758Y83842D02*
X744050Y84133D01*
X744300Y84300D01*
X744633Y84383D01*
X744925Y84300D01*
X745133Y84133D01*
X745300Y83883D01*
X745342Y83592D01*
X745300Y83342D01*
X745133Y83092D01*
X744883Y82883D01*
X744592Y82800D01*
X744258Y82883D01*
X743967Y83133D01*
X743800Y83508D01*
X743758Y83925D01*
X743842Y84467D01*
X743967Y84758D01*
X744175Y85050D01*
X744467Y85258D01*
X744758Y85300D01*
X745050Y85217D01*
X745258Y85008D01*
G01X746942Y83092D02*
X747233Y82883D01*
X747567Y82800D01*
X747900Y82883D01*
X748192Y83133D01*
X748400Y83508D01*
X748483Y83883D01*
Y84342D01*
X748400Y84717D01*
X748192Y85050D01*
X747942Y85217D01*
X747650Y85300D01*
X747317Y85217D01*
X747067Y85050D01*
X746900Y84800D01*
X746817Y84467D01*
X746900Y84175D01*
X747108Y83883D01*
X747358Y83717D01*
X747650Y83675D01*
X747983Y83758D01*
X748233Y83967D01*
X748483Y84342D01*
G01X750042Y83092D02*
X750333Y82883D01*
X750667Y82800D01*
X751000Y82883D01*
X751292Y83133D01*
X751500Y83508D01*
X751583Y83883D01*
Y84342D01*
X751500Y84717D01*
X751292Y85050D01*
X751042Y85217D01*
X750750Y85300D01*
X750417Y85217D01*
X750167Y85050D01*
X750000Y84800D01*
X749917Y84467D01*
X750000Y84175D01*
X750208Y83883D01*
X750458Y83717D01*
X750750Y83675D01*
X751083Y83758D01*
X751333Y83967D01*
X751583Y84342D01*
G01X763300Y80300D02*
Y84300D01*
X755900D01*
G01X739667Y78700D02*
Y76200D01*
X741333D01*
G01X744433D02*
X742767D01*
Y78700D01*
X744433D01*
G01X743767Y77492D02*
X742767D01*
G01X745783Y76200D02*
Y78700D01*
X746617D01*
X746950Y78575D01*
X747200Y78408D01*
X747408Y78158D01*
X747575Y77867D01*
X747617Y77450D01*
X747575Y77033D01*
X747408Y76742D01*
X747200Y76492D01*
X746950Y76325D01*
X746617Y76200D01*
X745783D01*
G01X749008Y78283D02*
X749258Y78533D01*
X749550Y78658D01*
X749883Y78700D01*
X750300Y78617D01*
X750592Y78408D01*
X750675Y78158D01*
X750633Y77908D01*
X750467Y77700D01*
X749633Y77283D01*
X749258Y76992D01*
X749008Y76575D01*
X748925Y76200D01*
X750675D01*
G01X752900Y78700D02*
X752567Y78617D01*
X752317Y78408D01*
X752150Y78158D01*
X752025Y77825D01*
X751983Y77450D01*
X752025Y77075D01*
X752150Y76742D01*
X752317Y76492D01*
X752567Y76283D01*
X752900Y76200D01*
X753233Y76283D01*
X753483Y76492D01*
X753650Y76742D01*
X753775Y77075D01*
X753817Y77450D01*
X753775Y77825D01*
X753650Y78158D01*
X753483Y78408D01*
X753233Y78617D01*
X752900Y78700D01*
G01X749719Y123933D02*
Y126433D01*
X750760D01*
X751094Y126308D01*
X751302Y126141D01*
X751385Y125808D01*
X751302Y125475D01*
X751052Y125266D01*
X750760Y125141D01*
X749719D01*
G01X750760D02*
X751385Y123933D01*
G01X753652D02*
X753944Y123975D01*
X754277Y124100D01*
X754485Y124308D01*
X754569Y124600D01*
X754485Y124891D01*
X754235Y125141D01*
X753860Y125266D01*
X753444D01*
X753194Y125350D01*
X752985Y125558D01*
X752902Y125850D01*
X753027Y126141D01*
X753319Y126350D01*
X753652Y126433D01*
X753985Y126350D01*
X754277Y126141D01*
X754402Y125850D01*
X754319Y125558D01*
X754110Y125350D01*
X753860Y125266D01*
X753444D01*
X753069Y125141D01*
X752819Y124891D01*
X752735Y124600D01*
X752819Y124308D01*
X753027Y124100D01*
X753360Y123975D01*
X753652Y123933D01*
G01X756752Y126433D02*
X756419Y126350D01*
X756169Y126141D01*
X756002Y125891D01*
X755877Y125558D01*
X755835Y125183D01*
X755877Y124808D01*
X756002Y124475D01*
X756169Y124225D01*
X756419Y124016D01*
X756752Y123933D01*
X757085Y124016D01*
X757335Y124225D01*
X757502Y124475D01*
X757627Y124808D01*
X757669Y125183D01*
X757627Y125558D01*
X757502Y125891D01*
X757335Y126141D01*
X757085Y126350D01*
X756752Y126433D01*
G01X759852D02*
X759519Y126350D01*
X759269Y126141D01*
X759102Y125891D01*
X758977Y125558D01*
X758935Y125183D01*
X758977Y124808D01*
X759102Y124475D01*
X759269Y124225D01*
X759519Y124016D01*
X759852Y123933D01*
X760185Y124016D01*
X760435Y124225D01*
X760602Y124475D01*
X760727Y124808D01*
X760769Y125183D01*
X760727Y125558D01*
X760602Y125891D01*
X760435Y126141D01*
X760185Y126350D01*
X759852Y126433D01*
G01X770900Y119200D02*
Y123200D01*
X763500D01*
G01X766517Y141667D02*
Y144167D01*
X767558D01*
X767892Y144042D01*
X768100Y143875D01*
X768183Y143542D01*
X768100Y143209D01*
X767850Y143000D01*
X767558Y142875D01*
X766517D01*
G01X767558D02*
X768183Y141667D01*
G01X770367D02*
X770450Y142209D01*
X770575Y142667D01*
X770742Y143084D01*
X770950Y143542D01*
X771283Y144167D01*
X769617D01*
G01X772842Y141959D02*
X773133Y141750D01*
X773467Y141667D01*
X773800Y141750D01*
X774092Y142000D01*
X774300Y142375D01*
X774383Y142750D01*
Y143209D01*
X774300Y143584D01*
X774092Y143917D01*
X773842Y144084D01*
X773550Y144167D01*
X773217Y144084D01*
X772967Y143917D01*
X772800Y143667D01*
X772717Y143334D01*
X772800Y143042D01*
X773008Y142750D01*
X773258Y142584D01*
X773550Y142542D01*
X773883Y142625D01*
X774133Y142834D01*
X774383Y143209D01*
G01X776650Y141667D02*
Y144167D01*
X776150Y143667D01*
G01Y141667D02*
X777150D01*
G01X771600Y137200D02*
Y133200D01*
X779000D01*
G01X749719Y132133D02*
Y134633D01*
X750760D01*
X751094Y134508D01*
X751302Y134341D01*
X751385Y134008D01*
X751302Y133675D01*
X751052Y133466D01*
X750760Y133341D01*
X749719D01*
G01X750760D02*
X751385Y132133D01*
G01X753569D02*
X753652Y132675D01*
X753777Y133133D01*
X753944Y133550D01*
X754152Y134008D01*
X754485Y134633D01*
X752819D01*
G01X756669Y132133D02*
X756752Y132675D01*
X756877Y133133D01*
X757044Y133550D01*
X757252Y134008D01*
X757585Y134633D01*
X755919D01*
G01X759852Y132133D02*
X760144Y132175D01*
X760477Y132300D01*
X760685Y132508D01*
X760769Y132800D01*
X760685Y133091D01*
X760435Y133341D01*
X760060Y133466D01*
X759644D01*
X759394Y133550D01*
X759185Y133758D01*
X759102Y134050D01*
X759227Y134341D01*
X759519Y134550D01*
X759852Y134633D01*
X760185Y134550D01*
X760477Y134341D01*
X760602Y134050D01*
X760519Y133758D01*
X760310Y133550D01*
X760060Y133466D01*
X759644D01*
X759269Y133341D01*
X759019Y133091D01*
X758935Y132800D01*
X759019Y132508D01*
X759227Y132300D01*
X759560Y132175D01*
X759852Y132133D01*
G01X763500Y131400D02*
Y127400D01*
X770900D01*
G01X749719Y128033D02*
Y130533D01*
X750760D01*
X751094Y130408D01*
X751302Y130241D01*
X751385Y129908D01*
X751302Y129575D01*
X751052Y129366D01*
X750760Y129241D01*
X749719D01*
G01X750760D02*
X751385Y128033D01*
G01X753569D02*
X753652Y128575D01*
X753777Y129033D01*
X753944Y129450D01*
X754152Y129908D01*
X754485Y130533D01*
X752819D01*
G01X756669Y128033D02*
X756752Y128575D01*
X756877Y129033D01*
X757044Y129450D01*
X757252Y129908D01*
X757585Y130533D01*
X755919D01*
G01X760352Y128033D02*
Y130533D01*
X758810Y128741D01*
X760894D01*
G01X763500Y127300D02*
Y123300D01*
X770900D01*
G01X749719Y136233D02*
Y138733D01*
X750760D01*
X751094Y138608D01*
X751302Y138441D01*
X751385Y138108D01*
X751302Y137775D01*
X751052Y137566D01*
X750760Y137441D01*
X749719D01*
G01X750760D02*
X751385Y136233D01*
G01X753569D02*
X753652Y136775D01*
X753777Y137233D01*
X753944Y137650D01*
X754152Y138108D01*
X754485Y138733D01*
X752819D01*
G01X755960Y137275D02*
X756252Y137566D01*
X756502Y137733D01*
X756835Y137816D01*
X757127Y137733D01*
X757335Y137566D01*
X757502Y137316D01*
X757544Y137025D01*
X757502Y136775D01*
X757335Y136525D01*
X757085Y136316D01*
X756794Y136233D01*
X756460Y136316D01*
X756169Y136566D01*
X756002Y136941D01*
X755960Y137358D01*
X756044Y137900D01*
X756169Y138191D01*
X756377Y138483D01*
X756669Y138691D01*
X756960Y138733D01*
X757252Y138650D01*
X757460Y138441D01*
G01X758935Y136733D02*
X759185Y136441D01*
X759519Y136275D01*
X759894Y136233D01*
X760227Y136275D01*
X760560Y136483D01*
X760769Y136733D01*
X760810Y136983D01*
X760727Y137275D01*
X760435Y137483D01*
X760144Y137566D01*
X759769D01*
G01X760144D02*
X760394Y137691D01*
X760602Y137900D01*
X760685Y138150D01*
X760602Y138400D01*
X760394Y138608D01*
X760019Y138733D01*
X759644Y138691D01*
X759269Y138525D01*
G01X770900Y131500D02*
Y135500D01*
X763500D01*
G01X742067Y119300D02*
Y121800D01*
X743108D01*
X743442Y121675D01*
X743650Y121508D01*
X743733Y121175D01*
X743650Y120842D01*
X743400Y120633D01*
X743108Y120508D01*
X742067D01*
G01X743108D02*
X743733Y119300D01*
G01X745292Y119592D02*
X745583Y119383D01*
X745917Y119300D01*
X746250Y119383D01*
X746542Y119633D01*
X746750Y120008D01*
X746833Y120383D01*
Y120842D01*
X746750Y121217D01*
X746542Y121550D01*
X746292Y121717D01*
X746000Y121800D01*
X745667Y121717D01*
X745417Y121550D01*
X745250Y121300D01*
X745167Y120967D01*
X745250Y120675D01*
X745458Y120383D01*
X745708Y120217D01*
X746000Y120175D01*
X746333Y120258D01*
X746583Y120467D01*
X746833Y120842D01*
G01X749100Y121800D02*
X748767Y121717D01*
X748517Y121508D01*
X748350Y121258D01*
X748225Y120925D01*
X748183Y120550D01*
X748225Y120175D01*
X748350Y119842D01*
X748517Y119592D01*
X748767Y119383D01*
X749100Y119300D01*
X749433Y119383D01*
X749683Y119592D01*
X749850Y119842D01*
X749975Y120175D01*
X750017Y120550D01*
X749975Y120925D01*
X749850Y121258D01*
X749683Y121508D01*
X749433Y121717D01*
X749100Y121800D01*
G01X761200Y116800D02*
Y120800D01*
X753800D01*
G01X744039Y191918D02*
Y233318D01*
G01X753145Y198959D02*
X753020Y198709D01*
X752937Y198417D01*
Y198084D01*
X753062Y197709D01*
X753270Y197417D01*
X753520Y197209D01*
X753937Y197042D01*
X754312Y197000D01*
X754687Y197084D01*
X754937Y197209D01*
X755187Y197459D01*
X755354Y197750D01*
X755437Y198042D01*
Y198334D01*
X755354Y198625D01*
X755229Y198875D01*
X755062Y199084D01*
G01Y200225D02*
X755270Y200475D01*
X755395Y200767D01*
X755437Y201142D01*
X755354Y201517D01*
X755187Y201809D01*
X754895Y202017D01*
X754562Y202059D01*
X754229Y201975D01*
X754020Y201767D01*
X753854Y201475D01*
X753812Y201184D01*
X753854Y200892D01*
X754020Y200517D01*
X752937Y200642D01*
Y201767D01*
G01X755437Y204242D02*
X752937D01*
X753437Y203742D01*
G01X755437D02*
Y204742D01*
G01Y207342D02*
X755395Y207634D01*
X755270Y207967D01*
X755062Y208175D01*
X754770Y208259D01*
X754479Y208175D01*
X754229Y207925D01*
X754104Y207550D01*
Y207134D01*
X754020Y206884D01*
X753812Y206675D01*
X753520Y206592D01*
X753229Y206717D01*
X753020Y207009D01*
X752937Y207342D01*
X753020Y207675D01*
X753229Y207967D01*
X753520Y208092D01*
X753812Y208009D01*
X754020Y207800D01*
X754104Y207550D01*
Y207134D01*
X754229Y206759D01*
X754479Y206509D01*
X754770Y206425D01*
X755062Y206509D01*
X755270Y206717D01*
X755395Y207050D01*
X755437Y207342D01*
G01X752976Y237911D02*
X752851Y237661D01*
X752768Y237369D01*
Y237036D01*
X752893Y236661D01*
X753101Y236369D01*
X753351Y236161D01*
X753768Y235994D01*
X754143Y235952D01*
X754518Y236036D01*
X754768Y236161D01*
X755018Y236411D01*
X755185Y236702D01*
X755268Y236994D01*
Y237286D01*
X755185Y237577D01*
X755060Y237827D01*
X754893Y238036D01*
G01Y239177D02*
X755101Y239427D01*
X755226Y239719D01*
X755268Y240094D01*
X755185Y240469D01*
X755018Y240761D01*
X754726Y240969D01*
X754393Y241011D01*
X754060Y240927D01*
X753851Y240719D01*
X753685Y240427D01*
X753643Y240136D01*
X753685Y239844D01*
X753851Y239469D01*
X752768Y239594D01*
Y240719D01*
G01X755268Y243111D02*
X754726Y243194D01*
X754268Y243319D01*
X753851Y243486D01*
X753393Y243694D01*
X752768Y244027D01*
Y242361D01*
G01X753185Y245502D02*
X752935Y245752D01*
X752810Y246044D01*
X752768Y246377D01*
X752851Y246794D01*
X753060Y247086D01*
X753310Y247169D01*
X753560Y247127D01*
X753768Y246961D01*
X754185Y246127D01*
X754476Y245752D01*
X754893Y245502D01*
X755268Y245419D01*
Y247169D01*
G01X748976Y237911D02*
X748851Y237661D01*
X748768Y237369D01*
Y237036D01*
X748893Y236661D01*
X749101Y236369D01*
X749351Y236161D01*
X749768Y235994D01*
X750143Y235952D01*
X750518Y236036D01*
X750768Y236161D01*
X751018Y236411D01*
X751185Y236702D01*
X751268Y236994D01*
Y237286D01*
X751185Y237577D01*
X751060Y237827D01*
X750893Y238036D01*
G01Y239177D02*
X751101Y239427D01*
X751226Y239719D01*
X751268Y240094D01*
X751185Y240469D01*
X751018Y240761D01*
X750726Y240969D01*
X750393Y241011D01*
X750060Y240927D01*
X749851Y240719D01*
X749685Y240427D01*
X749643Y240136D01*
X749685Y239844D01*
X749851Y239469D01*
X748768Y239594D01*
Y240719D01*
G01X750226Y242402D02*
X749935Y242694D01*
X749768Y242944D01*
X749685Y243277D01*
X749768Y243569D01*
X749935Y243777D01*
X750185Y243944D01*
X750476Y243986D01*
X750726Y243944D01*
X750976Y243777D01*
X751185Y243527D01*
X751268Y243236D01*
X751185Y242902D01*
X750935Y242611D01*
X750560Y242444D01*
X750143Y242402D01*
X749601Y242486D01*
X749310Y242611D01*
X749018Y242819D01*
X748810Y243111D01*
X748768Y243402D01*
X748851Y243694D01*
X749060Y243902D01*
G01X751268Y246794D02*
X748768D01*
X750560Y245252D01*
Y247336D01*
G01X744976Y237911D02*
X744851Y237661D01*
X744768Y237369D01*
Y237036D01*
X744893Y236661D01*
X745101Y236369D01*
X745351Y236161D01*
X745768Y235994D01*
X746143Y235952D01*
X746518Y236036D01*
X746768Y236161D01*
X747018Y236411D01*
X747185Y236702D01*
X747268Y236994D01*
Y237286D01*
X747185Y237577D01*
X747060Y237827D01*
X746893Y238036D01*
G01Y239177D02*
X747101Y239427D01*
X747226Y239719D01*
X747268Y240094D01*
X747185Y240469D01*
X747018Y240761D01*
X746726Y240969D01*
X746393Y241011D01*
X746060Y240927D01*
X745851Y240719D01*
X745685Y240427D01*
X745643Y240136D01*
X745685Y239844D01*
X745851Y239469D01*
X744768Y239594D01*
Y240719D01*
G01X746226Y242402D02*
X745935Y242694D01*
X745768Y242944D01*
X745685Y243277D01*
X745768Y243569D01*
X745935Y243777D01*
X746185Y243944D01*
X746476Y243986D01*
X746726Y243944D01*
X746976Y243777D01*
X747185Y243527D01*
X747268Y243236D01*
X747185Y242902D01*
X746935Y242611D01*
X746560Y242444D01*
X746143Y242402D01*
X745601Y242486D01*
X745310Y242611D01*
X745018Y242819D01*
X744810Y243111D01*
X744768Y243402D01*
X744851Y243694D01*
X745060Y243902D01*
G01X744768Y246294D02*
X744851Y245961D01*
X745060Y245711D01*
X745310Y245544D01*
X745643Y245419D01*
X746018Y245377D01*
X746393Y245419D01*
X746726Y245544D01*
X746976Y245711D01*
X747185Y245961D01*
X747268Y246294D01*
X747185Y246627D01*
X746976Y246877D01*
X746726Y247044D01*
X746393Y247169D01*
X746018Y247211D01*
X745643Y247169D01*
X745310Y247044D01*
X745060Y246877D01*
X744851Y246627D01*
X744768Y246294D01*
G01X740976Y237911D02*
X740851Y237661D01*
X740768Y237369D01*
Y237036D01*
X740893Y236661D01*
X741101Y236369D01*
X741351Y236161D01*
X741768Y235994D01*
X742143Y235952D01*
X742518Y236036D01*
X742768Y236161D01*
X743018Y236411D01*
X743185Y236702D01*
X743268Y236994D01*
Y237286D01*
X743185Y237577D01*
X743060Y237827D01*
X742893Y238036D01*
G01Y239177D02*
X743101Y239427D01*
X743226Y239719D01*
X743268Y240094D01*
X743185Y240469D01*
X743018Y240761D01*
X742726Y240969D01*
X742393Y241011D01*
X742060Y240927D01*
X741851Y240719D01*
X741685Y240427D01*
X741643Y240136D01*
X741685Y239844D01*
X741851Y239469D01*
X740768Y239594D01*
Y240719D01*
G01X742893Y242277D02*
X743101Y242527D01*
X743226Y242819D01*
X743268Y243194D01*
X743185Y243569D01*
X743018Y243861D01*
X742726Y244069D01*
X742393Y244111D01*
X742060Y244027D01*
X741851Y243819D01*
X741685Y243527D01*
X741643Y243236D01*
X741685Y242944D01*
X741851Y242569D01*
X740768Y242694D01*
Y243819D01*
G01X742976Y245586D02*
X743185Y245877D01*
X743268Y246211D01*
X743185Y246544D01*
X742935Y246836D01*
X742560Y247044D01*
X742185Y247127D01*
X741726D01*
X741351Y247044D01*
X741018Y246836D01*
X740851Y246586D01*
X740768Y246294D01*
X740851Y245961D01*
X741018Y245711D01*
X741268Y245544D01*
X741601Y245461D01*
X741893Y245544D01*
X742185Y245752D01*
X742351Y246002D01*
X742393Y246294D01*
X742310Y246627D01*
X742101Y246877D01*
X741726Y247127D01*
G01X741867Y402300D02*
Y404800D01*
X742867D01*
X743200Y404675D01*
X743450Y404383D01*
X743533Y404050D01*
X743450Y403717D01*
X743242Y403467D01*
X742867Y403342D01*
X741867D01*
G01X744967Y402300D02*
Y404800D01*
X746008D01*
X746342Y404675D01*
X746550Y404508D01*
X746633Y404175D01*
X746550Y403842D01*
X746300Y403633D01*
X746008Y403508D01*
X744967D01*
G01X746008D02*
X746633Y402300D01*
G01X748900D02*
Y404800D01*
X748400Y404300D01*
G01Y402300D02*
X749400D01*
G01X751917D02*
X752000Y402842D01*
X752125Y403300D01*
X752292Y403717D01*
X752500Y404175D01*
X752833Y404800D01*
X751167D01*
G01X754308Y404383D02*
X754558Y404633D01*
X754850Y404758D01*
X755183Y404800D01*
X755600Y404717D01*
X755892Y404508D01*
X755975Y404258D01*
X755933Y404008D01*
X755767Y403800D01*
X754933Y403383D01*
X754558Y403092D01*
X754308Y402675D01*
X754225Y402300D01*
X755975D01*
G01X741863Y410575D02*
X739363D01*
Y411575D01*
X739488Y411908D01*
X739780Y412158D01*
X740113Y412241D01*
X740446Y412158D01*
X740696Y411950D01*
X740821Y411575D01*
Y410575D01*
G01X741863Y413675D02*
X739363D01*
Y414716D01*
X739488Y415050D01*
X739655Y415258D01*
X739988Y415341D01*
X740321Y415258D01*
X740530Y415008D01*
X740655Y414716D01*
Y413675D01*
G01Y414716D02*
X741863Y415341D01*
G01Y417608D02*
X739363D01*
X739863Y417108D01*
G01X741863D02*
Y418108D01*
G01X740821Y419916D02*
X740530Y420208D01*
X740363Y420458D01*
X740280Y420791D01*
X740363Y421083D01*
X740530Y421291D01*
X740780Y421458D01*
X741071Y421500D01*
X741321Y421458D01*
X741571Y421291D01*
X741780Y421041D01*
X741863Y420750D01*
X741780Y420416D01*
X741530Y420125D01*
X741155Y419958D01*
X740738Y419916D01*
X740196Y420000D01*
X739905Y420125D01*
X739613Y420333D01*
X739405Y420625D01*
X739363Y420916D01*
X739446Y421208D01*
X739655Y421416D01*
G01X741863Y423725D02*
X741321Y423808D01*
X740863Y423933D01*
X740446Y424100D01*
X739988Y424308D01*
X739363Y424641D01*
Y422975D01*
G01X748630Y393908D02*
Y396408D01*
X749671D01*
X750005Y396283D01*
X750213Y396116D01*
X750296Y395783D01*
X750213Y395450D01*
X749963Y395241D01*
X749671Y395116D01*
X748630D01*
G01X749671D02*
X750296Y393908D01*
G01X752480D02*
X752563Y394450D01*
X752688Y394908D01*
X752855Y395325D01*
X753063Y395783D01*
X753396Y396408D01*
X751730D01*
G01X754871Y394950D02*
X755163Y395241D01*
X755413Y395408D01*
X755746Y395491D01*
X756038Y395408D01*
X756246Y395241D01*
X756413Y394991D01*
X756455Y394700D01*
X756413Y394450D01*
X756246Y394200D01*
X755996Y393991D01*
X755705Y393908D01*
X755371Y393991D01*
X755080Y394241D01*
X754913Y394616D01*
X754871Y395033D01*
X754955Y395575D01*
X755080Y395866D01*
X755288Y396158D01*
X755580Y396366D01*
X755871Y396408D01*
X756163Y396325D01*
X756371Y396116D01*
G01X748630Y398008D02*
Y400508D01*
X749671D01*
X750005Y400383D01*
X750213Y400216D01*
X750296Y399883D01*
X750213Y399550D01*
X749963Y399341D01*
X749671Y399216D01*
X748630D01*
G01X749671D02*
X750296Y398008D01*
G01X752480D02*
X752563Y398550D01*
X752688Y399008D01*
X752855Y399425D01*
X753063Y399883D01*
X753396Y400508D01*
X751730D01*
G01X754955Y398300D02*
X755246Y398091D01*
X755580Y398008D01*
X755913Y398091D01*
X756205Y398341D01*
X756413Y398716D01*
X756496Y399091D01*
Y399550D01*
X756413Y399925D01*
X756205Y400258D01*
X755955Y400425D01*
X755663Y400508D01*
X755330Y400425D01*
X755080Y400258D01*
X754913Y400008D01*
X754830Y399675D01*
X754913Y399383D01*
X755121Y399091D01*
X755371Y398925D01*
X755663Y398883D01*
X755996Y398966D01*
X756246Y399175D01*
X756496Y399550D01*
G01X756933Y418333D02*
X752267D01*
Y426333D01*
X756933D01*
G01X755067Y422466D02*
X752267D01*
G01X740078Y816633D02*
X739953Y816383D01*
X739870Y816091D01*
Y815758D01*
X739995Y815383D01*
X740203Y815091D01*
X740453Y814883D01*
X740870Y814716D01*
X741245Y814674D01*
X741620Y814758D01*
X741870Y814883D01*
X742120Y815133D01*
X742287Y815424D01*
X742370Y815716D01*
Y816008D01*
X742287Y816299D01*
X742162Y816549D01*
X741995Y816758D01*
G01X742370Y818816D02*
X739870D01*
X740370Y818316D01*
G01X742370D02*
Y819316D01*
G01X740287Y821124D02*
X740037Y821374D01*
X739912Y821666D01*
X739870Y821999D01*
X739953Y822416D01*
X740162Y822708D01*
X740412Y822791D01*
X740662Y822749D01*
X740870Y822583D01*
X741287Y821749D01*
X741578Y821374D01*
X741995Y821124D01*
X742370Y821041D01*
Y822791D01*
G01Y825516D02*
X739870D01*
X741662Y823974D01*
Y826058D01*
G01X748677Y816633D02*
X748552Y816383D01*
X748469Y816091D01*
Y815758D01*
X748594Y815383D01*
X748802Y815091D01*
X749052Y814883D01*
X749469Y814716D01*
X749844Y814674D01*
X750219Y814758D01*
X750469Y814883D01*
X750719Y815133D01*
X750886Y815424D01*
X750969Y815716D01*
Y816008D01*
X750886Y816299D01*
X750761Y816549D01*
X750594Y816758D01*
G01X750969Y818816D02*
X748469D01*
X748969Y818316D01*
G01X750969D02*
Y819316D01*
G01X748886Y821124D02*
X748636Y821374D01*
X748511Y821666D01*
X748469Y821999D01*
X748552Y822416D01*
X748761Y822708D01*
X749011Y822791D01*
X749261Y822749D01*
X749469Y822583D01*
X749886Y821749D01*
X750177Y821374D01*
X750594Y821124D01*
X750969Y821041D01*
Y822791D01*
G01X750469Y824099D02*
X750761Y824349D01*
X750927Y824683D01*
X750969Y825058D01*
X750927Y825391D01*
X750719Y825724D01*
X750469Y825933D01*
X750219Y825974D01*
X749927Y825891D01*
X749719Y825599D01*
X749636Y825308D01*
Y824933D01*
G01Y825308D02*
X749511Y825558D01*
X749302Y825766D01*
X749052Y825849D01*
X748802Y825766D01*
X748594Y825558D01*
X748469Y825183D01*
X748511Y824808D01*
X748677Y824433D01*
G01X752677Y816633D02*
X752552Y816383D01*
X752469Y816091D01*
Y815758D01*
X752594Y815383D01*
X752802Y815091D01*
X753052Y814883D01*
X753469Y814716D01*
X753844Y814674D01*
X754219Y814758D01*
X754469Y814883D01*
X754719Y815133D01*
X754886Y815424D01*
X754969Y815716D01*
Y816008D01*
X754886Y816299D01*
X754761Y816549D01*
X754594Y816758D01*
G01X754969Y818816D02*
X752469D01*
X752969Y818316D01*
G01X754969D02*
Y819316D01*
G01X752886Y821124D02*
X752636Y821374D01*
X752511Y821666D01*
X752469Y821999D01*
X752552Y822416D01*
X752761Y822708D01*
X753011Y822791D01*
X753261Y822749D01*
X753469Y822583D01*
X753886Y821749D01*
X754177Y821374D01*
X754594Y821124D01*
X754969Y821041D01*
Y822791D01*
G01X752886Y824224D02*
X752636Y824474D01*
X752511Y824766D01*
X752469Y825099D01*
X752552Y825516D01*
X752761Y825808D01*
X753011Y825891D01*
X753261Y825849D01*
X753469Y825683D01*
X753886Y824849D01*
X754177Y824474D01*
X754594Y824224D01*
X754969Y824141D01*
Y825891D01*
G01X761275Y816633D02*
X761150Y816383D01*
X761067Y816091D01*
Y815758D01*
X761192Y815383D01*
X761400Y815091D01*
X761650Y814883D01*
X762067Y814716D01*
X762442Y814674D01*
X762817Y814758D01*
X763067Y814883D01*
X763317Y815133D01*
X763484Y815424D01*
X763567Y815716D01*
Y816008D01*
X763484Y816299D01*
X763359Y816549D01*
X763192Y816758D01*
G01X763567Y818816D02*
X761067D01*
X761567Y818316D01*
G01X763567D02*
Y819316D01*
G01X761484Y821124D02*
X761234Y821374D01*
X761109Y821666D01*
X761067Y821999D01*
X761150Y822416D01*
X761359Y822708D01*
X761609Y822791D01*
X761859Y822749D01*
X762067Y822583D01*
X762484Y821749D01*
X762775Y821374D01*
X763192Y821124D01*
X763567Y821041D01*
Y822791D01*
G01Y825016D02*
X761067D01*
X761567Y824516D01*
G01X763567D02*
Y825516D01*
G01X765275Y816633D02*
X765150Y816383D01*
X765067Y816091D01*
Y815758D01*
X765192Y815383D01*
X765400Y815091D01*
X765650Y814883D01*
X766067Y814716D01*
X766442Y814674D01*
X766817Y814758D01*
X767067Y814883D01*
X767317Y815133D01*
X767484Y815424D01*
X767567Y815716D01*
Y816008D01*
X767484Y816299D01*
X767359Y816549D01*
X767192Y816758D01*
G01X767567Y818816D02*
X765067D01*
X765567Y818316D01*
G01X767567D02*
Y819316D01*
G01X765484Y821124D02*
X765234Y821374D01*
X765109Y821666D01*
X765067Y821999D01*
X765150Y822416D01*
X765359Y822708D01*
X765609Y822791D01*
X765859Y822749D01*
X766067Y822583D01*
X766484Y821749D01*
X766775Y821374D01*
X767192Y821124D01*
X767567Y821041D01*
Y822791D01*
G01X765067Y825016D02*
X765150Y824683D01*
X765359Y824433D01*
X765609Y824266D01*
X765942Y824141D01*
X766317Y824099D01*
X766692Y824141D01*
X767025Y824266D01*
X767275Y824433D01*
X767484Y824683D01*
X767567Y825016D01*
X767484Y825349D01*
X767275Y825599D01*
X767025Y825766D01*
X766692Y825891D01*
X766317Y825933D01*
X765942Y825891D01*
X765609Y825766D01*
X765359Y825599D01*
X765150Y825349D01*
X765067Y825016D01*
G01X783217Y-9333D02*
Y-6833D01*
X784258D01*
X784592Y-6958D01*
X784800Y-7125D01*
X784883Y-7458D01*
X784800Y-7791D01*
X784550Y-8000D01*
X784258Y-8125D01*
X783217D01*
G01X784258D02*
X784883Y-9333D01*
G01X786233Y-8958D02*
X786483Y-9166D01*
X786775Y-9291D01*
X787150Y-9333D01*
X787525Y-9250D01*
X787817Y-9083D01*
X788025Y-8791D01*
X788067Y-8458D01*
X787983Y-8125D01*
X787775Y-7916D01*
X787483Y-7750D01*
X787192Y-7708D01*
X786900Y-7750D01*
X786525Y-7916D01*
X786650Y-6833D01*
X787775D01*
G01X790750Y-9333D02*
Y-6833D01*
X789208Y-8625D01*
X791292D01*
G01X792433Y-8833D02*
X792683Y-9125D01*
X793017Y-9291D01*
X793392Y-9333D01*
X793725Y-9291D01*
X794058Y-9083D01*
X794267Y-8833D01*
X794308Y-8583D01*
X794225Y-8291D01*
X793933Y-8083D01*
X793642Y-8000D01*
X793267D01*
G01X793642D02*
X793892Y-7875D01*
X794100Y-7666D01*
X794183Y-7416D01*
X794100Y-7166D01*
X793892Y-6958D01*
X793517Y-6833D01*
X793142Y-6875D01*
X792767Y-7041D01*
G01X779600Y-5400D02*
Y7600D01*
G01X798600D02*
Y-5400D01*
G01D02*
X779600D01*
G01X804517Y-8333D02*
Y-10833D01*
X806183D01*
G01X809283D02*
X807617D01*
Y-8333D01*
X809283D01*
G01X808617Y-9541D02*
X807617D01*
G01X810633Y-10833D02*
Y-8333D01*
X811467D01*
X811800Y-8458D01*
X812050Y-8625D01*
X812258Y-8875D01*
X812425Y-9166D01*
X812467Y-9583D01*
X812425Y-10000D01*
X812258Y-10291D01*
X812050Y-10541D01*
X811800Y-10708D01*
X811467Y-10833D01*
X810633D01*
G01X813733Y-10458D02*
X813983Y-10666D01*
X814275Y-10791D01*
X814650Y-10833D01*
X815025Y-10750D01*
X815317Y-10583D01*
X815525Y-10291D01*
X815567Y-9958D01*
X815483Y-9625D01*
X815275Y-9416D01*
X814983Y-9250D01*
X814692Y-9208D01*
X814400Y-9250D01*
X814025Y-9416D01*
X814150Y-8333D01*
X815275D01*
G01X804274Y-3300D02*
G03X814624I5175J1348D01*
G01X818899Y3300D02*
X799999D01*
G01D02*
Y-3300D01*
G01D02*
X804274D01*
G01X800417Y5800D02*
X800625Y5550D01*
X800875Y5383D01*
X801167Y5300D01*
X801500Y5383D01*
X801750Y5550D01*
X802000Y5800D01*
X802083Y6133D01*
Y7800D01*
G01X803517Y5300D02*
Y7800D01*
X804517D01*
X804850Y7675D01*
X805100Y7383D01*
X805183Y7050D01*
X805100Y6717D01*
X804892Y6467D01*
X804517Y6342D01*
X803517D01*
G01X807450Y5300D02*
Y7800D01*
X806950Y7300D01*
G01Y5300D02*
X807950D01*
G01X810550Y7800D02*
X810217Y7717D01*
X809967Y7508D01*
X809800Y7258D01*
X809675Y6925D01*
X809633Y6550D01*
X809675Y6175D01*
X809800Y5842D01*
X809967Y5592D01*
X810217Y5383D01*
X810550Y5300D01*
X810883Y5383D01*
X811133Y5592D01*
X811300Y5842D01*
X811425Y6175D01*
X811467Y6550D01*
X811425Y6925D01*
X811300Y7258D01*
X811133Y7508D01*
X810883Y7717D01*
X810550Y7800D01*
G01X776594Y35891D02*
Y32184D01*
X774263D01*
Y23419D01*
X775763Y24919D01*
X772763D01*
X774263Y23419D01*
G01X779600Y7600D02*
X798600D01*
G01X775718Y28666D02*
Y31166D01*
X776759D01*
X777093Y31041D01*
X777301Y30874D01*
X777384Y30541D01*
X777301Y30208D01*
X777051Y29999D01*
X776759Y29874D01*
X775718D01*
G01X776759D02*
X777384Y28666D01*
G01X778734Y29166D02*
X778984Y28874D01*
X779318Y28708D01*
X779693Y28666D01*
X780026Y28708D01*
X780359Y28916D01*
X780568Y29166D01*
X780609Y29416D01*
X780526Y29708D01*
X780234Y29916D01*
X779943Y29999D01*
X779568D01*
G01X779943D02*
X780193Y30124D01*
X780401Y30333D01*
X780484Y30583D01*
X780401Y30833D01*
X780193Y31041D01*
X779818Y31166D01*
X779443Y31124D01*
X779068Y30958D01*
G01X782751Y31166D02*
X782418Y31083D01*
X782168Y30874D01*
X782001Y30624D01*
X781876Y30291D01*
X781834Y29916D01*
X781876Y29541D01*
X782001Y29208D01*
X782168Y28958D01*
X782418Y28749D01*
X782751Y28666D01*
X783084Y28749D01*
X783334Y28958D01*
X783501Y29208D01*
X783626Y29541D01*
X783668Y29916D01*
X783626Y30291D01*
X783501Y30624D01*
X783334Y30874D01*
X783084Y31083D01*
X782751Y31166D01*
G01X784934Y29041D02*
X785184Y28833D01*
X785476Y28708D01*
X785851Y28666D01*
X786226Y28749D01*
X786518Y28916D01*
X786726Y29208D01*
X786768Y29541D01*
X786684Y29874D01*
X786476Y30083D01*
X786184Y30249D01*
X785893Y30291D01*
X785601Y30249D01*
X785226Y30083D01*
X785351Y31166D01*
X786476D01*
G01X798070Y29950D02*
Y32450D01*
X799111D01*
X799445Y32325D01*
X799653Y32158D01*
X799736Y31825D01*
X799653Y31492D01*
X799403Y31283D01*
X799111Y31158D01*
X798070D01*
G01X799111D02*
X799736Y29950D01*
G01X801211Y32033D02*
X801461Y32283D01*
X801753Y32408D01*
X802086Y32450D01*
X802503Y32367D01*
X802795Y32158D01*
X802878Y31908D01*
X802836Y31658D01*
X802670Y31450D01*
X801836Y31033D01*
X801461Y30742D01*
X801211Y30325D01*
X801128Y29950D01*
X802878D01*
G01X804186Y30325D02*
X804436Y30117D01*
X804728Y29992D01*
X805103Y29950D01*
X805478Y30033D01*
X805770Y30200D01*
X805978Y30492D01*
X806020Y30825D01*
X805936Y31158D01*
X805728Y31367D01*
X805436Y31533D01*
X805145Y31575D01*
X804853Y31533D01*
X804478Y31367D01*
X804603Y32450D01*
X805728D01*
G01X789800Y23900D02*
X793800D01*
Y31300D01*
G01X802979Y25224D02*
Y27724D01*
X804020D01*
X804354Y27599D01*
X804562Y27432D01*
X804645Y27099D01*
X804562Y26766D01*
X804312Y26557D01*
X804020Y26432D01*
X802979D01*
G01X804020D02*
X804645Y25224D01*
G01X805995Y25724D02*
X806245Y25432D01*
X806579Y25266D01*
X806954Y25224D01*
X807287Y25266D01*
X807620Y25474D01*
X807829Y25724D01*
X807870Y25974D01*
X807787Y26266D01*
X807495Y26474D01*
X807204Y26557D01*
X806829D01*
G01X807204D02*
X807454Y26682D01*
X807662Y26891D01*
X807745Y27141D01*
X807662Y27391D01*
X807454Y27599D01*
X807079Y27724D01*
X806704Y27682D01*
X806329Y27516D01*
G01X795610Y28343D02*
Y24343D01*
X803010D01*
G01X777268Y24331D02*
Y26831D01*
X778309D01*
X778643Y26706D01*
X778851Y26539D01*
X778934Y26206D01*
X778851Y25873D01*
X778601Y25664D01*
X778309Y25539D01*
X777268D01*
G01X778309D02*
X778934Y24331D01*
G01X780493Y24623D02*
X780784Y24414D01*
X781118Y24331D01*
X781451Y24414D01*
X781743Y24664D01*
X781951Y25039D01*
X782034Y25414D01*
Y25873D01*
X781951Y26248D01*
X781743Y26581D01*
X781493Y26748D01*
X781201Y26831D01*
X780868Y26748D01*
X780618Y26581D01*
X780451Y26331D01*
X780368Y25998D01*
X780451Y25706D01*
X780659Y25414D01*
X780909Y25248D01*
X781201Y25206D01*
X781534Y25289D01*
X781784Y25498D01*
X782034Y25873D01*
G01X784801Y24331D02*
Y26831D01*
X783259Y25039D01*
X785343D01*
G01X787901Y24331D02*
Y26831D01*
X786359Y25039D01*
X788443D01*
G01X810600Y22000D02*
X780000D01*
Y10200D01*
X810600D01*
Y22000D01*
G01X782017Y63300D02*
Y65800D01*
X783058D01*
X783392Y65675D01*
X783600Y65508D01*
X783683Y65175D01*
X783600Y64842D01*
X783350Y64633D01*
X783058Y64508D01*
X782017D01*
G01X783058D02*
X783683Y63300D01*
G01X785325Y64425D02*
X786658D01*
X786533Y64717D01*
X786325Y64883D01*
X786033Y64967D01*
X785742Y64925D01*
X785492Y64800D01*
X785325Y64508D01*
X785242Y64258D01*
Y64008D01*
X785325Y63758D01*
X785533Y63508D01*
X785783Y63342D01*
X786075Y63300D01*
X786367Y63383D01*
X786658Y63633D01*
G01X789717Y64758D02*
X789425Y64925D01*
X789175Y64967D01*
X788842Y64883D01*
X788592Y64717D01*
X788425Y64425D01*
X788383Y64133D01*
X788425Y63842D01*
X788592Y63592D01*
X788842Y63383D01*
X789175Y63300D01*
X789467Y63383D01*
X789717Y63550D01*
G01X792150Y63300D02*
X791900Y63342D01*
X791650Y63508D01*
X791483Y63800D01*
X791400Y64133D01*
X791483Y64467D01*
X791650Y64758D01*
X791900Y64925D01*
X792150Y64967D01*
X792400Y64925D01*
X792650Y64758D01*
X792817Y64467D01*
X792858Y64133D01*
X792817Y63800D01*
X792650Y63508D01*
X792400Y63342D01*
X792150Y63300D01*
G01X794500Y64967D02*
X795250Y63300D01*
X796000Y64967D01*
G01X797725Y64425D02*
X799058D01*
X798933Y64717D01*
X798725Y64883D01*
X798433Y64967D01*
X798142Y64925D01*
X797892Y64800D01*
X797725Y64508D01*
X797642Y64258D01*
Y64008D01*
X797725Y63758D01*
X797933Y63508D01*
X798183Y63342D01*
X798475Y63300D01*
X798767Y63383D01*
X799058Y63633D01*
G01X800867Y63300D02*
Y64967D01*
G01Y64633D02*
X801075Y64800D01*
X801283Y64925D01*
X801575Y64967D01*
X801783Y64925D01*
X802033Y64800D01*
G01X803675Y62550D02*
X803925Y62467D01*
X804258Y62550D01*
X804467Y62717D01*
X804633Y62925D01*
X804883Y63592D01*
X805425Y64967D01*
G01X804092D02*
X804883Y63592D01*
G01X781975Y67633D02*
X782308Y67425D01*
X782683Y67300D01*
X783017D01*
X783350Y67425D01*
X783600Y67633D01*
X783725Y67925D01*
X783642Y68217D01*
X783433Y68467D01*
X783058Y68633D01*
X782558Y68717D01*
X782267Y68883D01*
X782142Y69175D01*
X782225Y69467D01*
X782433Y69675D01*
X782725Y69800D01*
X783017D01*
X783308Y69717D01*
X783558Y69508D01*
G01X784700Y69800D02*
X785283Y67300D01*
X785950Y69800D01*
X786617Y67300D01*
X787200Y69800D01*
G01X791900Y67300D02*
Y69425D01*
X791983Y69633D01*
X792150Y69758D01*
X792400Y69800D01*
X792650Y69717D01*
X792775Y69508D01*
G01X792275Y68800D02*
X791442D01*
G01X795250Y67300D02*
X795000Y67342D01*
X794750Y67508D01*
X794583Y67800D01*
X794500Y68133D01*
X794583Y68467D01*
X794750Y68758D01*
X795000Y68925D01*
X795250Y68967D01*
X795500Y68925D01*
X795750Y68758D01*
X795917Y68467D01*
X795958Y68133D01*
X795917Y67800D01*
X795750Y67508D01*
X795500Y67342D01*
X795250Y67300D01*
G01X797767D02*
Y68967D01*
G01Y68633D02*
X797975Y68800D01*
X798183Y68925D01*
X798475Y68967D01*
X798683Y68925D01*
X798933Y68800D01*
G01X802117Y68758D02*
X801825Y68925D01*
X801575Y68967D01*
X801242Y68883D01*
X800992Y68717D01*
X800825Y68425D01*
X800783Y68133D01*
X800825Y67842D01*
X800992Y67592D01*
X801242Y67383D01*
X801575Y67300D01*
X801867Y67383D01*
X802117Y67550D01*
G01X803925Y68425D02*
X805258D01*
X805133Y68717D01*
X804925Y68883D01*
X804633Y68967D01*
X804342Y68925D01*
X804092Y68800D01*
X803925Y68508D01*
X803842Y68258D01*
Y68008D01*
X803925Y67758D01*
X804133Y67508D01*
X804383Y67342D01*
X804675Y67300D01*
X804967Y67383D01*
X805258Y67633D01*
G01X778750Y57500D02*
Y60000D01*
X778250Y59500D01*
G01Y57500D02*
X779250D01*
G01X781308Y58333D02*
X782392D01*
G01X784158Y59583D02*
X784408Y59833D01*
X784700Y59958D01*
X785033Y60000D01*
X785450Y59917D01*
X785742Y59708D01*
X785825Y59458D01*
X785783Y59208D01*
X785617Y59000D01*
X784783Y58583D01*
X784408Y58292D01*
X784158Y57875D01*
X784075Y57500D01*
X785825D01*
G01X791900Y60000D02*
Y57500D01*
G01Y57875D02*
X791733Y57667D01*
X791483Y57542D01*
X791192Y57500D01*
X790858Y57583D01*
X790608Y57792D01*
X790442Y58042D01*
X790400Y58333D01*
X790442Y58625D01*
X790608Y58875D01*
X790858Y59083D01*
X791192Y59167D01*
X791483Y59125D01*
X791692Y59042D01*
X791900Y58875D01*
G01X794250Y59167D02*
Y57500D01*
G01Y59833D02*
X794167Y59875D01*
Y59958D01*
X794250Y60000D01*
X794333Y59958D01*
Y59875D01*
X794250Y59833D01*
G01X796725Y57792D02*
X796933Y57625D01*
X797225Y57500D01*
X797475D01*
X797725Y57583D01*
X797892Y57708D01*
X797975Y57875D01*
X797933Y58125D01*
X797767Y58250D01*
X797017Y58500D01*
X796850Y58792D01*
X796933Y59000D01*
X797100Y59125D01*
X797350Y59167D01*
X797600Y59125D01*
X797850Y59000D01*
G01X801200Y57500D02*
Y59167D01*
G01Y58875D02*
X801033Y59042D01*
X800783Y59125D01*
X800492Y59167D01*
X800200Y59083D01*
X799950Y58917D01*
X799783Y58667D01*
X799700Y58333D01*
X799783Y58000D01*
X799950Y57750D01*
X800200Y57583D01*
X800492Y57500D01*
X800783Y57542D01*
X801033Y57667D01*
X801200Y57833D01*
G01X802800Y57500D02*
Y60000D01*
G01Y58750D02*
X803008Y59000D01*
X803258Y59125D01*
X803508Y59167D01*
X803883Y59083D01*
X804133Y58917D01*
X804300Y58625D01*
Y58292D01*
X804217Y57958D01*
X804050Y57708D01*
X803758Y57542D01*
X803508Y57500D01*
X803258Y57542D01*
X803008Y57667D01*
X802800Y57875D01*
G01X806650Y57500D02*
Y60000D01*
G01X809125Y58625D02*
X810458D01*
X810333Y58917D01*
X810125Y59083D01*
X809833Y59167D01*
X809542Y59125D01*
X809292Y59000D01*
X809125Y58708D01*
X809042Y58458D01*
Y58208D01*
X809125Y57958D01*
X809333Y57708D01*
X809583Y57542D01*
X809875Y57500D01*
X810167Y57583D01*
X810458Y57833D01*
G01X777958Y55083D02*
X778208Y55333D01*
X778500Y55458D01*
X778833Y55500D01*
X779250Y55417D01*
X779542Y55208D01*
X779625Y54958D01*
X779583Y54708D01*
X779417Y54500D01*
X778583Y54083D01*
X778208Y53792D01*
X777958Y53375D01*
X777875Y53000D01*
X779625D01*
G01X781308Y53833D02*
X782392D01*
G01X784033Y53500D02*
X784283Y53208D01*
X784617Y53042D01*
X784992Y53000D01*
X785325Y53042D01*
X785658Y53250D01*
X785867Y53500D01*
X785908Y53750D01*
X785825Y54042D01*
X785533Y54250D01*
X785242Y54333D01*
X784867D01*
G01X785242D02*
X785492Y54458D01*
X785700Y54667D01*
X785783Y54917D01*
X785700Y55167D01*
X785492Y55375D01*
X785117Y55500D01*
X784742Y55458D01*
X784367Y55292D01*
G01X790525Y54125D02*
X791858D01*
X791733Y54417D01*
X791525Y54583D01*
X791233Y54667D01*
X790942Y54625D01*
X790692Y54500D01*
X790525Y54208D01*
X790442Y53958D01*
Y53708D01*
X790525Y53458D01*
X790733Y53208D01*
X790983Y53042D01*
X791275Y53000D01*
X791567Y53083D01*
X791858Y53333D01*
G01X793542Y53000D02*
Y54667D01*
G01Y54250D02*
X793708Y54458D01*
X793958Y54625D01*
X794292Y54667D01*
X794583Y54625D01*
X794833Y54458D01*
X794958Y54167D01*
Y53000D01*
G01X798100D02*
Y54667D01*
G01Y54375D02*
X797933Y54542D01*
X797683Y54625D01*
X797392Y54667D01*
X797100Y54583D01*
X796850Y54417D01*
X796683Y54167D01*
X796600Y53833D01*
X796683Y53500D01*
X796850Y53250D01*
X797100Y53083D01*
X797392Y53000D01*
X797683Y53042D01*
X797933Y53167D01*
X798100Y53333D01*
G01X799700Y53000D02*
Y55500D01*
G01Y54250D02*
X799908Y54500D01*
X800158Y54625D01*
X800408Y54667D01*
X800783Y54583D01*
X801033Y54417D01*
X801200Y54125D01*
Y53792D01*
X801117Y53458D01*
X800950Y53208D01*
X800658Y53042D01*
X800408Y53000D01*
X800158Y53042D01*
X799908Y53167D01*
X799700Y53375D01*
G01X803550Y53000D02*
Y55500D01*
G01X806025Y54125D02*
X807358D01*
X807233Y54417D01*
X807025Y54583D01*
X806733Y54667D01*
X806442Y54625D01*
X806192Y54500D01*
X806025Y54208D01*
X805942Y53958D01*
Y53708D01*
X806025Y53458D01*
X806233Y53208D01*
X806483Y53042D01*
X806775Y53000D01*
X807067Y53083D01*
X807358Y53333D01*
G01X775000Y50000D02*
Y47500D01*
G01Y47875D02*
X774833Y47667D01*
X774583Y47542D01*
X774292Y47500D01*
X773958Y47583D01*
X773708Y47792D01*
X773542Y48042D01*
X773500Y48333D01*
X773542Y48625D01*
X773708Y48875D01*
X773958Y49083D01*
X774292Y49167D01*
X774583Y49125D01*
X774792Y49042D01*
X775000Y48875D01*
G01X776725Y48625D02*
X778058D01*
X777933Y48917D01*
X777725Y49083D01*
X777433Y49167D01*
X777142Y49125D01*
X776892Y49000D01*
X776725Y48708D01*
X776642Y48458D01*
Y48208D01*
X776725Y47958D01*
X776933Y47708D01*
X777183Y47542D01*
X777475Y47500D01*
X777767Y47583D01*
X778058Y47833D01*
G01X780200Y47500D02*
Y49625D01*
X780283Y49833D01*
X780450Y49958D01*
X780700Y50000D01*
X780950Y49917D01*
X781075Y49708D01*
G01X780575Y49000D02*
X779742D01*
G01X784300Y47500D02*
Y49167D01*
G01Y48875D02*
X784133Y49042D01*
X783883Y49125D01*
X783592Y49167D01*
X783300Y49083D01*
X783050Y48917D01*
X782883Y48667D01*
X782800Y48333D01*
X782883Y48000D01*
X783050Y47750D01*
X783300Y47583D01*
X783592Y47500D01*
X783883Y47542D01*
X784133Y47667D01*
X784300Y47833D01*
G01X785942Y49167D02*
Y48000D01*
X786108Y47708D01*
X786358Y47542D01*
X786650Y47500D01*
X786942Y47542D01*
X787192Y47708D01*
X787358Y48000D01*
G01Y47500D02*
Y49167D01*
G01X789750Y47500D02*
Y50000D01*
G01X792850D02*
Y47500D01*
G01X792267Y49167D02*
X793433D01*
G01X803743Y51755D02*
Y40685D01*
X808784D01*
Y23585D01*
G01X776438Y61411D02*
X812438D01*
Y56411D01*
X776438D01*
Y61411D01*
G01X802217Y73500D02*
Y76000D01*
X803258D01*
X803592Y75875D01*
X803800Y75708D01*
X803883Y75375D01*
X803800Y75042D01*
X803550Y74833D01*
X803258Y74708D01*
X802217D01*
G01X803258D02*
X803883Y73500D01*
G01X805233Y73875D02*
X805483Y73667D01*
X805775Y73542D01*
X806150Y73500D01*
X806525Y73583D01*
X806817Y73750D01*
X807025Y74042D01*
X807067Y74375D01*
X806983Y74708D01*
X806775Y74917D01*
X806483Y75083D01*
X806192Y75125D01*
X805900Y75083D01*
X805525Y74917D01*
X805650Y76000D01*
X806775D01*
G01X808458Y74542D02*
X808750Y74833D01*
X809000Y75000D01*
X809333Y75083D01*
X809625Y75000D01*
X809833Y74833D01*
X810000Y74583D01*
X810042Y74292D01*
X810000Y74042D01*
X809833Y73792D01*
X809583Y73583D01*
X809292Y73500D01*
X808958Y73583D01*
X808667Y73833D01*
X808500Y74208D01*
X808458Y74625D01*
X808542Y75167D01*
X808667Y75458D01*
X808875Y75750D01*
X809167Y75958D01*
X809458Y76000D01*
X809750Y75917D01*
X809958Y75708D01*
G01X811558Y74542D02*
X811850Y74833D01*
X812100Y75000D01*
X812433Y75083D01*
X812725Y75000D01*
X812933Y74833D01*
X813100Y74583D01*
X813142Y74292D01*
X813100Y74042D01*
X812933Y73792D01*
X812683Y73583D01*
X812392Y73500D01*
X812058Y73583D01*
X811767Y73833D01*
X811600Y74208D01*
X811558Y74625D01*
X811642Y75167D01*
X811767Y75458D01*
X811975Y75750D01*
X812267Y75958D01*
X812558Y76000D01*
X812850Y75917D01*
X813058Y75708D01*
G01X782200Y76100D02*
Y72100D01*
X789600D01*
G01X780300Y72000D02*
Y76000D01*
X772900D01*
G01X800300Y72200D02*
Y76200D01*
X792900D01*
G01X804800Y84400D02*
Y80400D01*
X812200D01*
G01Y84500D02*
Y88500D01*
X804800D01*
G01X812200Y88600D02*
Y92600D01*
X804800D01*
G01X804900Y96600D02*
Y92600D01*
X812300D01*
G01X804900Y100700D02*
Y96700D01*
X812300D01*
G01X780583Y106000D02*
Y104208D01*
X780750Y103833D01*
X781083Y103583D01*
X781500Y103500D01*
X781917Y103583D01*
X782250Y103833D01*
X782417Y104208D01*
Y106000D01*
G01X783683Y103875D02*
X783933Y103667D01*
X784225Y103542D01*
X784600Y103500D01*
X784975Y103583D01*
X785267Y103750D01*
X785475Y104042D01*
X785517Y104375D01*
X785433Y104708D01*
X785225Y104917D01*
X784933Y105083D01*
X784642Y105125D01*
X784350Y105083D01*
X783975Y104917D01*
X784100Y106000D01*
X785225D01*
G01X786908Y104542D02*
X787200Y104833D01*
X787450Y105000D01*
X787783Y105083D01*
X788075Y105000D01*
X788283Y104833D01*
X788450Y104583D01*
X788492Y104292D01*
X788450Y104042D01*
X788283Y103792D01*
X788033Y103583D01*
X787742Y103500D01*
X787408Y103583D01*
X787117Y103833D01*
X786950Y104208D01*
X786908Y104625D01*
X786992Y105167D01*
X787117Y105458D01*
X787325Y105750D01*
X787617Y105958D01*
X787908Y106000D01*
X788200Y105917D01*
X788408Y105708D01*
G01X784738Y99100D02*
X782538Y101300D01*
G01X784738Y99100D02*
X786938Y101300D01*
G01X791738D02*
X777738D01*
G01Y79800D02*
Y100600D01*
G01X791738Y79800D02*
X777738D01*
G01X791738Y101300D02*
Y79800D01*
G01X782834Y142017D02*
X780334D01*
Y143058D01*
X780459Y143392D01*
X780626Y143600D01*
X780959Y143683D01*
X781292Y143600D01*
X781501Y143350D01*
X781626Y143058D01*
Y142017D01*
G01Y143058D02*
X782834Y143683D01*
G01Y145867D02*
X782292Y145950D01*
X781834Y146075D01*
X781417Y146242D01*
X780959Y146450D01*
X780334Y146783D01*
Y145117D01*
G01X781792Y148258D02*
X781501Y148550D01*
X781334Y148800D01*
X781251Y149133D01*
X781334Y149425D01*
X781501Y149633D01*
X781751Y149800D01*
X782042Y149842D01*
X782292Y149800D01*
X782542Y149633D01*
X782751Y149383D01*
X782834Y149092D01*
X782751Y148758D01*
X782501Y148467D01*
X782126Y148300D01*
X781709Y148258D01*
X781167Y148342D01*
X780876Y148467D01*
X780584Y148675D01*
X780376Y148967D01*
X780334Y149258D01*
X780417Y149550D01*
X780626Y149758D01*
G01X782459Y151233D02*
X782667Y151483D01*
X782792Y151775D01*
X782834Y152150D01*
X782751Y152525D01*
X782584Y152817D01*
X782292Y153025D01*
X781959Y153067D01*
X781626Y152983D01*
X781417Y152775D01*
X781251Y152483D01*
X781209Y152192D01*
X781251Y151900D01*
X781417Y151525D01*
X780334Y151650D01*
Y152775D01*
G01X779100Y133200D02*
X783100D01*
Y140600D01*
G01X789983Y137666D02*
Y135874D01*
X790150Y135499D01*
X790483Y135249D01*
X790900Y135166D01*
X791317Y135249D01*
X791650Y135499D01*
X791817Y135874D01*
Y137666D01*
G01X793083Y135541D02*
X793333Y135333D01*
X793625Y135208D01*
X794000Y135166D01*
X794375Y135249D01*
X794667Y135416D01*
X794875Y135708D01*
X794917Y136041D01*
X794833Y136374D01*
X794625Y136583D01*
X794333Y136749D01*
X794042Y136791D01*
X793750Y136749D01*
X793375Y136583D01*
X793500Y137666D01*
X794625D01*
G01X796183Y135541D02*
X796433Y135333D01*
X796725Y135208D01*
X797100Y135166D01*
X797475Y135249D01*
X797767Y135416D01*
X797975Y135708D01*
X798017Y136041D01*
X797933Y136374D01*
X797725Y136583D01*
X797433Y136749D01*
X797142Y136791D01*
X796850Y136749D01*
X796475Y136583D01*
X796600Y137666D01*
X797725D01*
G01X787638Y130500D02*
X785438Y132700D01*
G01X787638Y130500D02*
X789838Y132700D01*
G01X794638D02*
X780638D01*
G01Y111200D02*
Y132000D01*
G01X794638Y111200D02*
X780638D01*
G01X794638Y132700D02*
Y111200D01*
G01X779517Y305500D02*
Y308000D01*
X780517D01*
X780850Y307875D01*
X781100Y307583D01*
X781183Y307250D01*
X781100Y306917D01*
X780892Y306667D01*
X780517Y306542D01*
X779517D01*
G01X782408Y305500D02*
X783450Y308000D01*
X784492Y305500D01*
G01X784117Y306375D02*
X782783D01*
G01X785633Y305500D02*
Y308000D01*
X786467D01*
X786800Y307875D01*
X787050Y307708D01*
X787258Y307458D01*
X787425Y307167D01*
X787467Y306750D01*
X787425Y306333D01*
X787258Y306042D01*
X787050Y305792D01*
X786800Y305625D01*
X786467Y305500D01*
X785633D01*
G01X790150D02*
Y308000D01*
X788608Y306208D01*
X790692D01*
G01X783100Y447300D02*
X846600D01*
Y380800D01*
X773100D01*
Y447300D01*
X783100D01*
G01X782567Y386966D02*
Y389466D01*
X783608D01*
X783942Y389341D01*
X784150Y389174D01*
X784233Y388841D01*
X784150Y388508D01*
X783900Y388299D01*
X783608Y388174D01*
X782567D01*
G01X783608D02*
X784233Y386966D01*
G01X785583Y387341D02*
X785833Y387133D01*
X786125Y387008D01*
X786500Y386966D01*
X786875Y387049D01*
X787167Y387216D01*
X787375Y387508D01*
X787417Y387841D01*
X787333Y388174D01*
X787125Y388383D01*
X786833Y388549D01*
X786542Y388591D01*
X786250Y388549D01*
X785875Y388383D01*
X786000Y389466D01*
X787125D01*
G01X789517Y386966D02*
X789600Y387508D01*
X789725Y387966D01*
X789892Y388383D01*
X790100Y388841D01*
X790433Y389466D01*
X788767D01*
G01X792617Y386966D02*
X792700Y387508D01*
X792825Y387966D01*
X792992Y388383D01*
X793200Y388841D01*
X793533Y389466D01*
X791867D01*
G01X796300Y386966D02*
Y389466D01*
X794758Y387674D01*
X796842D01*
G01X805900Y395767D02*
X803400D01*
Y396808D01*
X803525Y397142D01*
X803692Y397350D01*
X804025Y397433D01*
X804358Y397350D01*
X804567Y397100D01*
X804692Y396808D01*
Y395767D01*
G01Y396808D02*
X805900Y397433D01*
G01Y399617D02*
X805358Y399700D01*
X804900Y399825D01*
X804483Y399992D01*
X804025Y400200D01*
X803400Y400533D01*
Y398867D01*
G01X805608Y402092D02*
X805817Y402383D01*
X805900Y402717D01*
X805817Y403050D01*
X805567Y403342D01*
X805192Y403550D01*
X804817Y403633D01*
X804358D01*
X803983Y403550D01*
X803650Y403342D01*
X803483Y403092D01*
X803400Y402800D01*
X803483Y402467D01*
X803650Y402217D01*
X803900Y402050D01*
X804233Y401967D01*
X804525Y402050D01*
X804817Y402258D01*
X804983Y402508D01*
X805025Y402800D01*
X804942Y403133D01*
X804733Y403383D01*
X804358Y403633D01*
G01X803400Y405900D02*
X803483Y405567D01*
X803692Y405317D01*
X803942Y405150D01*
X804275Y405025D01*
X804650Y404983D01*
X805025Y405025D01*
X805358Y405150D01*
X805608Y405317D01*
X805817Y405567D01*
X805900Y405900D01*
X805817Y406233D01*
X805608Y406483D01*
X805358Y406650D01*
X805025Y406775D01*
X804650Y406817D01*
X804275Y406775D01*
X803942Y406650D01*
X803692Y406483D01*
X803483Y406233D01*
X803400Y405900D01*
G01X805900Y408917D02*
X805358Y409000D01*
X804900Y409125D01*
X804483Y409292D01*
X804025Y409500D01*
X803400Y409833D01*
Y408167D01*
G01X801852Y397317D02*
X799352D01*
Y398358D01*
X799477Y398692D01*
X799644Y398900D01*
X799977Y398983D01*
X800310Y398900D01*
X800519Y398650D01*
X800644Y398358D01*
Y397317D01*
G01Y398358D02*
X801852Y398983D01*
G01X800810Y400458D02*
X800519Y400750D01*
X800352Y401000D01*
X800269Y401333D01*
X800352Y401625D01*
X800519Y401833D01*
X800769Y402000D01*
X801060Y402042D01*
X801310Y402000D01*
X801560Y401833D01*
X801769Y401583D01*
X801852Y401292D01*
X801769Y400958D01*
X801519Y400667D01*
X801144Y400500D01*
X800727Y400458D01*
X800185Y400542D01*
X799894Y400667D01*
X799602Y400875D01*
X799394Y401167D01*
X799352Y401458D01*
X799435Y401750D01*
X799644Y401958D01*
G01X801852Y404267D02*
X801310Y404350D01*
X800852Y404475D01*
X800435Y404642D01*
X799977Y404850D01*
X799352Y405183D01*
Y403517D01*
G01X801477Y406533D02*
X801685Y406783D01*
X801810Y407075D01*
X801852Y407450D01*
X801769Y407825D01*
X801602Y408117D01*
X801310Y408325D01*
X800977Y408367D01*
X800644Y408283D01*
X800435Y408075D01*
X800269Y407783D01*
X800227Y407492D01*
X800269Y407200D01*
X800435Y406825D01*
X799352Y406950D01*
Y408075D01*
G01X797852Y397317D02*
X795352D01*
Y398358D01*
X795477Y398692D01*
X795644Y398900D01*
X795977Y398983D01*
X796310Y398900D01*
X796519Y398650D01*
X796644Y398358D01*
Y397317D01*
G01Y398358D02*
X797852Y398983D01*
G01X796810Y400458D02*
X796519Y400750D01*
X796352Y401000D01*
X796269Y401333D01*
X796352Y401625D01*
X796519Y401833D01*
X796769Y402000D01*
X797060Y402042D01*
X797310Y402000D01*
X797560Y401833D01*
X797769Y401583D01*
X797852Y401292D01*
X797769Y400958D01*
X797519Y400667D01*
X797144Y400500D01*
X796727Y400458D01*
X796185Y400542D01*
X795894Y400667D01*
X795602Y400875D01*
X795394Y401167D01*
X795352Y401458D01*
X795435Y401750D01*
X795644Y401958D01*
G01X797852Y404267D02*
X797310Y404350D01*
X796852Y404475D01*
X796435Y404642D01*
X795977Y404850D01*
X795352Y405183D01*
Y403517D01*
G01X796810Y406658D02*
X796519Y406950D01*
X796352Y407200D01*
X796269Y407533D01*
X796352Y407825D01*
X796519Y408033D01*
X796769Y408200D01*
X797060Y408242D01*
X797310Y408200D01*
X797560Y408033D01*
X797769Y407783D01*
X797852Y407492D01*
X797769Y407158D01*
X797519Y406867D01*
X797144Y406700D01*
X796727Y406658D01*
X796185Y406742D01*
X795894Y406867D01*
X795602Y407075D01*
X795394Y407367D01*
X795352Y407658D01*
X795435Y407950D01*
X795644Y408158D01*
G01X793852Y397317D02*
X791352D01*
Y398358D01*
X791477Y398692D01*
X791644Y398900D01*
X791977Y398983D01*
X792310Y398900D01*
X792519Y398650D01*
X792644Y398358D01*
Y397317D01*
G01Y398358D02*
X793852Y398983D01*
G01X792810Y400458D02*
X792519Y400750D01*
X792352Y401000D01*
X792269Y401333D01*
X792352Y401625D01*
X792519Y401833D01*
X792769Y402000D01*
X793060Y402042D01*
X793310Y402000D01*
X793560Y401833D01*
X793769Y401583D01*
X793852Y401292D01*
X793769Y400958D01*
X793519Y400667D01*
X793144Y400500D01*
X792727Y400458D01*
X792185Y400542D01*
X791894Y400667D01*
X791602Y400875D01*
X791394Y401167D01*
X791352Y401458D01*
X791435Y401750D01*
X791644Y401958D01*
G01X793852Y404267D02*
X793310Y404350D01*
X792852Y404475D01*
X792435Y404642D01*
X791977Y404850D01*
X791352Y405183D01*
Y403517D01*
G01X793852Y407367D02*
X793310Y407450D01*
X792852Y407575D01*
X792435Y407742D01*
X791977Y407950D01*
X791352Y408283D01*
Y406617D01*
G01X789852Y397317D02*
X787352D01*
Y398358D01*
X787477Y398692D01*
X787644Y398900D01*
X787977Y398983D01*
X788310Y398900D01*
X788519Y398650D01*
X788644Y398358D01*
Y397317D01*
G01Y398358D02*
X789852Y398983D01*
G01X788810Y400458D02*
X788519Y400750D01*
X788352Y401000D01*
X788269Y401333D01*
X788352Y401625D01*
X788519Y401833D01*
X788769Y402000D01*
X789060Y402042D01*
X789310Y402000D01*
X789560Y401833D01*
X789769Y401583D01*
X789852Y401292D01*
X789769Y400958D01*
X789519Y400667D01*
X789144Y400500D01*
X788727Y400458D01*
X788185Y400542D01*
X787894Y400667D01*
X787602Y400875D01*
X787394Y401167D01*
X787352Y401458D01*
X787435Y401750D01*
X787644Y401958D01*
G01X789852Y404267D02*
X789310Y404350D01*
X788852Y404475D01*
X788435Y404642D01*
X787977Y404850D01*
X787352Y405183D01*
Y403517D01*
G01X789852Y407450D02*
X789810Y407742D01*
X789685Y408075D01*
X789477Y408283D01*
X789185Y408367D01*
X788894Y408283D01*
X788644Y408033D01*
X788519Y407658D01*
Y407242D01*
X788435Y406992D01*
X788227Y406783D01*
X787935Y406700D01*
X787644Y406825D01*
X787435Y407117D01*
X787352Y407450D01*
X787435Y407783D01*
X787644Y408075D01*
X787935Y408200D01*
X788227Y408117D01*
X788435Y407908D01*
X788519Y407658D01*
Y407242D01*
X788644Y406867D01*
X788894Y406617D01*
X789185Y406533D01*
X789477Y406617D01*
X789685Y406825D01*
X789810Y407158D01*
X789852Y407450D01*
G01X785852Y397317D02*
X783352D01*
Y398358D01*
X783477Y398692D01*
X783644Y398900D01*
X783977Y398983D01*
X784310Y398900D01*
X784519Y398650D01*
X784644Y398358D01*
Y397317D01*
G01Y398358D02*
X785852Y398983D01*
G01X784810Y400458D02*
X784519Y400750D01*
X784352Y401000D01*
X784269Y401333D01*
X784352Y401625D01*
X784519Y401833D01*
X784769Y402000D01*
X785060Y402042D01*
X785310Y402000D01*
X785560Y401833D01*
X785769Y401583D01*
X785852Y401292D01*
X785769Y400958D01*
X785519Y400667D01*
X785144Y400500D01*
X784727Y400458D01*
X784185Y400542D01*
X783894Y400667D01*
X783602Y400875D01*
X783394Y401167D01*
X783352Y401458D01*
X783435Y401750D01*
X783644Y401958D01*
G01X785852Y404350D02*
X785810Y404642D01*
X785685Y404975D01*
X785477Y405183D01*
X785185Y405267D01*
X784894Y405183D01*
X784644Y404933D01*
X784519Y404558D01*
Y404142D01*
X784435Y403892D01*
X784227Y403683D01*
X783935Y403600D01*
X783644Y403725D01*
X783435Y404017D01*
X783352Y404350D01*
X783435Y404683D01*
X783644Y404975D01*
X783935Y405100D01*
X784227Y405017D01*
X784435Y404808D01*
X784519Y404558D01*
Y404142D01*
X784644Y403767D01*
X784894Y403517D01*
X785185Y403433D01*
X785477Y403517D01*
X785685Y403725D01*
X785810Y404058D01*
X785852Y404350D01*
G01X783352Y407450D02*
X783435Y407117D01*
X783644Y406867D01*
X783894Y406700D01*
X784227Y406575D01*
X784602Y406533D01*
X784977Y406575D01*
X785310Y406700D01*
X785560Y406867D01*
X785769Y407117D01*
X785852Y407450D01*
X785769Y407783D01*
X785560Y408033D01*
X785310Y408200D01*
X784977Y408325D01*
X784602Y408367D01*
X784227Y408325D01*
X783894Y408200D01*
X783644Y408033D01*
X783435Y407783D01*
X783352Y407450D01*
G01X781852Y397317D02*
X779352D01*
Y398358D01*
X779477Y398692D01*
X779644Y398900D01*
X779977Y398983D01*
X780310Y398900D01*
X780519Y398650D01*
X780644Y398358D01*
Y397317D01*
G01Y398358D02*
X781852Y398983D01*
G01X780810Y400458D02*
X780519Y400750D01*
X780352Y401000D01*
X780269Y401333D01*
X780352Y401625D01*
X780519Y401833D01*
X780769Y402000D01*
X781060Y402042D01*
X781310Y402000D01*
X781560Y401833D01*
X781769Y401583D01*
X781852Y401292D01*
X781769Y400958D01*
X781519Y400667D01*
X781144Y400500D01*
X780727Y400458D01*
X780185Y400542D01*
X779894Y400667D01*
X779602Y400875D01*
X779394Y401167D01*
X779352Y401458D01*
X779435Y401750D01*
X779644Y401958D01*
G01X781852Y404350D02*
X781810Y404642D01*
X781685Y404975D01*
X781477Y405183D01*
X781185Y405267D01*
X780894Y405183D01*
X780644Y404933D01*
X780519Y404558D01*
Y404142D01*
X780435Y403892D01*
X780227Y403683D01*
X779935Y403600D01*
X779644Y403725D01*
X779435Y404017D01*
X779352Y404350D01*
X779435Y404683D01*
X779644Y404975D01*
X779935Y405100D01*
X780227Y405017D01*
X780435Y404808D01*
X780519Y404558D01*
Y404142D01*
X780644Y403767D01*
X780894Y403517D01*
X781185Y403433D01*
X781477Y403517D01*
X781685Y403725D01*
X781810Y404058D01*
X781852Y404350D01*
G01Y407450D02*
X779352D01*
X779852Y406950D01*
G01X781852D02*
Y407950D01*
G01X777852Y397317D02*
X775352D01*
Y398358D01*
X775477Y398692D01*
X775644Y398900D01*
X775977Y398983D01*
X776310Y398900D01*
X776519Y398650D01*
X776644Y398358D01*
Y397317D01*
G01Y398358D02*
X777852Y398983D01*
G01X776810Y400458D02*
X776519Y400750D01*
X776352Y401000D01*
X776269Y401333D01*
X776352Y401625D01*
X776519Y401833D01*
X776769Y402000D01*
X777060Y402042D01*
X777310Y402000D01*
X777560Y401833D01*
X777769Y401583D01*
X777852Y401292D01*
X777769Y400958D01*
X777519Y400667D01*
X777144Y400500D01*
X776727Y400458D01*
X776185Y400542D01*
X775894Y400667D01*
X775602Y400875D01*
X775394Y401167D01*
X775352Y401458D01*
X775435Y401750D01*
X775644Y401958D01*
G01X777852Y404350D02*
X777810Y404642D01*
X777685Y404975D01*
X777477Y405183D01*
X777185Y405267D01*
X776894Y405183D01*
X776644Y404933D01*
X776519Y404558D01*
Y404142D01*
X776435Y403892D01*
X776227Y403683D01*
X775935Y403600D01*
X775644Y403725D01*
X775435Y404017D01*
X775352Y404350D01*
X775435Y404683D01*
X775644Y404975D01*
X775935Y405100D01*
X776227Y405017D01*
X776435Y404808D01*
X776519Y404558D01*
Y404142D01*
X776644Y403767D01*
X776894Y403517D01*
X777185Y403433D01*
X777477Y403517D01*
X777685Y403725D01*
X777810Y404058D01*
X777852Y404350D01*
G01X775769Y406658D02*
X775519Y406908D01*
X775394Y407200D01*
X775352Y407533D01*
X775435Y407950D01*
X775644Y408242D01*
X775894Y408325D01*
X776144Y408283D01*
X776352Y408117D01*
X776769Y407283D01*
X777060Y406908D01*
X777477Y406658D01*
X777852Y406575D01*
Y408325D01*
G01X797567Y389966D02*
Y392466D01*
X798608D01*
X798942Y392341D01*
X799150Y392174D01*
X799233Y391841D01*
X799150Y391508D01*
X798900Y391299D01*
X798608Y391174D01*
X797567D01*
G01X798608D02*
X799233Y389966D01*
G01X800583Y390466D02*
X800833Y390174D01*
X801167Y390008D01*
X801542Y389966D01*
X801875Y390008D01*
X802208Y390216D01*
X802417Y390466D01*
X802458Y390716D01*
X802375Y391008D01*
X802083Y391216D01*
X801792Y391299D01*
X801417D01*
G01X801792D02*
X802042Y391424D01*
X802250Y391633D01*
X802333Y391883D01*
X802250Y392133D01*
X802042Y392341D01*
X801667Y392466D01*
X801292Y392424D01*
X800917Y392258D01*
G01X804517Y389966D02*
X804600Y390508D01*
X804725Y390966D01*
X804892Y391383D01*
X805100Y391841D01*
X805433Y392466D01*
X803767D01*
G01X806908Y392049D02*
X807158Y392299D01*
X807450Y392424D01*
X807783Y392466D01*
X808200Y392383D01*
X808492Y392174D01*
X808575Y391924D01*
X808533Y391674D01*
X808367Y391466D01*
X807533Y391049D01*
X807158Y390758D01*
X806908Y390341D01*
X806825Y389966D01*
X808575D01*
G01X809883Y390341D02*
X810133Y390133D01*
X810425Y390008D01*
X810800Y389966D01*
X811175Y390049D01*
X811467Y390216D01*
X811675Y390508D01*
X811717Y390841D01*
X811633Y391174D01*
X811425Y391383D01*
X811133Y391549D01*
X810842Y391591D01*
X810550Y391549D01*
X810175Y391383D01*
X810300Y392466D01*
X811425D01*
G01X795475Y383299D02*
X795808Y383091D01*
X796183Y382966D01*
X796517D01*
X796850Y383091D01*
X797100Y383299D01*
X797225Y383591D01*
X797142Y383883D01*
X796933Y384133D01*
X796558Y384299D01*
X796058Y384383D01*
X795767Y384549D01*
X795642Y384841D01*
X795725Y385133D01*
X795933Y385341D01*
X796225Y385466D01*
X796517D01*
X796808Y385383D01*
X797058Y385174D01*
G01X798617Y385466D02*
Y382966D01*
X800283D01*
G01X803383D02*
X801717D01*
Y385466D01*
X803383D01*
G01X802717Y384258D02*
X801717D01*
G01X804733Y382966D02*
Y385466D01*
X805567D01*
X805900Y385341D01*
X806150Y385174D01*
X806358Y384924D01*
X806525Y384633D01*
X806567Y384216D01*
X806525Y383799D01*
X806358Y383508D01*
X806150Y383258D01*
X805900Y383091D01*
X805567Y382966D01*
X804733D01*
G01X807958Y385049D02*
X808208Y385299D01*
X808500Y385424D01*
X808833Y385466D01*
X809250Y385383D01*
X809542Y385174D01*
X809625Y384924D01*
X809583Y384674D01*
X809417Y384466D01*
X808583Y384049D01*
X808208Y383758D01*
X807958Y383341D01*
X807875Y382966D01*
X809625D01*
G01X811142Y383258D02*
X811433Y383049D01*
X811767Y382966D01*
X812100Y383049D01*
X812392Y383299D01*
X812600Y383674D01*
X812683Y384049D01*
Y384508D01*
X812600Y384883D01*
X812392Y385216D01*
X812142Y385383D01*
X811850Y385466D01*
X811517Y385383D01*
X811267Y385216D01*
X811100Y384966D01*
X811017Y384633D01*
X811100Y384341D01*
X811308Y384049D01*
X811558Y383883D01*
X811850Y383841D01*
X812183Y383924D01*
X812433Y384133D01*
X812683Y384508D01*
G01X794934Y422333D02*
X796726D01*
X797101Y422500D01*
X797351Y422833D01*
X797434Y423250D01*
X797351Y423667D01*
X797101Y424000D01*
X796726Y424167D01*
X794934D01*
G01X796392Y425558D02*
X796101Y425850D01*
X795934Y426100D01*
X795851Y426433D01*
X795934Y426725D01*
X796101Y426933D01*
X796351Y427100D01*
X796642Y427142D01*
X796892Y427100D01*
X797142Y426933D01*
X797351Y426683D01*
X797434Y426392D01*
X797351Y426058D01*
X797101Y425767D01*
X796726Y425600D01*
X796309Y425558D01*
X795767Y425642D01*
X795476Y425767D01*
X795184Y425975D01*
X794976Y426267D01*
X794934Y426558D01*
X795017Y426850D01*
X795226Y427058D01*
G01X787618Y420146D02*
X785118D01*
Y421187D01*
X785243Y421521D01*
X785410Y421729D01*
X785743Y421812D01*
X786076Y421729D01*
X786285Y421479D01*
X786410Y421187D01*
Y420146D01*
G01Y421187D02*
X787618Y421812D01*
G01Y423996D02*
X787076Y424079D01*
X786618Y424204D01*
X786201Y424371D01*
X785743Y424579D01*
X785118Y424912D01*
Y423246D01*
G01X787618Y427179D02*
X787576Y427471D01*
X787451Y427804D01*
X787243Y428012D01*
X786951Y428096D01*
X786660Y428012D01*
X786410Y427762D01*
X786285Y427387D01*
Y426971D01*
X786201Y426721D01*
X785993Y426512D01*
X785701Y426429D01*
X785410Y426554D01*
X785201Y426846D01*
X785118Y427179D01*
X785201Y427512D01*
X785410Y427804D01*
X785701Y427929D01*
X785993Y427846D01*
X786201Y427637D01*
X786285Y427387D01*
Y426971D01*
X786410Y426596D01*
X786660Y426346D01*
X786951Y426262D01*
X787243Y426346D01*
X787451Y426554D01*
X787576Y426887D01*
X787618Y427179D01*
G01X787326Y429571D02*
X787535Y429862D01*
X787618Y430196D01*
X787535Y430529D01*
X787285Y430821D01*
X786910Y431029D01*
X786535Y431112D01*
X786076D01*
X785701Y431029D01*
X785368Y430821D01*
X785201Y430571D01*
X785118Y430279D01*
X785201Y429946D01*
X785368Y429696D01*
X785618Y429529D01*
X785951Y429446D01*
X786243Y429529D01*
X786535Y429737D01*
X786701Y429987D01*
X786743Y430279D01*
X786660Y430612D01*
X786451Y430862D01*
X786076Y431112D01*
G01X785535Y432587D02*
X785285Y432837D01*
X785160Y433129D01*
X785118Y433462D01*
X785201Y433879D01*
X785410Y434171D01*
X785660Y434254D01*
X785910Y434212D01*
X786118Y434046D01*
X786535Y433212D01*
X786826Y432837D01*
X787243Y432587D01*
X787618Y432504D01*
Y434254D01*
G01X791718Y420146D02*
X789218D01*
Y421187D01*
X789343Y421521D01*
X789510Y421729D01*
X789843Y421812D01*
X790176Y421729D01*
X790385Y421479D01*
X790510Y421187D01*
Y420146D01*
G01Y421187D02*
X791718Y421812D01*
G01Y423996D02*
X791176Y424079D01*
X790718Y424204D01*
X790301Y424371D01*
X789843Y424579D01*
X789218Y424912D01*
Y423246D01*
G01X791718Y427179D02*
X791676Y427471D01*
X791551Y427804D01*
X791343Y428012D01*
X791051Y428096D01*
X790760Y428012D01*
X790510Y427762D01*
X790385Y427387D01*
Y426971D01*
X790301Y426721D01*
X790093Y426512D01*
X789801Y426429D01*
X789510Y426554D01*
X789301Y426846D01*
X789218Y427179D01*
X789301Y427512D01*
X789510Y427804D01*
X789801Y427929D01*
X790093Y427846D01*
X790301Y427637D01*
X790385Y427387D01*
Y426971D01*
X790510Y426596D01*
X790760Y426346D01*
X791051Y426262D01*
X791343Y426346D01*
X791551Y426554D01*
X791676Y426887D01*
X791718Y427179D01*
G01Y430279D02*
X791676Y430571D01*
X791551Y430904D01*
X791343Y431112D01*
X791051Y431196D01*
X790760Y431112D01*
X790510Y430862D01*
X790385Y430487D01*
Y430071D01*
X790301Y429821D01*
X790093Y429612D01*
X789801Y429529D01*
X789510Y429654D01*
X789301Y429946D01*
X789218Y430279D01*
X789301Y430612D01*
X789510Y430904D01*
X789801Y431029D01*
X790093Y430946D01*
X790301Y430737D01*
X790385Y430487D01*
Y430071D01*
X790510Y429696D01*
X790760Y429446D01*
X791051Y429362D01*
X791343Y429446D01*
X791551Y429654D01*
X791676Y429987D01*
X791718Y430279D01*
G01X791426Y432671D02*
X791635Y432962D01*
X791718Y433296D01*
X791635Y433629D01*
X791385Y433921D01*
X791010Y434129D01*
X790635Y434212D01*
X790176D01*
X789801Y434129D01*
X789468Y433921D01*
X789301Y433671D01*
X789218Y433379D01*
X789301Y433046D01*
X789468Y432796D01*
X789718Y432629D01*
X790051Y432546D01*
X790343Y432629D01*
X790635Y432837D01*
X790801Y433087D01*
X790843Y433379D01*
X790760Y433712D01*
X790551Y433962D01*
X790176Y434212D01*
G01X802601Y420175D02*
X802809Y420508D01*
X802934Y420883D01*
Y421217D01*
X802809Y421550D01*
X802601Y421800D01*
X802309Y421925D01*
X802017Y421842D01*
X801767Y421633D01*
X801601Y421258D01*
X801517Y420758D01*
X801351Y420467D01*
X801059Y420342D01*
X800767Y420425D01*
X800559Y420633D01*
X800434Y420925D01*
Y421217D01*
X800517Y421508D01*
X800726Y421758D01*
G01X800642Y425067D02*
X800517Y424817D01*
X800434Y424525D01*
Y424192D01*
X800559Y423817D01*
X800767Y423525D01*
X801017Y423317D01*
X801434Y423150D01*
X801809Y423108D01*
X802184Y423192D01*
X802434Y423317D01*
X802684Y423567D01*
X802851Y423858D01*
X802934Y424150D01*
Y424442D01*
X802851Y424733D01*
X802726Y424983D01*
X802559Y425192D01*
G01X802934Y427250D02*
X800434D01*
X800934Y426750D01*
G01X802934D02*
Y427750D01*
G01Y430350D02*
X800434D01*
X800934Y429850D01*
G01X802934D02*
Y430850D01*
G01Y433450D02*
X800434D01*
X800934Y432950D01*
G01X802934D02*
Y433950D01*
G01X802559Y435633D02*
X802767Y435883D01*
X802892Y436175D01*
X802934Y436550D01*
X802851Y436925D01*
X802684Y437217D01*
X802392Y437425D01*
X802059Y437467D01*
X801726Y437383D01*
X801517Y437175D01*
X801351Y436883D01*
X801309Y436592D01*
X801351Y436300D01*
X801517Y435925D01*
X800434Y436050D01*
Y437175D01*
G01X788300Y440150D02*
X788258Y439817D01*
X788092Y439525D01*
X787842Y439275D01*
X787550Y439108D01*
X787217Y439025D01*
X786883D01*
X786550Y439108D01*
X786258Y439275D01*
X786008Y439525D01*
X785842Y439817D01*
X785800Y440150D01*
X785842Y440483D01*
X786008Y440775D01*
X786258Y441025D01*
X786550Y441192D01*
X786883Y441275D01*
X787217D01*
X787550Y441192D01*
X787842Y441025D01*
X788092Y440775D01*
X788258Y440483D01*
X788300Y440150D01*
G01X787633Y440483D02*
X788300Y440983D01*
G01X787258Y442458D02*
X786967Y442750D01*
X786800Y443000D01*
X786717Y443333D01*
X786800Y443625D01*
X786967Y443833D01*
X787217Y444000D01*
X787508Y444042D01*
X787758Y444000D01*
X788008Y443833D01*
X788217Y443583D01*
X788300Y443292D01*
X788217Y442958D01*
X787967Y442667D01*
X787592Y442500D01*
X787175Y442458D01*
X786633Y442542D01*
X786342Y442667D01*
X786050Y442875D01*
X785842Y443167D01*
X785800Y443458D01*
X785883Y443750D01*
X786092Y443958D01*
G01X773873Y816633D02*
X773748Y816383D01*
X773665Y816091D01*
Y815758D01*
X773790Y815383D01*
X773998Y815091D01*
X774248Y814883D01*
X774665Y814716D01*
X775040Y814674D01*
X775415Y814758D01*
X775665Y814883D01*
X775915Y815133D01*
X776082Y815424D01*
X776165Y815716D01*
Y816008D01*
X776082Y816299D01*
X775957Y816549D01*
X775790Y816758D01*
G01X776165Y818816D02*
X773665D01*
X774165Y818316D01*
G01X776165D02*
Y819316D01*
G01Y821916D02*
X773665D01*
X774165Y821416D01*
G01X776165D02*
Y822416D01*
G01X775873Y824308D02*
X776082Y824599D01*
X776165Y824933D01*
X776082Y825266D01*
X775832Y825558D01*
X775457Y825766D01*
X775082Y825849D01*
X774623D01*
X774248Y825766D01*
X773915Y825558D01*
X773748Y825308D01*
X773665Y825016D01*
X773748Y824683D01*
X773915Y824433D01*
X774165Y824266D01*
X774498Y824183D01*
X774790Y824266D01*
X775082Y824474D01*
X775248Y824724D01*
X775290Y825016D01*
X775207Y825349D01*
X774998Y825599D01*
X774623Y825849D01*
G01X777873Y816633D02*
X777748Y816383D01*
X777665Y816091D01*
Y815758D01*
X777790Y815383D01*
X777998Y815091D01*
X778248Y814883D01*
X778665Y814716D01*
X779040Y814674D01*
X779415Y814758D01*
X779665Y814883D01*
X779915Y815133D01*
X780082Y815424D01*
X780165Y815716D01*
Y816008D01*
X780082Y816299D01*
X779957Y816549D01*
X779790Y816758D01*
G01X780165Y818816D02*
X777665D01*
X778165Y818316D01*
G01X780165D02*
Y819316D01*
G01Y821916D02*
X777665D01*
X778165Y821416D01*
G01X780165D02*
Y822416D01*
G01Y825016D02*
X780123Y825308D01*
X779998Y825641D01*
X779790Y825849D01*
X779498Y825933D01*
X779207Y825849D01*
X778957Y825599D01*
X778832Y825224D01*
Y824808D01*
X778748Y824558D01*
X778540Y824349D01*
X778248Y824266D01*
X777957Y824391D01*
X777748Y824683D01*
X777665Y825016D01*
X777748Y825349D01*
X777957Y825641D01*
X778248Y825766D01*
X778540Y825683D01*
X778748Y825474D01*
X778832Y825224D01*
Y824808D01*
X778957Y824433D01*
X779207Y824183D01*
X779498Y824099D01*
X779790Y824183D01*
X779998Y824391D01*
X780123Y824724D01*
X780165Y825016D01*
G01X786471Y816633D02*
X786346Y816383D01*
X786263Y816091D01*
Y815758D01*
X786388Y815383D01*
X786596Y815091D01*
X786846Y814883D01*
X787263Y814716D01*
X787638Y814674D01*
X788013Y814758D01*
X788263Y814883D01*
X788513Y815133D01*
X788680Y815424D01*
X788763Y815716D01*
Y816008D01*
X788680Y816299D01*
X788555Y816549D01*
X788388Y816758D01*
G01X788763Y818816D02*
X786263D01*
X786763Y818316D01*
G01X788763D02*
Y819316D01*
G01Y821916D02*
X786263D01*
X786763Y821416D01*
G01X788763D02*
Y822416D01*
G01Y824933D02*
X788221Y825016D01*
X787763Y825141D01*
X787346Y825308D01*
X786888Y825516D01*
X786263Y825849D01*
Y824183D01*
G01X790471Y816633D02*
X790346Y816383D01*
X790263Y816091D01*
Y815758D01*
X790388Y815383D01*
X790596Y815091D01*
X790846Y814883D01*
X791263Y814716D01*
X791638Y814674D01*
X792013Y814758D01*
X792263Y814883D01*
X792513Y815133D01*
X792680Y815424D01*
X792763Y815716D01*
Y816008D01*
X792680Y816299D01*
X792555Y816549D01*
X792388Y816758D01*
G01X792763Y818816D02*
X790263D01*
X790763Y818316D01*
G01X792763D02*
Y819316D01*
G01Y821916D02*
X790263D01*
X790763Y821416D01*
G01X792763D02*
Y822416D01*
G01X791721Y824224D02*
X791430Y824516D01*
X791263Y824766D01*
X791180Y825099D01*
X791263Y825391D01*
X791430Y825599D01*
X791680Y825766D01*
X791971Y825808D01*
X792221Y825766D01*
X792471Y825599D01*
X792680Y825349D01*
X792763Y825058D01*
X792680Y824724D01*
X792430Y824433D01*
X792055Y824266D01*
X791638Y824224D01*
X791096Y824308D01*
X790805Y824433D01*
X790513Y824641D01*
X790305Y824933D01*
X790263Y825224D01*
X790346Y825516D01*
X790555Y825724D01*
G01X799070Y816633D02*
X798945Y816383D01*
X798862Y816091D01*
Y815758D01*
X798987Y815383D01*
X799195Y815091D01*
X799445Y814883D01*
X799862Y814716D01*
X800237Y814674D01*
X800612Y814758D01*
X800862Y814883D01*
X801112Y815133D01*
X801279Y815424D01*
X801362Y815716D01*
Y816008D01*
X801279Y816299D01*
X801154Y816549D01*
X800987Y816758D01*
G01X801362Y818816D02*
X798862D01*
X799362Y818316D01*
G01X801362D02*
Y819316D01*
G01Y821916D02*
X798862D01*
X799362Y821416D01*
G01X801362D02*
Y822416D01*
G01X800987Y824099D02*
X801195Y824349D01*
X801320Y824641D01*
X801362Y825016D01*
X801279Y825391D01*
X801112Y825683D01*
X800820Y825891D01*
X800487Y825933D01*
X800154Y825849D01*
X799945Y825641D01*
X799779Y825349D01*
X799737Y825058D01*
X799779Y824766D01*
X799945Y824391D01*
X798862Y824516D01*
Y825641D01*
G01X803070Y816633D02*
X802945Y816383D01*
X802862Y816091D01*
Y815758D01*
X802987Y815383D01*
X803195Y815091D01*
X803445Y814883D01*
X803862Y814716D01*
X804237Y814674D01*
X804612Y814758D01*
X804862Y814883D01*
X805112Y815133D01*
X805279Y815424D01*
X805362Y815716D01*
Y816008D01*
X805279Y816299D01*
X805154Y816549D01*
X804987Y816758D01*
G01X805362Y818816D02*
X802862D01*
X803362Y818316D01*
G01X805362D02*
Y819316D01*
G01Y821916D02*
X802862D01*
X803362Y821416D01*
G01X805362D02*
Y822416D01*
G01Y825516D02*
X802862D01*
X804654Y823974D01*
Y826058D01*
G01X818500Y5800D02*
Y43956D01*
X816398D01*
Y53347D01*
X812667D01*
G01X900000Y9500D02*
X898000D01*
Y-3500D01*
X857000D01*
Y-6000D01*
X819000D01*
Y-5000D01*
G01X842000Y-4500D02*
X823000D01*
G01D02*
Y8500D01*
G01X814624Y-3300D02*
X818899D01*
G01D02*
Y3300D01*
G01X826567Y37666D02*
X825867Y38066D01*
X825050Y38333D01*
X824117D01*
X823067Y37933D01*
X822250Y37266D01*
X821667Y36466D01*
X821200Y35133D01*
X821083Y33933D01*
X821317Y32733D01*
X821667Y31933D01*
X822367Y31133D01*
X823183Y30600D01*
X824000Y30333D01*
X824817D01*
X825633Y30600D01*
X826333Y31000D01*
X826917Y31533D01*
G01X808800Y22993D02*
X810300Y24493D01*
X807300D01*
X808800Y22993D01*
G01X831202Y35000D02*
X851802D01*
G01X831202Y46000D02*
Y35000D01*
G01X823000Y8500D02*
X842000D01*
G01X840252Y19700D02*
X836252D01*
Y12300D01*
G01Y19700D02*
X832252D01*
Y12300D01*
G01Y19700D02*
X828252D01*
Y12300D01*
G01Y19700D02*
X824252D01*
Y12300D01*
G01Y19700D02*
X820252D01*
Y12300D01*
G01X815701Y24579D02*
X813201D01*
Y25620D01*
X813326Y25954D01*
X813493Y26162D01*
X813826Y26245D01*
X814159Y26162D01*
X814368Y25912D01*
X814493Y25620D01*
Y24579D01*
G01Y25620D02*
X815701Y26245D01*
G01X815326Y27595D02*
X815534Y27845D01*
X815659Y28137D01*
X815701Y28512D01*
X815618Y28887D01*
X815451Y29179D01*
X815159Y29387D01*
X814826Y29429D01*
X814493Y29345D01*
X814284Y29137D01*
X814118Y28845D01*
X814076Y28554D01*
X814118Y28262D01*
X814284Y27887D01*
X813201Y28012D01*
Y29137D01*
G01X815701Y31612D02*
X815659Y31904D01*
X815534Y32237D01*
X815326Y32445D01*
X815034Y32529D01*
X814743Y32445D01*
X814493Y32195D01*
X814368Y31820D01*
Y31404D01*
X814284Y31154D01*
X814076Y30945D01*
X813784Y30862D01*
X813493Y30987D01*
X813284Y31279D01*
X813201Y31612D01*
X813284Y31945D01*
X813493Y32237D01*
X813784Y32362D01*
X814076Y32279D01*
X814284Y32070D01*
X814368Y31820D01*
Y31404D01*
X814493Y31029D01*
X814743Y30779D01*
X815034Y30695D01*
X815326Y30779D01*
X815534Y30987D01*
X815659Y31320D01*
X815701Y31612D01*
G01X813500Y15100D02*
X817500D01*
Y22500D01*
G01X868500Y55500D02*
Y57500D01*
X830000D01*
Y72500D01*
X810400D01*
Y63700D01*
G01X851802Y46000D02*
X831202D01*
G01X818018Y45679D02*
X822018D01*
Y53079D01*
G01X822118Y45679D02*
X826118D01*
Y53079D01*
G01X815317Y73600D02*
Y76100D01*
X816358D01*
X816692Y75975D01*
X816900Y75808D01*
X816983Y75475D01*
X816900Y75142D01*
X816650Y74933D01*
X816358Y74808D01*
X815317D01*
G01X816358D02*
X816983Y73600D01*
G01X819167D02*
X819250Y74142D01*
X819375Y74600D01*
X819542Y75017D01*
X819750Y75475D01*
X820083Y76100D01*
X818417D01*
G01X822350D02*
X822017Y76017D01*
X821767Y75808D01*
X821600Y75558D01*
X821475Y75225D01*
X821433Y74850D01*
X821475Y74475D01*
X821600Y74142D01*
X821767Y73892D01*
X822017Y73683D01*
X822350Y73600D01*
X822683Y73683D01*
X822933Y73892D01*
X823100Y74142D01*
X823225Y74475D01*
X823267Y74850D01*
X823225Y75225D01*
X823100Y75558D01*
X822933Y75808D01*
X822683Y76017D01*
X822350Y76100D01*
G01X824533Y74100D02*
X824783Y73808D01*
X825117Y73642D01*
X825492Y73600D01*
X825825Y73642D01*
X826158Y73850D01*
X826367Y74100D01*
X826408Y74350D01*
X826325Y74642D01*
X826033Y74850D01*
X825742Y74933D01*
X825367D01*
G01X825742D02*
X825992Y75058D01*
X826200Y75267D01*
X826283Y75517D01*
X826200Y75767D01*
X825992Y75975D01*
X825617Y76100D01*
X825242Y76058D01*
X824867Y75892D01*
G01X827700Y57400D02*
Y70400D01*
G01D02*
X813700D01*
G01D02*
Y57400D01*
G01D02*
X827700D01*
G01X832903Y96411D02*
Y93911D01*
G01X831945Y96411D02*
X833861D01*
G01X835170Y93911D02*
Y96411D01*
X836170D01*
X836503Y96286D01*
X836753Y95994D01*
X836836Y95661D01*
X836753Y95328D01*
X836545Y95078D01*
X836170Y94953D01*
X835170D01*
G01X838186Y94411D02*
X838436Y94119D01*
X838770Y93953D01*
X839145Y93911D01*
X839478Y93953D01*
X839811Y94161D01*
X840020Y94411D01*
X840061Y94661D01*
X839978Y94953D01*
X839686Y95161D01*
X839395Y95244D01*
X839020D01*
G01X839395D02*
X839645Y95369D01*
X839853Y95578D01*
X839936Y95828D01*
X839853Y96078D01*
X839645Y96286D01*
X839270Y96411D01*
X838895Y96369D01*
X838520Y96203D01*
G01X841411Y95994D02*
X841661Y96244D01*
X841953Y96369D01*
X842286Y96411D01*
X842703Y96328D01*
X842995Y96119D01*
X843078Y95869D01*
X843036Y95619D01*
X842870Y95411D01*
X842036Y94994D01*
X841661Y94703D01*
X841411Y94286D01*
X841328Y93911D01*
X843078D01*
G01X845303D02*
X845595Y93953D01*
X845928Y94078D01*
X846136Y94286D01*
X846220Y94578D01*
X846136Y94869D01*
X845886Y95119D01*
X845511Y95244D01*
X845095D01*
X844845Y95328D01*
X844636Y95536D01*
X844553Y95828D01*
X844678Y96119D01*
X844970Y96328D01*
X845303Y96411D01*
X845636Y96328D01*
X845928Y96119D01*
X846053Y95828D01*
X845970Y95536D01*
X845761Y95328D01*
X845511Y95244D01*
X845095D01*
X844720Y95119D01*
X844470Y94869D01*
X844386Y94578D01*
X844470Y94286D01*
X844678Y94078D01*
X845011Y93953D01*
X845303Y93911D01*
G01X840800Y103600D02*
Y107600D01*
X833400D01*
G01X814517Y85400D02*
Y87900D01*
X815558D01*
X815892Y87775D01*
X816100Y87608D01*
X816183Y87275D01*
X816100Y86942D01*
X815850Y86733D01*
X815558Y86608D01*
X814517D01*
G01X815558D02*
X816183Y85400D01*
G01X817533Y85775D02*
X817783Y85567D01*
X818075Y85442D01*
X818450Y85400D01*
X818825Y85483D01*
X819117Y85650D01*
X819325Y85942D01*
X819367Y86275D01*
X819283Y86608D01*
X819075Y86817D01*
X818783Y86983D01*
X818492Y87025D01*
X818200Y86983D01*
X817825Y86817D01*
X817950Y87900D01*
X819075D01*
G01X821550Y85400D02*
X821842Y85442D01*
X822175Y85567D01*
X822383Y85775D01*
X822467Y86067D01*
X822383Y86358D01*
X822133Y86608D01*
X821758Y86733D01*
X821342D01*
X821092Y86817D01*
X820883Y87025D01*
X820800Y87317D01*
X820925Y87608D01*
X821217Y87817D01*
X821550Y87900D01*
X821883Y87817D01*
X822175Y87608D01*
X822300Y87317D01*
X822217Y87025D01*
X822008Y86817D01*
X821758Y86733D01*
X821342D01*
X820967Y86608D01*
X820717Y86358D01*
X820633Y86067D01*
X820717Y85775D01*
X820925Y85567D01*
X821258Y85442D01*
X821550Y85400D01*
G01X823733Y85900D02*
X823983Y85608D01*
X824317Y85442D01*
X824692Y85400D01*
X825025Y85442D01*
X825358Y85650D01*
X825567Y85900D01*
X825608Y86150D01*
X825525Y86442D01*
X825233Y86650D01*
X824942Y86733D01*
X824567D01*
G01X824942D02*
X825192Y86858D01*
X825400Y87067D01*
X825483Y87317D01*
X825400Y87567D01*
X825192Y87775D01*
X824817Y87900D01*
X824442Y87858D01*
X824067Y87692D01*
G01X814819Y89766D02*
Y92266D01*
X815860D01*
X816194Y92141D01*
X816402Y91974D01*
X816485Y91641D01*
X816402Y91308D01*
X816152Y91099D01*
X815860Y90974D01*
X814819D01*
G01X815860D02*
X816485Y89766D01*
G01X817960Y90808D02*
X818252Y91099D01*
X818502Y91266D01*
X818835Y91349D01*
X819127Y91266D01*
X819335Y91099D01*
X819502Y90849D01*
X819544Y90558D01*
X819502Y90308D01*
X819335Y90058D01*
X819085Y89849D01*
X818794Y89766D01*
X818460Y89849D01*
X818169Y90099D01*
X818002Y90474D01*
X817960Y90891D01*
X818044Y91433D01*
X818169Y91724D01*
X818377Y92016D01*
X818669Y92224D01*
X818960Y92266D01*
X819252Y92183D01*
X819460Y91974D01*
G01X821144Y90058D02*
X821435Y89849D01*
X821769Y89766D01*
X822102Y89849D01*
X822394Y90099D01*
X822602Y90474D01*
X822685Y90849D01*
Y91308D01*
X822602Y91683D01*
X822394Y92016D01*
X822144Y92183D01*
X821852Y92266D01*
X821519Y92183D01*
X821269Y92016D01*
X821102Y91766D01*
X821019Y91433D01*
X821102Y91141D01*
X821310Y90849D01*
X821560Y90683D01*
X821852Y90641D01*
X822185Y90724D01*
X822435Y90933D01*
X822685Y91308D01*
G01X814651Y94477D02*
Y96977D01*
X815692D01*
X816026Y96852D01*
X816234Y96685D01*
X816317Y96352D01*
X816234Y96019D01*
X815984Y95810D01*
X815692Y95685D01*
X814651D01*
G01X815692D02*
X816317Y94477D01*
G01X818584D02*
X818876Y94519D01*
X819209Y94644D01*
X819417Y94852D01*
X819501Y95144D01*
X819417Y95435D01*
X819167Y95685D01*
X818792Y95810D01*
X818376D01*
X818126Y95894D01*
X817917Y96102D01*
X817834Y96394D01*
X817959Y96685D01*
X818251Y96894D01*
X818584Y96977D01*
X818917Y96894D01*
X819209Y96685D01*
X819334Y96394D01*
X819251Y96102D01*
X819042Y95894D01*
X818792Y95810D01*
X818376D01*
X818001Y95685D01*
X817751Y95435D01*
X817667Y95144D01*
X817751Y94852D01*
X817959Y94644D01*
X818292Y94519D01*
X818584Y94477D01*
G01X820767Y94977D02*
X821017Y94685D01*
X821351Y94519D01*
X821726Y94477D01*
X822059Y94519D01*
X822392Y94727D01*
X822601Y94977D01*
X822642Y95227D01*
X822559Y95519D01*
X822267Y95727D01*
X821976Y95810D01*
X821601D01*
G01X821976D02*
X822226Y95935D01*
X822434Y96144D01*
X822517Y96394D01*
X822434Y96644D01*
X822226Y96852D01*
X821851Y96977D01*
X821476Y96935D01*
X821101Y96769D01*
G01X823867Y94852D02*
X824117Y94644D01*
X824409Y94519D01*
X824784Y94477D01*
X825159Y94560D01*
X825451Y94727D01*
X825659Y95019D01*
X825701Y95352D01*
X825617Y95685D01*
X825409Y95894D01*
X825117Y96060D01*
X824826Y96102D01*
X824534Y96060D01*
X824159Y95894D01*
X824284Y96977D01*
X825409D01*
G01X828017Y76000D02*
Y78500D01*
X829058D01*
X829392Y78375D01*
X829600Y78208D01*
X829683Y77875D01*
X829600Y77542D01*
X829350Y77333D01*
X829058Y77208D01*
X828017D01*
G01X829058D02*
X829683Y76000D01*
G01X831867D02*
X831950Y76542D01*
X832075Y77000D01*
X832242Y77417D01*
X832450Y77875D01*
X832783Y78500D01*
X831117D01*
G01X835050D02*
X834717Y78417D01*
X834467Y78208D01*
X834300Y77958D01*
X834175Y77625D01*
X834133Y77250D01*
X834175Y76875D01*
X834300Y76542D01*
X834467Y76292D01*
X834717Y76083D01*
X835050Y76000D01*
X835383Y76083D01*
X835633Y76292D01*
X835800Y76542D01*
X835925Y76875D01*
X835967Y77250D01*
X835925Y77625D01*
X835800Y77958D01*
X835633Y78208D01*
X835383Y78417D01*
X835050Y78500D01*
G01X837358Y77042D02*
X837650Y77333D01*
X837900Y77500D01*
X838233Y77583D01*
X838525Y77500D01*
X838733Y77333D01*
X838900Y77083D01*
X838942Y76792D01*
X838900Y76542D01*
X838733Y76292D01*
X838483Y76083D01*
X838192Y76000D01*
X837858Y76083D01*
X837567Y76333D01*
X837400Y76708D01*
X837358Y77125D01*
X837442Y77667D01*
X837567Y77958D01*
X837775Y78250D01*
X838067Y78458D01*
X838358Y78500D01*
X838650Y78417D01*
X838858Y78208D01*
G01X814420Y98874D02*
Y101374D01*
X815461D01*
X815795Y101249D01*
X816003Y101082D01*
X816086Y100749D01*
X816003Y100416D01*
X815753Y100207D01*
X815461Y100082D01*
X814420D01*
G01X815461D02*
X816086Y98874D01*
G01X817561Y100957D02*
X817811Y101207D01*
X818103Y101332D01*
X818436Y101374D01*
X818853Y101291D01*
X819145Y101082D01*
X819228Y100832D01*
X819186Y100582D01*
X819020Y100374D01*
X818186Y99957D01*
X817811Y99666D01*
X817561Y99249D01*
X817478Y98874D01*
X819228D01*
G01X820745Y99166D02*
X821036Y98957D01*
X821370Y98874D01*
X821703Y98957D01*
X821995Y99207D01*
X822203Y99582D01*
X822286Y99957D01*
Y100416D01*
X822203Y100791D01*
X821995Y101124D01*
X821745Y101291D01*
X821453Y101374D01*
X821120Y101291D01*
X820870Y101124D01*
X820703Y100874D01*
X820620Y100541D01*
X820703Y100249D01*
X820911Y99957D01*
X821161Y99791D01*
X821453Y99749D01*
X821786Y99832D01*
X822036Y100041D01*
X822286Y100416D01*
G01X823761Y99916D02*
X824053Y100207D01*
X824303Y100374D01*
X824636Y100457D01*
X824928Y100374D01*
X825136Y100207D01*
X825303Y99957D01*
X825345Y99666D01*
X825303Y99416D01*
X825136Y99166D01*
X824886Y98957D01*
X824595Y98874D01*
X824261Y98957D01*
X823970Y99207D01*
X823803Y99582D01*
X823761Y99999D01*
X823845Y100541D01*
X823970Y100832D01*
X824178Y101124D01*
X824470Y101332D01*
X824761Y101374D01*
X825053Y101291D01*
X825261Y101082D01*
G01X826945Y99166D02*
X827236Y98957D01*
X827570Y98874D01*
X827903Y98957D01*
X828195Y99207D01*
X828403Y99582D01*
X828486Y99957D01*
Y100416D01*
X828403Y100791D01*
X828195Y101124D01*
X827945Y101291D01*
X827653Y101374D01*
X827320Y101291D01*
X827070Y101124D01*
X826903Y100874D01*
X826820Y100541D01*
X826903Y100249D01*
X827111Y99957D01*
X827361Y99791D01*
X827653Y99749D01*
X827986Y99832D01*
X828236Y100041D01*
X828486Y100416D01*
G01X810086Y103899D02*
Y106399D01*
X811127D01*
X811461Y106274D01*
X811669Y106107D01*
X811752Y105774D01*
X811669Y105441D01*
X811419Y105232D01*
X811127Y105107D01*
X810086D01*
G01X811127D02*
X811752Y103899D01*
G01X813227Y105982D02*
X813477Y106232D01*
X813769Y106357D01*
X814102Y106399D01*
X814519Y106316D01*
X814811Y106107D01*
X814894Y105857D01*
X814852Y105607D01*
X814686Y105399D01*
X813852Y104982D01*
X813477Y104691D01*
X813227Y104274D01*
X813144Y103899D01*
X814894D01*
G01X816411Y104191D02*
X816702Y103982D01*
X817036Y103899D01*
X817369Y103982D01*
X817661Y104232D01*
X817869Y104607D01*
X817952Y104982D01*
Y105441D01*
X817869Y105816D01*
X817661Y106149D01*
X817411Y106316D01*
X817119Y106399D01*
X816786Y106316D01*
X816536Y106149D01*
X816369Y105899D01*
X816286Y105566D01*
X816369Y105274D01*
X816577Y104982D01*
X816827Y104816D01*
X817119Y104774D01*
X817452Y104857D01*
X817702Y105066D01*
X817952Y105441D01*
G01X819427Y104941D02*
X819719Y105232D01*
X819969Y105399D01*
X820302Y105482D01*
X820594Y105399D01*
X820802Y105232D01*
X820969Y104982D01*
X821011Y104691D01*
X820969Y104441D01*
X820802Y104191D01*
X820552Y103982D01*
X820261Y103899D01*
X819927Y103982D01*
X819636Y104232D01*
X819469Y104607D01*
X819427Y105024D01*
X819511Y105566D01*
X819636Y105857D01*
X819844Y106149D01*
X820136Y106357D01*
X820427Y106399D01*
X820719Y106316D01*
X820927Y106107D01*
G01X823319Y103899D02*
X823611Y103941D01*
X823944Y104066D01*
X824152Y104274D01*
X824236Y104566D01*
X824152Y104857D01*
X823902Y105107D01*
X823527Y105232D01*
X823111D01*
X822861Y105316D01*
X822652Y105524D01*
X822569Y105816D01*
X822694Y106107D01*
X822986Y106316D01*
X823319Y106399D01*
X823652Y106316D01*
X823944Y106107D01*
X824069Y105816D01*
X823986Y105524D01*
X823777Y105316D01*
X823527Y105232D01*
X823111D01*
X822736Y105107D01*
X822486Y104857D01*
X822402Y104566D01*
X822486Y104274D01*
X822694Y104066D01*
X823027Y103941D01*
X823319Y103899D01*
G01X825860Y107630D02*
Y103630D01*
X833260D01*
G01X812255Y110525D02*
X812005Y110650D01*
X811713Y110733D01*
X811380D01*
X811005Y110608D01*
X810713Y110400D01*
X810505Y110150D01*
X810338Y109733D01*
X810296Y109358D01*
X810380Y108983D01*
X810505Y108733D01*
X810755Y108483D01*
X811046Y108316D01*
X811338Y108233D01*
X811630D01*
X811921Y108316D01*
X812171Y108441D01*
X812380Y108608D01*
G01X814438Y108233D02*
Y110733D01*
X813938Y110233D01*
G01Y108233D02*
X814938D01*
G01X816621Y108733D02*
X816871Y108441D01*
X817205Y108275D01*
X817580Y108233D01*
X817913Y108275D01*
X818246Y108483D01*
X818455Y108733D01*
X818496Y108983D01*
X818413Y109275D01*
X818121Y109483D01*
X817830Y109566D01*
X817455D01*
G01X817830D02*
X818080Y109691D01*
X818288Y109900D01*
X818371Y110150D01*
X818288Y110400D01*
X818080Y110608D01*
X817705Y110733D01*
X817330Y110691D01*
X816955Y110525D01*
G01X819846Y109275D02*
X820138Y109566D01*
X820388Y109733D01*
X820721Y109816D01*
X821013Y109733D01*
X821221Y109566D01*
X821388Y109316D01*
X821430Y109025D01*
X821388Y108775D01*
X821221Y108525D01*
X820971Y108316D01*
X820680Y108233D01*
X820346Y108316D01*
X820055Y108566D01*
X819888Y108941D01*
X819846Y109358D01*
X819930Y109900D01*
X820055Y110191D01*
X820263Y110483D01*
X820555Y110691D01*
X820846Y110733D01*
X821138Y110650D01*
X821346Y110441D01*
G01X819550Y118848D02*
Y121348D01*
X820591D01*
X820925Y121223D01*
X821133Y121056D01*
X821216Y120723D01*
X821133Y120390D01*
X820883Y120181D01*
X820591Y120056D01*
X819550D01*
G01X820591D02*
X821216Y118848D01*
G01X823483D02*
X823775Y118890D01*
X824108Y119015D01*
X824316Y119223D01*
X824400Y119515D01*
X824316Y119806D01*
X824066Y120056D01*
X823691Y120181D01*
X823275D01*
X823025Y120265D01*
X822816Y120473D01*
X822733Y120765D01*
X822858Y121056D01*
X823150Y121265D01*
X823483Y121348D01*
X823816Y121265D01*
X824108Y121056D01*
X824233Y120765D01*
X824150Y120473D01*
X823941Y120265D01*
X823691Y120181D01*
X823275D01*
X822900Y120056D01*
X822650Y119806D01*
X822566Y119515D01*
X822650Y119223D01*
X822858Y119015D01*
X823191Y118890D01*
X823483Y118848D01*
G01X825791Y120931D02*
X826041Y121181D01*
X826333Y121306D01*
X826666Y121348D01*
X827083Y121265D01*
X827375Y121056D01*
X827458Y120806D01*
X827416Y120556D01*
X827250Y120348D01*
X826416Y119931D01*
X826041Y119640D01*
X825791Y119223D01*
X825708Y118848D01*
X827458D01*
G01X828766Y119348D02*
X829016Y119056D01*
X829350Y118890D01*
X829725Y118848D01*
X830058Y118890D01*
X830391Y119098D01*
X830600Y119348D01*
X830641Y119598D01*
X830558Y119890D01*
X830266Y120098D01*
X829975Y120181D01*
X829600D01*
G01X829975D02*
X830225Y120306D01*
X830433Y120515D01*
X830516Y120765D01*
X830433Y121015D01*
X830225Y121223D01*
X829850Y121348D01*
X829475Y121306D01*
X829100Y121140D01*
G01X814113Y116898D02*
Y120898D01*
X806713D01*
G01X819319Y123245D02*
Y125745D01*
X820360D01*
X820694Y125620D01*
X820902Y125453D01*
X820985Y125120D01*
X820902Y124787D01*
X820652Y124578D01*
X820360Y124453D01*
X819319D01*
G01X820360D02*
X820985Y123245D01*
G01X822460Y125328D02*
X822710Y125578D01*
X823002Y125703D01*
X823335Y125745D01*
X823752Y125662D01*
X824044Y125453D01*
X824127Y125203D01*
X824085Y124953D01*
X823919Y124745D01*
X823085Y124328D01*
X822710Y124037D01*
X822460Y123620D01*
X822377Y123245D01*
X824127D01*
G01X825644Y123537D02*
X825935Y123328D01*
X826269Y123245D01*
X826602Y123328D01*
X826894Y123578D01*
X827102Y123953D01*
X827185Y124328D01*
Y124787D01*
X827102Y125162D01*
X826894Y125495D01*
X826644Y125662D01*
X826352Y125745D01*
X826019Y125662D01*
X825769Y125495D01*
X825602Y125245D01*
X825519Y124912D01*
X825602Y124620D01*
X825810Y124328D01*
X826060Y124162D01*
X826352Y124120D01*
X826685Y124203D01*
X826935Y124412D01*
X827185Y124787D01*
G01X829452Y123245D02*
X829744Y123287D01*
X830077Y123412D01*
X830285Y123620D01*
X830369Y123912D01*
X830285Y124203D01*
X830035Y124453D01*
X829660Y124578D01*
X829244D01*
X828994Y124662D01*
X828785Y124870D01*
X828702Y125162D01*
X828827Y125453D01*
X829119Y125662D01*
X829452Y125745D01*
X829785Y125662D01*
X830077Y125453D01*
X830202Y125162D01*
X830119Y124870D01*
X829910Y124662D01*
X829660Y124578D01*
X829244D01*
X828869Y124453D01*
X828619Y124203D01*
X828535Y123912D01*
X828619Y123620D01*
X828827Y123412D01*
X829160Y123287D01*
X829452Y123245D01*
G01X832552Y125745D02*
X832219Y125662D01*
X831969Y125453D01*
X831802Y125203D01*
X831677Y124870D01*
X831635Y124495D01*
X831677Y124120D01*
X831802Y123787D01*
X831969Y123537D01*
X832219Y123328D01*
X832552Y123245D01*
X832885Y123328D01*
X833135Y123537D01*
X833302Y123787D01*
X833427Y124120D01*
X833469Y124495D01*
X833427Y124870D01*
X833302Y125203D01*
X833135Y125453D01*
X832885Y125662D01*
X832552Y125745D01*
G01X809725Y125631D02*
Y121631D01*
X817125D01*
G01X807196Y132919D02*
Y135419D01*
X808237D01*
X808571Y135294D01*
X808779Y135127D01*
X808862Y134794D01*
X808779Y134461D01*
X808529Y134252D01*
X808237Y134127D01*
X807196D01*
G01X808237D02*
X808862Y132919D01*
G01X810337Y135002D02*
X810587Y135252D01*
X810879Y135377D01*
X811212Y135419D01*
X811629Y135336D01*
X811921Y135127D01*
X812004Y134877D01*
X811962Y134627D01*
X811796Y134419D01*
X810962Y134002D01*
X810587Y133711D01*
X810337Y133294D01*
X810254Y132919D01*
X812004D01*
G01X813521Y133211D02*
X813812Y133002D01*
X814146Y132919D01*
X814479Y133002D01*
X814771Y133252D01*
X814979Y133627D01*
X815062Y134002D01*
Y134461D01*
X814979Y134836D01*
X814771Y135169D01*
X814521Y135336D01*
X814229Y135419D01*
X813896Y135336D01*
X813646Y135169D01*
X813479Y134919D01*
X813396Y134586D01*
X813479Y134294D01*
X813687Y134002D01*
X813937Y133836D01*
X814229Y133794D01*
X814562Y133877D01*
X814812Y134086D01*
X815062Y134461D01*
G01X817246Y132919D02*
X817329Y133461D01*
X817454Y133919D01*
X817621Y134336D01*
X817829Y134794D01*
X818162Y135419D01*
X816496D01*
G01X819721Y133211D02*
X820012Y133002D01*
X820346Y132919D01*
X820679Y133002D01*
X820971Y133252D01*
X821179Y133627D01*
X821262Y134002D01*
Y134461D01*
X821179Y134836D01*
X820971Y135169D01*
X820721Y135336D01*
X820429Y135419D01*
X820096Y135336D01*
X819846Y135169D01*
X819679Y134919D01*
X819596Y134586D01*
X819679Y134294D01*
X819887Y134002D01*
X820137Y133836D01*
X820429Y133794D01*
X820762Y133877D01*
X821012Y134086D01*
X821262Y134461D01*
G01X809725Y129631D02*
Y125631D01*
X817125D01*
G01X838915Y110790D02*
X836415D01*
Y111831D01*
X836540Y112165D01*
X836707Y112373D01*
X837040Y112456D01*
X837373Y112373D01*
X837582Y112123D01*
X837707Y111831D01*
Y110790D01*
G01Y111831D02*
X838915Y112456D01*
G01Y114723D02*
X838873Y115015D01*
X838748Y115348D01*
X838540Y115556D01*
X838248Y115640D01*
X837957Y115556D01*
X837707Y115306D01*
X837582Y114931D01*
Y114515D01*
X837498Y114265D01*
X837290Y114056D01*
X836998Y113973D01*
X836707Y114098D01*
X836498Y114390D01*
X836415Y114723D01*
X836498Y115056D01*
X836707Y115348D01*
X836998Y115473D01*
X837290Y115390D01*
X837498Y115181D01*
X837582Y114931D01*
Y114515D01*
X837707Y114140D01*
X837957Y113890D01*
X838248Y113806D01*
X838540Y113890D01*
X838748Y114098D01*
X838873Y114431D01*
X838915Y114723D01*
G01X838415Y116906D02*
X838707Y117156D01*
X838873Y117490D01*
X838915Y117865D01*
X838873Y118198D01*
X838665Y118531D01*
X838415Y118740D01*
X838165Y118781D01*
X837873Y118698D01*
X837665Y118406D01*
X837582Y118115D01*
Y117740D01*
G01Y118115D02*
X837457Y118365D01*
X837248Y118573D01*
X836998Y118656D01*
X836748Y118573D01*
X836540Y118365D01*
X836415Y117990D01*
X836457Y117615D01*
X836623Y117240D01*
G01X838623Y120215D02*
X838832Y120506D01*
X838915Y120840D01*
X838832Y121173D01*
X838582Y121465D01*
X838207Y121673D01*
X837832Y121756D01*
X837373D01*
X836998Y121673D01*
X836665Y121465D01*
X836498Y121215D01*
X836415Y120923D01*
X836498Y120590D01*
X836665Y120340D01*
X836915Y120173D01*
X837248Y120090D01*
X837540Y120173D01*
X837832Y120381D01*
X837998Y120631D01*
X838040Y120923D01*
X837957Y121256D01*
X837748Y121506D01*
X837373Y121756D01*
G01X812443Y114733D02*
X812193Y114858D01*
X811901Y114941D01*
X811568D01*
X811193Y114816D01*
X810901Y114608D01*
X810693Y114358D01*
X810526Y113941D01*
X810484Y113566D01*
X810568Y113191D01*
X810693Y112941D01*
X810943Y112691D01*
X811234Y112524D01*
X811526Y112441D01*
X811818D01*
X812109Y112524D01*
X812359Y112649D01*
X812568Y112816D01*
G01X814626Y112441D02*
Y114941D01*
X814126Y114441D01*
G01Y112441D02*
X815126D01*
G01X816809Y112941D02*
X817059Y112649D01*
X817393Y112483D01*
X817768Y112441D01*
X818101Y112483D01*
X818434Y112691D01*
X818643Y112941D01*
X818684Y113191D01*
X818601Y113483D01*
X818309Y113691D01*
X818018Y113774D01*
X817643D01*
G01X818018D02*
X818268Y113899D01*
X818476Y114108D01*
X818559Y114358D01*
X818476Y114608D01*
X818268Y114816D01*
X817893Y114941D01*
X817518Y114899D01*
X817143Y114733D01*
G01X819909Y112816D02*
X820159Y112608D01*
X820451Y112483D01*
X820826Y112441D01*
X821201Y112524D01*
X821493Y112691D01*
X821701Y112983D01*
X821743Y113316D01*
X821659Y113649D01*
X821451Y113858D01*
X821159Y114024D01*
X820868Y114066D01*
X820576Y114024D01*
X820201Y113858D01*
X820326Y114941D01*
X821451D01*
G01X833267Y155459D02*
X833017Y155584D01*
X832725Y155667D01*
X832392D01*
X832017Y155542D01*
X831725Y155334D01*
X831517Y155084D01*
X831350Y154667D01*
X831308Y154292D01*
X831392Y153917D01*
X831517Y153667D01*
X831767Y153417D01*
X832058Y153250D01*
X832350Y153167D01*
X832642D01*
X832933Y153250D01*
X833183Y153375D01*
X833392Y153542D01*
G01X834658Y154209D02*
X834950Y154500D01*
X835200Y154667D01*
X835533Y154750D01*
X835825Y154667D01*
X836033Y154500D01*
X836200Y154250D01*
X836242Y153959D01*
X836200Y153709D01*
X836033Y153459D01*
X835783Y153250D01*
X835492Y153167D01*
X835158Y153250D01*
X834867Y153500D01*
X834700Y153875D01*
X834658Y154292D01*
X834742Y154834D01*
X834867Y155125D01*
X835075Y155417D01*
X835367Y155625D01*
X835658Y155667D01*
X835950Y155584D01*
X836158Y155375D01*
G01X837633Y153667D02*
X837883Y153375D01*
X838217Y153209D01*
X838592Y153167D01*
X838925Y153209D01*
X839258Y153417D01*
X839467Y153667D01*
X839508Y153917D01*
X839425Y154209D01*
X839133Y154417D01*
X838842Y154500D01*
X838467D01*
G01X838842D02*
X839092Y154625D01*
X839300Y154834D01*
X839383Y155084D01*
X839300Y155334D01*
X839092Y155542D01*
X838717Y155667D01*
X838342Y155625D01*
X837967Y155459D01*
G01X840942Y153459D02*
X841233Y153250D01*
X841567Y153167D01*
X841900Y153250D01*
X842192Y153500D01*
X842400Y153875D01*
X842483Y154250D01*
Y154709D01*
X842400Y155084D01*
X842192Y155417D01*
X841942Y155584D01*
X841650Y155667D01*
X841317Y155584D01*
X841067Y155417D01*
X840900Y155167D01*
X840817Y154834D01*
X840900Y154542D01*
X841108Y154250D01*
X841358Y154084D01*
X841650Y154042D01*
X841983Y154125D01*
X842233Y154334D01*
X842483Y154709D01*
G01X833253Y151532D02*
X833003Y151657D01*
X832711Y151740D01*
X832378D01*
X832003Y151615D01*
X831711Y151407D01*
X831503Y151157D01*
X831336Y150740D01*
X831294Y150365D01*
X831378Y149990D01*
X831503Y149740D01*
X831753Y149490D01*
X832044Y149323D01*
X832336Y149240D01*
X832628D01*
X832919Y149323D01*
X833169Y149448D01*
X833378Y149615D01*
G01X834644Y150282D02*
X834936Y150573D01*
X835186Y150740D01*
X835519Y150823D01*
X835811Y150740D01*
X836019Y150573D01*
X836186Y150323D01*
X836228Y150032D01*
X836186Y149782D01*
X836019Y149532D01*
X835769Y149323D01*
X835478Y149240D01*
X835144Y149323D01*
X834853Y149573D01*
X834686Y149948D01*
X834644Y150365D01*
X834728Y150907D01*
X834853Y151198D01*
X835061Y151490D01*
X835353Y151698D01*
X835644Y151740D01*
X835936Y151657D01*
X836144Y151448D01*
G01X839036Y149240D02*
Y151740D01*
X837494Y149948D01*
X839578D01*
G01X841636Y149240D02*
Y151740D01*
X841136Y151240D01*
G01Y149240D02*
X842136D01*
G01X813441Y290854D02*
X825141D01*
Y259854D01*
X813441D01*
Y290854D01*
G01X817317Y296292D02*
X817067Y296417D01*
X816775Y296500D01*
X816442D01*
X816067Y296375D01*
X815775Y296167D01*
X815567Y295917D01*
X815400Y295500D01*
X815358Y295125D01*
X815442Y294750D01*
X815567Y294500D01*
X815817Y294250D01*
X816108Y294083D01*
X816400Y294000D01*
X816692D01*
X816983Y294083D01*
X817233Y294208D01*
X817442Y294375D01*
G01X818542Y294000D02*
Y296500D01*
X820458Y294000D01*
Y296500D01*
G01X822517Y294000D02*
X822600Y294542D01*
X822725Y295000D01*
X822892Y295417D01*
X823100Y295875D01*
X823433Y296500D01*
X821767D01*
G01X830583Y388966D02*
Y387174D01*
X830750Y386799D01*
X831083Y386549D01*
X831500Y386466D01*
X831917Y386549D01*
X832250Y386799D01*
X832417Y387174D01*
Y388966D01*
G01X833808Y388549D02*
X834058Y388799D01*
X834350Y388924D01*
X834683Y388966D01*
X835100Y388883D01*
X835392Y388674D01*
X835475Y388424D01*
X835433Y388174D01*
X835267Y387966D01*
X834433Y387549D01*
X834058Y387258D01*
X833808Y386841D01*
X833725Y386466D01*
X835475D01*
G01X837617D02*
X837700Y387008D01*
X837825Y387466D01*
X837992Y387883D01*
X838200Y388341D01*
X838533Y388966D01*
X836867D01*
G01X810000Y397317D02*
X807500D01*
Y398358D01*
X807625Y398692D01*
X807792Y398900D01*
X808125Y398983D01*
X808458Y398900D01*
X808667Y398650D01*
X808792Y398358D01*
Y397317D01*
G01Y398358D02*
X810000Y398983D01*
G01X808958Y400458D02*
X808667Y400750D01*
X808500Y401000D01*
X808417Y401333D01*
X808500Y401625D01*
X808667Y401833D01*
X808917Y402000D01*
X809208Y402042D01*
X809458Y402000D01*
X809708Y401833D01*
X809917Y401583D01*
X810000Y401292D01*
X809917Y400958D01*
X809667Y400667D01*
X809292Y400500D01*
X808875Y400458D01*
X808333Y400542D01*
X808042Y400667D01*
X807750Y400875D01*
X807542Y401167D01*
X807500Y401458D01*
X807583Y401750D01*
X807792Y401958D01*
G01X808958Y403558D02*
X808667Y403850D01*
X808500Y404100D01*
X808417Y404433D01*
X808500Y404725D01*
X808667Y404933D01*
X808917Y405100D01*
X809208Y405142D01*
X809458Y405100D01*
X809708Y404933D01*
X809917Y404683D01*
X810000Y404392D01*
X809917Y404058D01*
X809667Y403767D01*
X809292Y403600D01*
X808875Y403558D01*
X808333Y403642D01*
X808042Y403767D01*
X807750Y403975D01*
X807542Y404267D01*
X807500Y404558D01*
X807583Y404850D01*
X807792Y405058D01*
G01X809625Y406533D02*
X809833Y406783D01*
X809958Y407075D01*
X810000Y407450D01*
X809917Y407825D01*
X809750Y408117D01*
X809458Y408325D01*
X809125Y408367D01*
X808792Y408283D01*
X808583Y408075D01*
X808417Y407783D01*
X808375Y407492D01*
X808417Y407200D01*
X808583Y406825D01*
X807500Y406950D01*
Y408075D01*
G01X822934Y408817D02*
X820434D01*
Y409858D01*
X820559Y410192D01*
X820726Y410400D01*
X821059Y410483D01*
X821392Y410400D01*
X821601Y410150D01*
X821726Y409858D01*
Y408817D01*
G01Y409858D02*
X822934Y410483D01*
G01Y413250D02*
X820434D01*
X822226Y411708D01*
Y413792D01*
G01X822559Y414933D02*
X822767Y415183D01*
X822892Y415475D01*
X822934Y415850D01*
X822851Y416225D01*
X822684Y416517D01*
X822392Y416725D01*
X822059Y416767D01*
X821726Y416683D01*
X821517Y416475D01*
X821351Y416183D01*
X821309Y415892D01*
X821351Y415600D01*
X821517Y415225D01*
X820434Y415350D01*
Y416475D01*
G01X822934Y419450D02*
X820434D01*
X822226Y417908D01*
Y419992D01*
G01X817617Y390466D02*
Y392966D01*
X818658D01*
X818992Y392841D01*
X819200Y392674D01*
X819283Y392341D01*
X819200Y392008D01*
X818950Y391799D01*
X818658Y391674D01*
X817617D01*
G01X818658D02*
X819283Y390466D01*
G01X822050D02*
Y392966D01*
X820508Y391174D01*
X822592D01*
G01X823733Y390966D02*
X823983Y390674D01*
X824317Y390508D01*
X824692Y390466D01*
X825025Y390508D01*
X825358Y390716D01*
X825567Y390966D01*
X825608Y391216D01*
X825525Y391508D01*
X825233Y391716D01*
X824942Y391799D01*
X824567D01*
G01X824942D02*
X825192Y391924D01*
X825400Y392133D01*
X825483Y392383D01*
X825400Y392633D01*
X825192Y392841D01*
X824817Y392966D01*
X824442Y392924D01*
X824067Y392758D01*
G01X826833Y390841D02*
X827083Y390633D01*
X827375Y390508D01*
X827750Y390466D01*
X828125Y390549D01*
X828417Y390716D01*
X828625Y391008D01*
X828667Y391341D01*
X828583Y391674D01*
X828375Y391883D01*
X828083Y392049D01*
X827792Y392091D01*
X827500Y392049D01*
X827125Y391883D01*
X827250Y392966D01*
X828375D01*
G01X812317Y386700D02*
Y389200D01*
X813358D01*
X813692Y389075D01*
X813900Y388908D01*
X813983Y388575D01*
X813900Y388242D01*
X813650Y388033D01*
X813358Y387908D01*
X812317D01*
G01X813358D02*
X813983Y386700D01*
G01X816750D02*
Y389200D01*
X815208Y387408D01*
X817292D01*
G01X819350Y386700D02*
Y389200D01*
X818850Y388700D01*
G01Y386700D02*
X819850D01*
G01X821658Y388783D02*
X821908Y389033D01*
X822200Y389158D01*
X822533Y389200D01*
X822950Y389117D01*
X823242Y388908D01*
X823325Y388658D01*
X823283Y388408D01*
X823117Y388200D01*
X822283Y387783D01*
X821908Y387492D01*
X821658Y387075D01*
X821575Y386700D01*
X823325D01*
G01X823100Y395817D02*
X820600D01*
Y396858D01*
X820725Y397192D01*
X820892Y397400D01*
X821225Y397483D01*
X821558Y397400D01*
X821767Y397150D01*
X821892Y396858D01*
Y395817D01*
G01Y396858D02*
X823100Y397483D01*
G01X821017Y398958D02*
X820767Y399208D01*
X820642Y399500D01*
X820600Y399833D01*
X820683Y400250D01*
X820892Y400542D01*
X821142Y400625D01*
X821392Y400583D01*
X821600Y400417D01*
X822017Y399583D01*
X822308Y399208D01*
X822725Y398958D01*
X823100Y398875D01*
Y400625D01*
G01Y402767D02*
X822558Y402850D01*
X822100Y402975D01*
X821683Y403142D01*
X821225Y403350D01*
X820600Y403683D01*
Y402017D01*
G01X822725Y405033D02*
X822933Y405283D01*
X823058Y405575D01*
X823100Y405950D01*
X823017Y406325D01*
X822850Y406617D01*
X822558Y406825D01*
X822225Y406867D01*
X821892Y406783D01*
X821683Y406575D01*
X821517Y406283D01*
X821475Y405992D01*
X821517Y405700D01*
X821683Y405325D01*
X820600Y405450D01*
Y406575D01*
G01X838901Y393694D02*
X836401D01*
Y394735D01*
X836526Y395069D01*
X836693Y395277D01*
X837026Y395360D01*
X837359Y395277D01*
X837568Y395027D01*
X837693Y394735D01*
Y393694D01*
G01Y394735D02*
X838901Y395360D01*
G01Y397627D02*
X836401D01*
X836901Y397127D01*
G01X838901D02*
Y398127D01*
G01Y400644D02*
X838359Y400727D01*
X837901Y400852D01*
X837484Y401019D01*
X837026Y401227D01*
X836401Y401560D01*
Y399894D01*
G01X837859Y403035D02*
X837568Y403327D01*
X837401Y403577D01*
X837318Y403910D01*
X837401Y404202D01*
X837568Y404410D01*
X837818Y404577D01*
X838109Y404619D01*
X838359Y404577D01*
X838609Y404410D01*
X838818Y404160D01*
X838901Y403869D01*
X838818Y403535D01*
X838568Y403244D01*
X838193Y403077D01*
X837776Y403035D01*
X837234Y403119D01*
X836943Y403244D01*
X836651Y403452D01*
X836443Y403744D01*
X836401Y404035D01*
X836484Y404327D01*
X836693Y404535D01*
G01X834120Y393819D02*
X831620D01*
Y394860D01*
X831745Y395194D01*
X831912Y395402D01*
X832245Y395485D01*
X832578Y395402D01*
X832787Y395152D01*
X832912Y394860D01*
Y393819D01*
G01Y394860D02*
X834120Y395485D01*
G01Y397752D02*
X831620D01*
X832120Y397252D01*
G01X834120D02*
Y398252D01*
G01Y400769D02*
X833578Y400852D01*
X833120Y400977D01*
X832703Y401144D01*
X832245Y401352D01*
X831620Y401685D01*
Y400019D01*
G01X833745Y403035D02*
X833953Y403285D01*
X834078Y403577D01*
X834120Y403952D01*
X834037Y404327D01*
X833870Y404619D01*
X833578Y404827D01*
X833245Y404869D01*
X832912Y404785D01*
X832703Y404577D01*
X832537Y404285D01*
X832495Y403994D01*
X832537Y403702D01*
X832703Y403327D01*
X831620Y403452D01*
Y404577D01*
G01X817019Y394175D02*
X817227Y394508D01*
X817352Y394883D01*
Y395217D01*
X817227Y395550D01*
X817019Y395800D01*
X816727Y395925D01*
X816435Y395842D01*
X816185Y395633D01*
X816019Y395258D01*
X815935Y394758D01*
X815769Y394467D01*
X815477Y394342D01*
X815185Y394425D01*
X814977Y394633D01*
X814852Y394925D01*
Y395217D01*
X814935Y395508D01*
X815144Y395758D01*
G01X815060Y399067D02*
X814935Y398817D01*
X814852Y398525D01*
Y398192D01*
X814977Y397817D01*
X815185Y397525D01*
X815435Y397317D01*
X815852Y397150D01*
X816227Y397108D01*
X816602Y397192D01*
X816852Y397317D01*
X817102Y397567D01*
X817269Y397858D01*
X817352Y398150D01*
Y398442D01*
X817269Y398733D01*
X817144Y398983D01*
X816977Y399192D01*
G01X817352Y401250D02*
X814852D01*
X815352Y400750D01*
G01X817352D02*
Y401750D01*
G01Y404350D02*
X814852D01*
X815352Y403850D01*
G01X817352D02*
Y404850D01*
G01Y407450D02*
X814852D01*
X815352Y406950D01*
G01X817352D02*
Y407950D01*
G01X816310Y409758D02*
X816019Y410050D01*
X815852Y410300D01*
X815769Y410633D01*
X815852Y410925D01*
X816019Y411133D01*
X816269Y411300D01*
X816560Y411342D01*
X816810Y411300D01*
X817060Y411133D01*
X817269Y410883D01*
X817352Y410592D01*
X817269Y410258D01*
X817019Y409967D01*
X816644Y409800D01*
X816227Y409758D01*
X815685Y409842D01*
X815394Y409967D01*
X815102Y410175D01*
X814894Y410467D01*
X814852Y410758D01*
X814935Y411050D01*
X815144Y411258D01*
G01X813519Y394175D02*
X813727Y394508D01*
X813852Y394883D01*
Y395217D01*
X813727Y395550D01*
X813519Y395800D01*
X813227Y395925D01*
X812935Y395842D01*
X812685Y395633D01*
X812519Y395258D01*
X812435Y394758D01*
X812269Y394467D01*
X811977Y394342D01*
X811685Y394425D01*
X811477Y394633D01*
X811352Y394925D01*
Y395217D01*
X811435Y395508D01*
X811644Y395758D01*
G01X811560Y399067D02*
X811435Y398817D01*
X811352Y398525D01*
Y398192D01*
X811477Y397817D01*
X811685Y397525D01*
X811935Y397317D01*
X812352Y397150D01*
X812727Y397108D01*
X813102Y397192D01*
X813352Y397317D01*
X813602Y397567D01*
X813769Y397858D01*
X813852Y398150D01*
Y398442D01*
X813769Y398733D01*
X813644Y398983D01*
X813477Y399192D01*
G01X813852Y401250D02*
X811352D01*
X811852Y400750D01*
G01X813852D02*
Y401750D01*
G01Y404350D02*
X811352D01*
X811852Y403850D01*
G01X813852D02*
Y404850D01*
G01Y407450D02*
X811352D01*
X811852Y406950D01*
G01X813852D02*
Y407950D01*
G01Y411050D02*
X811352D01*
X813144Y409508D01*
Y411592D01*
G01X829100Y400200D02*
X829058Y399867D01*
X828892Y399575D01*
X828642Y399325D01*
X828350Y399158D01*
X828017Y399075D01*
X827683D01*
X827350Y399158D01*
X827058Y399325D01*
X826808Y399575D01*
X826642Y399867D01*
X826600Y400200D01*
X826642Y400533D01*
X826808Y400825D01*
X827058Y401075D01*
X827350Y401242D01*
X827683Y401325D01*
X828017D01*
X828350Y401242D01*
X828642Y401075D01*
X828892Y400825D01*
X829058Y400533D01*
X829100Y400200D01*
G01X828433Y400533D02*
X829100Y401033D01*
G01Y403300D02*
X826600D01*
X827100Y402800D01*
G01X829100D02*
Y403800D01*
G01X828808Y405692D02*
X829017Y405983D01*
X829100Y406317D01*
X829017Y406650D01*
X828767Y406942D01*
X828392Y407150D01*
X828017Y407233D01*
X827558D01*
X827183Y407150D01*
X826850Y406942D01*
X826683Y406692D01*
X826600Y406400D01*
X826683Y406067D01*
X826850Y405817D01*
X827100Y405650D01*
X827433Y405567D01*
X827725Y405650D01*
X828017Y405858D01*
X828183Y406108D01*
X828225Y406400D01*
X828142Y406733D01*
X827933Y406983D01*
X827558Y407233D01*
G01X836167Y427966D02*
X835467Y428366D01*
X834650Y428633D01*
X833717D01*
X832667Y428233D01*
X831850Y427566D01*
X831267Y426766D01*
X830800Y425433D01*
X830683Y424233D01*
X830917Y423033D01*
X831267Y422233D01*
X831967Y421433D01*
X832783Y420900D01*
X833600Y420633D01*
X834417D01*
X835233Y420900D01*
X835933Y421300D01*
X836517Y421833D01*
G01X807617Y441100D02*
Y443600D01*
X808658D01*
X808992Y443475D01*
X809200Y443308D01*
X809283Y442975D01*
X809200Y442642D01*
X808950Y442433D01*
X808658Y442308D01*
X807617D01*
G01X808658D02*
X809283Y441100D01*
G01X811467D02*
X811550Y441642D01*
X811675Y442100D01*
X811842Y442517D01*
X812050Y442975D01*
X812383Y443600D01*
X810717D01*
G01X814650Y441100D02*
Y443600D01*
X814150Y443100D01*
G01Y441100D02*
X815150D01*
G01X818250D02*
Y443600D01*
X816708Y441808D01*
X818792D01*
G01X807117Y416300D02*
Y418800D01*
X808158D01*
X808492Y418675D01*
X808700Y418508D01*
X808783Y418175D01*
X808700Y417842D01*
X808450Y417633D01*
X808158Y417508D01*
X807117D01*
G01X808158D02*
X808783Y416300D01*
G01X810258Y417342D02*
X810550Y417633D01*
X810800Y417800D01*
X811133Y417883D01*
X811425Y417800D01*
X811633Y417633D01*
X811800Y417383D01*
X811842Y417092D01*
X811800Y416842D01*
X811633Y416592D01*
X811383Y416383D01*
X811092Y416300D01*
X810758Y416383D01*
X810467Y416633D01*
X810300Y417008D01*
X810258Y417425D01*
X810342Y417967D01*
X810467Y418258D01*
X810675Y418550D01*
X810967Y418758D01*
X811258Y418800D01*
X811550Y418717D01*
X811758Y418508D01*
G01X813358Y417342D02*
X813650Y417633D01*
X813900Y417800D01*
X814233Y417883D01*
X814525Y417800D01*
X814733Y417633D01*
X814900Y417383D01*
X814942Y417092D01*
X814900Y416842D01*
X814733Y416592D01*
X814483Y416383D01*
X814192Y416300D01*
X813858Y416383D01*
X813567Y416633D01*
X813400Y417008D01*
X813358Y417425D01*
X813442Y417967D01*
X813567Y418258D01*
X813775Y418550D01*
X814067Y418758D01*
X814358Y418800D01*
X814650Y418717D01*
X814858Y418508D01*
G01X816333Y416800D02*
X816583Y416508D01*
X816917Y416342D01*
X817292Y416300D01*
X817625Y416342D01*
X817958Y416550D01*
X818167Y416800D01*
X818208Y417050D01*
X818125Y417342D01*
X817833Y417550D01*
X817542Y417633D01*
X817167D01*
G01X817542D02*
X817792Y417758D01*
X818000Y417967D01*
X818083Y418217D01*
X818000Y418467D01*
X817792Y418675D01*
X817417Y418800D01*
X817042Y418758D01*
X816667Y418592D01*
G01X807117Y424300D02*
Y426800D01*
X808158D01*
X808492Y426675D01*
X808700Y426508D01*
X808783Y426175D01*
X808700Y425842D01*
X808450Y425633D01*
X808158Y425508D01*
X807117D01*
G01X808158D02*
X808783Y424300D01*
G01X810258Y425342D02*
X810550Y425633D01*
X810800Y425800D01*
X811133Y425883D01*
X811425Y425800D01*
X811633Y425633D01*
X811800Y425383D01*
X811842Y425092D01*
X811800Y424842D01*
X811633Y424592D01*
X811383Y424383D01*
X811092Y424300D01*
X810758Y424383D01*
X810467Y424633D01*
X810300Y425008D01*
X810258Y425425D01*
X810342Y425967D01*
X810467Y426258D01*
X810675Y426550D01*
X810967Y426758D01*
X811258Y426800D01*
X811550Y426717D01*
X811758Y426508D01*
G01X813358Y425342D02*
X813650Y425633D01*
X813900Y425800D01*
X814233Y425883D01*
X814525Y425800D01*
X814733Y425633D01*
X814900Y425383D01*
X814942Y425092D01*
X814900Y424842D01*
X814733Y424592D01*
X814483Y424383D01*
X814192Y424300D01*
X813858Y424383D01*
X813567Y424633D01*
X813400Y425008D01*
X813358Y425425D01*
X813442Y425967D01*
X813567Y426258D01*
X813775Y426550D01*
X814067Y426758D01*
X814358Y426800D01*
X814650Y426717D01*
X814858Y426508D01*
G01X816458Y426383D02*
X816708Y426633D01*
X817000Y426758D01*
X817333Y426800D01*
X817750Y426717D01*
X818042Y426508D01*
X818125Y426258D01*
X818083Y426008D01*
X817917Y425800D01*
X817083Y425383D01*
X816708Y425092D01*
X816458Y424675D01*
X816375Y424300D01*
X818125D01*
G01X807450Y432334D02*
Y434834D01*
X808491D01*
X808825Y434709D01*
X809033Y434542D01*
X809116Y434209D01*
X809033Y433876D01*
X808783Y433667D01*
X808491Y433542D01*
X807450D01*
G01X808491D02*
X809116Y432334D01*
G01X810591Y433376D02*
X810883Y433667D01*
X811133Y433834D01*
X811466Y433917D01*
X811758Y433834D01*
X811966Y433667D01*
X812133Y433417D01*
X812175Y433126D01*
X812133Y432876D01*
X811966Y432626D01*
X811716Y432417D01*
X811425Y432334D01*
X811091Y432417D01*
X810800Y432667D01*
X810633Y433042D01*
X810591Y433459D01*
X810675Y434001D01*
X810800Y434292D01*
X811008Y434584D01*
X811300Y434792D01*
X811591Y434834D01*
X811883Y434751D01*
X812091Y434542D01*
G01X813691Y433376D02*
X813983Y433667D01*
X814233Y433834D01*
X814566Y433917D01*
X814858Y433834D01*
X815066Y433667D01*
X815233Y433417D01*
X815275Y433126D01*
X815233Y432876D01*
X815066Y432626D01*
X814816Y432417D01*
X814525Y432334D01*
X814191Y432417D01*
X813900Y432667D01*
X813733Y433042D01*
X813691Y433459D01*
X813775Y434001D01*
X813900Y434292D01*
X814108Y434584D01*
X814400Y434792D01*
X814691Y434834D01*
X814983Y434751D01*
X815191Y434542D01*
G01X817583Y432334D02*
Y434834D01*
X817083Y434334D01*
G01Y432334D02*
X818083D01*
G01X807117Y420300D02*
Y422800D01*
X808158D01*
X808492Y422675D01*
X808700Y422508D01*
X808783Y422175D01*
X808700Y421842D01*
X808450Y421633D01*
X808158Y421508D01*
X807117D01*
G01X808158D02*
X808783Y420300D01*
G01X810258Y421342D02*
X810550Y421633D01*
X810800Y421800D01*
X811133Y421883D01*
X811425Y421800D01*
X811633Y421633D01*
X811800Y421383D01*
X811842Y421092D01*
X811800Y420842D01*
X811633Y420592D01*
X811383Y420383D01*
X811092Y420300D01*
X810758Y420383D01*
X810467Y420633D01*
X810300Y421008D01*
X810258Y421425D01*
X810342Y421967D01*
X810467Y422258D01*
X810675Y422550D01*
X810967Y422758D01*
X811258Y422800D01*
X811550Y422717D01*
X811758Y422508D01*
G01X813358Y421342D02*
X813650Y421633D01*
X813900Y421800D01*
X814233Y421883D01*
X814525Y421800D01*
X814733Y421633D01*
X814900Y421383D01*
X814942Y421092D01*
X814900Y420842D01*
X814733Y420592D01*
X814483Y420383D01*
X814192Y420300D01*
X813858Y420383D01*
X813567Y420633D01*
X813400Y421008D01*
X813358Y421425D01*
X813442Y421967D01*
X813567Y422258D01*
X813775Y422550D01*
X814067Y422758D01*
X814358Y422800D01*
X814650Y422717D01*
X814858Y422508D01*
G01X817250Y422800D02*
X816917Y422717D01*
X816667Y422508D01*
X816500Y422258D01*
X816375Y421925D01*
X816333Y421550D01*
X816375Y421175D01*
X816500Y420842D01*
X816667Y420592D01*
X816917Y420383D01*
X817250Y420300D01*
X817583Y420383D01*
X817833Y420592D01*
X818000Y420842D01*
X818125Y421175D01*
X818167Y421550D01*
X818125Y421925D01*
X818000Y422258D01*
X817833Y422508D01*
X817583Y422717D01*
X817250Y422800D01*
G01X807117Y428300D02*
Y430800D01*
X808158D01*
X808492Y430675D01*
X808700Y430508D01*
X808783Y430175D01*
X808700Y429842D01*
X808450Y429633D01*
X808158Y429508D01*
X807117D01*
G01X808158D02*
X808783Y428300D01*
G01X810258Y429342D02*
X810550Y429633D01*
X810800Y429800D01*
X811133Y429883D01*
X811425Y429800D01*
X811633Y429633D01*
X811800Y429383D01*
X811842Y429092D01*
X811800Y428842D01*
X811633Y428592D01*
X811383Y428383D01*
X811092Y428300D01*
X810758Y428383D01*
X810467Y428633D01*
X810300Y429008D01*
X810258Y429425D01*
X810342Y429967D01*
X810467Y430258D01*
X810675Y430550D01*
X810967Y430758D01*
X811258Y430800D01*
X811550Y430717D01*
X811758Y430508D01*
G01X813233Y428675D02*
X813483Y428467D01*
X813775Y428342D01*
X814150Y428300D01*
X814525Y428383D01*
X814817Y428550D01*
X815025Y428842D01*
X815067Y429175D01*
X814983Y429508D01*
X814775Y429717D01*
X814483Y429883D01*
X814192Y429925D01*
X813900Y429883D01*
X813525Y429717D01*
X813650Y430800D01*
X814775D01*
G01X817167Y428300D02*
X817250Y428842D01*
X817375Y429300D01*
X817542Y429717D01*
X817750Y430175D01*
X818083Y430800D01*
X816417D01*
G01X807617Y436800D02*
Y439300D01*
X808658D01*
X808992Y439175D01*
X809200Y439008D01*
X809283Y438675D01*
X809200Y438342D01*
X808950Y438133D01*
X808658Y438008D01*
X807617D01*
G01X808658D02*
X809283Y436800D01*
G01X810758Y437842D02*
X811050Y438133D01*
X811300Y438300D01*
X811633Y438383D01*
X811925Y438300D01*
X812133Y438133D01*
X812300Y437883D01*
X812342Y437592D01*
X812300Y437342D01*
X812133Y437092D01*
X811883Y436883D01*
X811592Y436800D01*
X811258Y436883D01*
X810967Y437133D01*
X810800Y437508D01*
X810758Y437925D01*
X810842Y438467D01*
X810967Y438758D01*
X811175Y439050D01*
X811467Y439258D01*
X811758Y439300D01*
X812050Y439217D01*
X812258Y439008D01*
G01X813733Y437175D02*
X813983Y436967D01*
X814275Y436842D01*
X814650Y436800D01*
X815025Y436883D01*
X815317Y437050D01*
X815525Y437342D01*
X815567Y437675D01*
X815483Y438008D01*
X815275Y438217D01*
X814983Y438383D01*
X814692Y438425D01*
X814400Y438383D01*
X814025Y438217D01*
X814150Y439300D01*
X815275D01*
G01X818250Y436800D02*
Y439300D01*
X816708Y437508D01*
X818792D01*
G01X838760Y741956D02*
X836260D01*
Y742997D01*
X836385Y743331D01*
X836552Y743539D01*
X836885Y743622D01*
X837218Y743539D01*
X837427Y743289D01*
X837552Y742997D01*
Y741956D01*
G01Y742997D02*
X838760Y743622D01*
G01Y745806D02*
X838218Y745889D01*
X837760Y746014D01*
X837343Y746181D01*
X836885Y746389D01*
X836260Y746722D01*
Y745056D01*
G01X838468Y748281D02*
X838677Y748572D01*
X838760Y748906D01*
X838677Y749239D01*
X838427Y749531D01*
X838052Y749739D01*
X837677Y749822D01*
X837218D01*
X836843Y749739D01*
X836510Y749531D01*
X836343Y749281D01*
X836260Y748989D01*
X836343Y748656D01*
X836510Y748406D01*
X836760Y748239D01*
X837093Y748156D01*
X837385Y748239D01*
X837677Y748447D01*
X837843Y748697D01*
X837885Y748989D01*
X837802Y749322D01*
X837593Y749572D01*
X837218Y749822D01*
G01X837718Y751297D02*
X837427Y751589D01*
X837260Y751839D01*
X837177Y752172D01*
X837260Y752464D01*
X837427Y752672D01*
X837677Y752839D01*
X837968Y752881D01*
X838218Y752839D01*
X838468Y752672D01*
X838677Y752422D01*
X838760Y752131D01*
X838677Y751797D01*
X838427Y751506D01*
X838052Y751339D01*
X837635Y751297D01*
X837093Y751381D01*
X836802Y751506D01*
X836510Y751714D01*
X836302Y752006D01*
X836260Y752297D01*
X836343Y752589D01*
X836552Y752797D01*
G01X838385Y754272D02*
X838593Y754522D01*
X838718Y754814D01*
X838760Y755189D01*
X838677Y755564D01*
X838510Y755856D01*
X838218Y756064D01*
X837885Y756106D01*
X837552Y756022D01*
X837343Y755814D01*
X837177Y755522D01*
X837135Y755231D01*
X837177Y754939D01*
X837343Y754564D01*
X836260Y754689D01*
Y755814D01*
G01X827065Y741741D02*
X824565D01*
Y742782D01*
X824690Y743116D01*
X824857Y743324D01*
X825190Y743407D01*
X825523Y743324D01*
X825732Y743074D01*
X825857Y742782D01*
Y741741D01*
G01Y742782D02*
X827065Y743407D01*
G01Y745591D02*
X826523Y745674D01*
X826065Y745799D01*
X825648Y745966D01*
X825190Y746174D01*
X824565Y746507D01*
Y744841D01*
G01X826773Y748066D02*
X826982Y748357D01*
X827065Y748691D01*
X826982Y749024D01*
X826732Y749316D01*
X826357Y749524D01*
X825982Y749607D01*
X825523D01*
X825148Y749524D01*
X824815Y749316D01*
X824648Y749066D01*
X824565Y748774D01*
X824648Y748441D01*
X824815Y748191D01*
X825065Y748024D01*
X825398Y747941D01*
X825690Y748024D01*
X825982Y748232D01*
X826148Y748482D01*
X826190Y748774D01*
X826107Y749107D01*
X825898Y749357D01*
X825523Y749607D01*
G01X826690Y750957D02*
X826898Y751207D01*
X827023Y751499D01*
X827065Y751874D01*
X826982Y752249D01*
X826815Y752541D01*
X826523Y752749D01*
X826190Y752791D01*
X825857Y752707D01*
X825648Y752499D01*
X825482Y752207D01*
X825440Y751916D01*
X825482Y751624D01*
X825648Y751249D01*
X824565Y751374D01*
Y752499D01*
G01Y754974D02*
X824648Y754641D01*
X824857Y754391D01*
X825107Y754224D01*
X825440Y754099D01*
X825815Y754057D01*
X826190Y754099D01*
X826523Y754224D01*
X826773Y754391D01*
X826982Y754641D01*
X827065Y754974D01*
X826982Y755307D01*
X826773Y755557D01*
X826523Y755724D01*
X826190Y755849D01*
X825815Y755891D01*
X825440Y755849D01*
X825107Y755724D01*
X824857Y755557D01*
X824648Y755307D01*
X824565Y754974D01*
G01X823046Y741863D02*
X820546D01*
Y742904D01*
X820671Y743238D01*
X820838Y743446D01*
X821171Y743529D01*
X821504Y743446D01*
X821713Y743196D01*
X821838Y742904D01*
Y741863D01*
G01Y742904D02*
X823046Y743529D01*
G01Y745713D02*
X822504Y745796D01*
X822046Y745921D01*
X821629Y746088D01*
X821171Y746296D01*
X820546Y746629D01*
Y744963D01*
G01X822754Y748188D02*
X822963Y748479D01*
X823046Y748813D01*
X822963Y749146D01*
X822713Y749438D01*
X822338Y749646D01*
X821963Y749729D01*
X821504D01*
X821129Y749646D01*
X820796Y749438D01*
X820629Y749188D01*
X820546Y748896D01*
X820629Y748563D01*
X820796Y748313D01*
X821046Y748146D01*
X821379Y748063D01*
X821671Y748146D01*
X821963Y748354D01*
X822129Y748604D01*
X822171Y748896D01*
X822088Y749229D01*
X821879Y749479D01*
X821504Y749729D01*
G01X820963Y751204D02*
X820713Y751454D01*
X820588Y751746D01*
X820546Y752079D01*
X820629Y752496D01*
X820838Y752788D01*
X821088Y752871D01*
X821338Y752829D01*
X821546Y752663D01*
X821963Y751829D01*
X822254Y751454D01*
X822671Y751204D01*
X823046Y751121D01*
Y752871D01*
G01X822546Y754179D02*
X822838Y754429D01*
X823004Y754763D01*
X823046Y755138D01*
X823004Y755471D01*
X822796Y755804D01*
X822546Y756013D01*
X822296Y756054D01*
X822004Y755971D01*
X821796Y755679D01*
X821713Y755388D01*
Y755013D01*
G01Y755388D02*
X821588Y755638D01*
X821379Y755846D01*
X821129Y755929D01*
X820879Y755846D01*
X820671Y755638D01*
X820546Y755263D01*
X820588Y754888D01*
X820754Y754513D01*
G01X814946Y742134D02*
X812446D01*
Y743175D01*
X812571Y743509D01*
X812738Y743717D01*
X813071Y743800D01*
X813404Y743717D01*
X813613Y743467D01*
X813738Y743175D01*
Y742134D01*
G01Y743175D02*
X814946Y743800D01*
G01X814571Y745150D02*
X814779Y745400D01*
X814904Y745692D01*
X814946Y746067D01*
X814863Y746442D01*
X814696Y746734D01*
X814404Y746942D01*
X814071Y746984D01*
X813738Y746900D01*
X813529Y746692D01*
X813363Y746400D01*
X813321Y746109D01*
X813363Y745817D01*
X813529Y745442D01*
X812446Y745567D01*
Y746692D01*
G01X814571Y748250D02*
X814779Y748500D01*
X814904Y748792D01*
X814946Y749167D01*
X814863Y749542D01*
X814696Y749834D01*
X814404Y750042D01*
X814071Y750084D01*
X813738Y750000D01*
X813529Y749792D01*
X813363Y749500D01*
X813321Y749209D01*
X813363Y748917D01*
X813529Y748542D01*
X812446Y748667D01*
Y749792D01*
G01X812863Y751475D02*
X812613Y751725D01*
X812488Y752017D01*
X812446Y752350D01*
X812529Y752767D01*
X812738Y753059D01*
X812988Y753142D01*
X813238Y753100D01*
X813446Y752934D01*
X813863Y752100D01*
X814154Y751725D01*
X814571Y751475D01*
X814946Y751392D01*
Y753142D01*
G01X819087Y742012D02*
X816587D01*
Y743053D01*
X816712Y743387D01*
X816879Y743595D01*
X817212Y743678D01*
X817545Y743595D01*
X817754Y743345D01*
X817879Y743053D01*
Y742012D01*
G01Y743053D02*
X819087Y743678D01*
G01X818712Y745028D02*
X818920Y745278D01*
X819045Y745570D01*
X819087Y745945D01*
X819004Y746320D01*
X818837Y746612D01*
X818545Y746820D01*
X818212Y746862D01*
X817879Y746778D01*
X817670Y746570D01*
X817504Y746278D01*
X817462Y745987D01*
X817504Y745695D01*
X817670Y745320D01*
X816587Y745445D01*
Y746570D01*
G01X818712Y748128D02*
X818920Y748378D01*
X819045Y748670D01*
X819087Y749045D01*
X819004Y749420D01*
X818837Y749712D01*
X818545Y749920D01*
X818212Y749962D01*
X817879Y749878D01*
X817670Y749670D01*
X817504Y749378D01*
X817462Y749087D01*
X817504Y748795D01*
X817670Y748420D01*
X816587Y748545D01*
Y749670D01*
G01Y752145D02*
X816670Y751812D01*
X816879Y751562D01*
X817129Y751395D01*
X817462Y751270D01*
X817837Y751228D01*
X818212Y751270D01*
X818545Y751395D01*
X818795Y751562D01*
X819004Y751812D01*
X819087Y752145D01*
X819004Y752478D01*
X818795Y752728D01*
X818545Y752895D01*
X818212Y753020D01*
X817837Y753062D01*
X817462Y753020D01*
X817129Y752895D01*
X816879Y752728D01*
X816670Y752478D01*
X816587Y752145D01*
G01X830997Y794650D02*
X828497D01*
Y795691D01*
X828622Y796025D01*
X828789Y796233D01*
X829122Y796316D01*
X829455Y796233D01*
X829664Y795983D01*
X829789Y795691D01*
Y794650D01*
G01Y795691D02*
X830997Y796316D01*
G01Y798500D02*
X830455Y798583D01*
X829997Y798708D01*
X829580Y798875D01*
X829122Y799083D01*
X828497Y799416D01*
Y797750D01*
G01X830705Y800975D02*
X830914Y801266D01*
X830997Y801600D01*
X830914Y801933D01*
X830664Y802225D01*
X830289Y802433D01*
X829914Y802516D01*
X829455D01*
X829080Y802433D01*
X828747Y802225D01*
X828580Y801975D01*
X828497Y801683D01*
X828580Y801350D01*
X828747Y801100D01*
X828997Y800933D01*
X829330Y800850D01*
X829622Y800933D01*
X829914Y801141D01*
X830080Y801391D01*
X830122Y801683D01*
X830039Y802016D01*
X829830Y802266D01*
X829455Y802516D01*
G01X830997Y804700D02*
X830455Y804783D01*
X829997Y804908D01*
X829580Y805075D01*
X829122Y805283D01*
X828497Y805616D01*
Y803950D01*
G01X830705Y807175D02*
X830914Y807466D01*
X830997Y807800D01*
X830914Y808133D01*
X830664Y808425D01*
X830289Y808633D01*
X829914Y808716D01*
X829455D01*
X829080Y808633D01*
X828747Y808425D01*
X828580Y808175D01*
X828497Y807883D01*
X828580Y807550D01*
X828747Y807300D01*
X828997Y807133D01*
X829330Y807050D01*
X829622Y807133D01*
X829914Y807341D01*
X830080Y807591D01*
X830122Y807883D01*
X830039Y808216D01*
X829830Y808466D01*
X829455Y808716D01*
G01X834773Y794590D02*
X832273D01*
Y795631D01*
X832398Y795965D01*
X832565Y796173D01*
X832898Y796256D01*
X833231Y796173D01*
X833440Y795923D01*
X833565Y795631D01*
Y794590D01*
G01Y795631D02*
X834773Y796256D01*
G01Y798440D02*
X834231Y798523D01*
X833773Y798648D01*
X833356Y798815D01*
X832898Y799023D01*
X832273Y799356D01*
Y797690D01*
G01X834481Y800915D02*
X834690Y801206D01*
X834773Y801540D01*
X834690Y801873D01*
X834440Y802165D01*
X834065Y802373D01*
X833690Y802456D01*
X833231D01*
X832856Y802373D01*
X832523Y802165D01*
X832356Y801915D01*
X832273Y801623D01*
X832356Y801290D01*
X832523Y801040D01*
X832773Y800873D01*
X833106Y800790D01*
X833398Y800873D01*
X833690Y801081D01*
X833856Y801331D01*
X833898Y801623D01*
X833815Y801956D01*
X833606Y802206D01*
X833231Y802456D01*
G01X833731Y803931D02*
X833440Y804223D01*
X833273Y804473D01*
X833190Y804806D01*
X833273Y805098D01*
X833440Y805306D01*
X833690Y805473D01*
X833981Y805515D01*
X834231Y805473D01*
X834481Y805306D01*
X834690Y805056D01*
X834773Y804765D01*
X834690Y804431D01*
X834440Y804140D01*
X834065Y803973D01*
X833648Y803931D01*
X833106Y804015D01*
X832815Y804140D01*
X832523Y804348D01*
X832315Y804640D01*
X832273Y804931D01*
X832356Y805223D01*
X832565Y805431D01*
G01X834773Y808323D02*
X832273D01*
X834065Y806781D01*
Y808865D01*
G01X838813Y797239D02*
X836313D01*
Y798280D01*
X836438Y798614D01*
X836605Y798822D01*
X836938Y798905D01*
X837271Y798822D01*
X837480Y798572D01*
X837605Y798280D01*
Y797239D01*
G01Y798280D02*
X838813Y798905D01*
G01Y801089D02*
X838271Y801172D01*
X837813Y801297D01*
X837396Y801464D01*
X836938Y801672D01*
X836313Y802005D01*
Y800339D01*
G01X838521Y803564D02*
X838730Y803855D01*
X838813Y804189D01*
X838730Y804522D01*
X838480Y804814D01*
X838105Y805022D01*
X837730Y805105D01*
X837271D01*
X836896Y805022D01*
X836563Y804814D01*
X836396Y804564D01*
X836313Y804272D01*
X836396Y803939D01*
X836563Y803689D01*
X836813Y803522D01*
X837146Y803439D01*
X837438Y803522D01*
X837730Y803730D01*
X837896Y803980D01*
X837938Y804272D01*
X837855Y804605D01*
X837646Y804855D01*
X837271Y805105D01*
G01X838813Y807872D02*
X836313D01*
X838105Y806330D01*
Y808414D01*
G01X838521Y809764D02*
X838730Y810055D01*
X838813Y810389D01*
X838730Y810722D01*
X838480Y811014D01*
X838105Y811222D01*
X837730Y811305D01*
X837271D01*
X836896Y811222D01*
X836563Y811014D01*
X836396Y810764D01*
X836313Y810472D01*
X836396Y810139D01*
X836563Y809889D01*
X836813Y809722D01*
X837146Y809639D01*
X837438Y809722D01*
X837730Y809930D01*
X837896Y810180D01*
X837938Y810472D01*
X837855Y810805D01*
X837646Y811055D01*
X837271Y811305D01*
G01X823536Y794620D02*
X821036D01*
Y795661D01*
X821161Y795995D01*
X821328Y796203D01*
X821661Y796286D01*
X821994Y796203D01*
X822203Y795953D01*
X822328Y795661D01*
Y794620D01*
G01Y795661D02*
X823536Y796286D01*
G01Y798470D02*
X822994Y798553D01*
X822536Y798678D01*
X822119Y798845D01*
X821661Y799053D01*
X821036Y799386D01*
Y797720D01*
G01X823244Y800945D02*
X823453Y801236D01*
X823536Y801570D01*
X823453Y801903D01*
X823203Y802195D01*
X822828Y802403D01*
X822453Y802486D01*
X821994D01*
X821619Y802403D01*
X821286Y802195D01*
X821119Y801945D01*
X821036Y801653D01*
X821119Y801320D01*
X821286Y801070D01*
X821536Y800903D01*
X821869Y800820D01*
X822161Y800903D01*
X822453Y801111D01*
X822619Y801361D01*
X822661Y801653D01*
X822578Y801986D01*
X822369Y802236D01*
X821994Y802486D01*
G01X823536Y804753D02*
X821036D01*
X821536Y804253D01*
G01X823536D02*
Y805253D01*
G01X823244Y807145D02*
X823453Y807436D01*
X823536Y807770D01*
X823453Y808103D01*
X823203Y808395D01*
X822828Y808603D01*
X822453Y808686D01*
X821994D01*
X821619Y808603D01*
X821286Y808395D01*
X821119Y808145D01*
X821036Y807853D01*
X821119Y807520D01*
X821286Y807270D01*
X821536Y807103D01*
X821869Y807020D01*
X822161Y807103D01*
X822453Y807311D01*
X822619Y807561D01*
X822661Y807853D01*
X822578Y808186D01*
X822369Y808436D01*
X821994Y808686D01*
G01X819455Y794711D02*
X816955D01*
Y795752D01*
X817080Y796086D01*
X817247Y796294D01*
X817580Y796377D01*
X817913Y796294D01*
X818122Y796044D01*
X818247Y795752D01*
Y794711D01*
G01Y795752D02*
X819455Y796377D01*
G01Y798561D02*
X818913Y798644D01*
X818455Y798769D01*
X818038Y798936D01*
X817580Y799144D01*
X816955Y799477D01*
Y797811D01*
G01X819163Y801036D02*
X819372Y801327D01*
X819455Y801661D01*
X819372Y801994D01*
X819122Y802286D01*
X818747Y802494D01*
X818372Y802577D01*
X817913D01*
X817538Y802494D01*
X817205Y802286D01*
X817038Y802036D01*
X816955Y801744D01*
X817038Y801411D01*
X817205Y801161D01*
X817455Y800994D01*
X817788Y800911D01*
X818080Y800994D01*
X818372Y801202D01*
X818538Y801452D01*
X818580Y801744D01*
X818497Y802077D01*
X818288Y802327D01*
X817913Y802577D01*
G01X819455Y804844D02*
X816955D01*
X817455Y804344D01*
G01X819455D02*
Y805344D01*
G01Y807944D02*
X819413Y808236D01*
X819288Y808569D01*
X819080Y808777D01*
X818788Y808861D01*
X818497Y808777D01*
X818247Y808527D01*
X818122Y808152D01*
Y807736D01*
X818038Y807486D01*
X817830Y807277D01*
X817538Y807194D01*
X817247Y807319D01*
X817038Y807611D01*
X816955Y807944D01*
X817038Y808277D01*
X817247Y808569D01*
X817538Y808694D01*
X817830Y808611D01*
X818038Y808402D01*
X818122Y808152D01*
Y807736D01*
X818247Y807361D01*
X818497Y807111D01*
X818788Y807027D01*
X819080Y807111D01*
X819288Y807319D01*
X819413Y807652D01*
X819455Y807944D01*
G01X827435Y794831D02*
X824935D01*
Y795872D01*
X825060Y796206D01*
X825227Y796414D01*
X825560Y796497D01*
X825893Y796414D01*
X826102Y796164D01*
X826227Y795872D01*
Y794831D01*
G01Y795872D02*
X827435Y796497D01*
G01X827060Y797847D02*
X827268Y798097D01*
X827393Y798389D01*
X827435Y798764D01*
X827352Y799139D01*
X827185Y799431D01*
X826893Y799639D01*
X826560Y799681D01*
X826227Y799597D01*
X826018Y799389D01*
X825852Y799097D01*
X825810Y798806D01*
X825852Y798514D01*
X826018Y798139D01*
X824935Y798264D01*
Y799389D01*
G01X827060Y800947D02*
X827268Y801197D01*
X827393Y801489D01*
X827435Y801864D01*
X827352Y802239D01*
X827185Y802531D01*
X826893Y802739D01*
X826560Y802781D01*
X826227Y802697D01*
X826018Y802489D01*
X825852Y802197D01*
X825810Y801906D01*
X825852Y801614D01*
X826018Y801239D01*
X824935Y801364D01*
Y802489D01*
G01X827435Y804881D02*
X826893Y804964D01*
X826435Y805089D01*
X826018Y805256D01*
X825560Y805464D01*
X824935Y805797D01*
Y804131D01*
G01X813037Y796494D02*
X812912Y796244D01*
X812829Y795952D01*
Y795619D01*
X812954Y795244D01*
X813162Y794952D01*
X813412Y794744D01*
X813829Y794577D01*
X814204Y794535D01*
X814579Y794619D01*
X814829Y794744D01*
X815079Y794994D01*
X815246Y795285D01*
X815329Y795577D01*
Y795869D01*
X815246Y796160D01*
X815121Y796410D01*
X814954Y796619D01*
G01X814829Y797760D02*
X815121Y798010D01*
X815287Y798344D01*
X815329Y798719D01*
X815287Y799052D01*
X815079Y799385D01*
X814829Y799594D01*
X814579Y799635D01*
X814287Y799552D01*
X814079Y799260D01*
X813996Y798969D01*
Y798594D01*
G01Y798969D02*
X813871Y799219D01*
X813662Y799427D01*
X813412Y799510D01*
X813162Y799427D01*
X812954Y799219D01*
X812829Y798844D01*
X812871Y798469D01*
X813037Y798094D01*
G01X813246Y800985D02*
X812996Y801235D01*
X812871Y801527D01*
X812829Y801860D01*
X812912Y802277D01*
X813121Y802569D01*
X813371Y802652D01*
X813621Y802610D01*
X813829Y802444D01*
X814246Y801610D01*
X814537Y801235D01*
X814954Y800985D01*
X815329Y800902D01*
Y802652D01*
G01Y804877D02*
X812829D01*
X813329Y804377D01*
G01X815329D02*
Y805377D01*
G01X814954Y807060D02*
X815162Y807310D01*
X815287Y807602D01*
X815329Y807977D01*
X815246Y808352D01*
X815079Y808644D01*
X814787Y808852D01*
X814454Y808894D01*
X814121Y808810D01*
X813912Y808602D01*
X813746Y808310D01*
X813704Y808019D01*
X813746Y807727D01*
X813912Y807352D01*
X812829Y807477D01*
Y808602D01*
G01X811668Y816633D02*
X811543Y816383D01*
X811460Y816091D01*
Y815758D01*
X811585Y815383D01*
X811793Y815091D01*
X812043Y814883D01*
X812460Y814716D01*
X812835Y814674D01*
X813210Y814758D01*
X813460Y814883D01*
X813710Y815133D01*
X813877Y815424D01*
X813960Y815716D01*
Y816008D01*
X813877Y816299D01*
X813752Y816549D01*
X813585Y816758D01*
G01X813960Y818816D02*
X811460D01*
X811960Y818316D01*
G01X813960D02*
Y819316D01*
G01Y821916D02*
X811460D01*
X811960Y821416D01*
G01X813960D02*
Y822416D01*
G01X813460Y824099D02*
X813752Y824349D01*
X813918Y824683D01*
X813960Y825058D01*
X813918Y825391D01*
X813710Y825724D01*
X813460Y825933D01*
X813210Y825974D01*
X812918Y825891D01*
X812710Y825599D01*
X812627Y825308D01*
Y824933D01*
G01Y825308D02*
X812502Y825558D01*
X812293Y825766D01*
X812043Y825849D01*
X811793Y825766D01*
X811585Y825558D01*
X811460Y825183D01*
X811502Y824808D01*
X811668Y824433D01*
G01X815668Y816633D02*
X815543Y816383D01*
X815460Y816091D01*
Y815758D01*
X815585Y815383D01*
X815793Y815091D01*
X816043Y814883D01*
X816460Y814716D01*
X816835Y814674D01*
X817210Y814758D01*
X817460Y814883D01*
X817710Y815133D01*
X817877Y815424D01*
X817960Y815716D01*
Y816008D01*
X817877Y816299D01*
X817752Y816549D01*
X817585Y816758D01*
G01X817960Y818816D02*
X815460D01*
X815960Y818316D01*
G01X817960D02*
Y819316D01*
G01Y821916D02*
X815460D01*
X815960Y821416D01*
G01X817960D02*
Y822416D01*
G01X815877Y824224D02*
X815627Y824474D01*
X815502Y824766D01*
X815460Y825099D01*
X815543Y825516D01*
X815752Y825808D01*
X816002Y825891D01*
X816252Y825849D01*
X816460Y825683D01*
X816877Y824849D01*
X817168Y824474D01*
X817585Y824224D01*
X817960Y824141D01*
Y825891D01*
G01X836665Y816968D02*
X836540Y816718D01*
X836457Y816426D01*
Y816093D01*
X836582Y815718D01*
X836790Y815426D01*
X837040Y815218D01*
X837457Y815051D01*
X837832Y815009D01*
X838207Y815093D01*
X838457Y815218D01*
X838707Y815468D01*
X838874Y815759D01*
X838957Y816051D01*
Y816343D01*
X838874Y816634D01*
X838749Y816884D01*
X838582Y817093D01*
G01X838957Y819151D02*
X836457D01*
X836957Y818651D01*
G01X838957D02*
Y819651D01*
G01Y822251D02*
X836457D01*
X836957Y821751D01*
G01X838957D02*
Y822751D01*
G01Y825351D02*
X836457D01*
X836957Y824851D01*
G01X838957D02*
Y825851D01*
G01X842000Y8500D02*
Y-4500D01*
G01X860300Y10000D02*
Y6000D01*
X867700D01*
G01X858500Y5900D02*
Y1900D01*
X865900D01*
G01X851581Y3499D02*
Y7499D01*
X844181D01*
G01X843534Y785D02*
X854334D01*
Y-4415D01*
X843534D01*
Y785D01*
G01X871500Y28000D02*
X885000D01*
G01X850352Y40500D02*
X851802Y41950D01*
G01Y39050D02*
X850352Y40500D01*
G01X851802Y35000D02*
Y46000D01*
G01X848300Y12300D02*
X852300D01*
Y19700D01*
G01X856400D02*
X852400D01*
Y12300D01*
G01X848252Y19700D02*
X844252D01*
Y12300D01*
G01Y19700D02*
X840252D01*
Y12300D01*
G01X859800Y30000D02*
Y26000D01*
X867200D01*
G01X859800Y38000D02*
Y34000D01*
X867200D01*
G01Y30000D02*
Y34000D01*
X859800D01*
G01X867200Y38000D02*
Y42000D01*
X859800D01*
G01X865500Y18300D02*
X869500D01*
Y25700D01*
G01X865500Y10800D02*
X869500D01*
Y18200D01*
G01X884000Y25000D02*
X870000D01*
G01Y12000D02*
X884000D01*
G01X870000Y25000D02*
Y12000D01*
G01X872385Y62728D02*
X869885D01*
Y63769D01*
X870010Y64103D01*
X870177Y64311D01*
X870510Y64394D01*
X870843Y64311D01*
X871052Y64061D01*
X871177Y63769D01*
Y62728D01*
G01Y63769D02*
X872385Y64394D01*
G01Y66578D02*
X871843Y66661D01*
X871385Y66786D01*
X870968Y66953D01*
X870510Y67161D01*
X869885Y67494D01*
Y65828D01*
G01X872093Y69053D02*
X872302Y69344D01*
X872385Y69678D01*
X872302Y70011D01*
X872052Y70303D01*
X871677Y70511D01*
X871302Y70594D01*
X870843D01*
X870468Y70511D01*
X870135Y70303D01*
X869968Y70053D01*
X869885Y69761D01*
X869968Y69428D01*
X870135Y69178D01*
X870385Y69011D01*
X870718Y68928D01*
X871010Y69011D01*
X871302Y69219D01*
X871468Y69469D01*
X871510Y69761D01*
X871427Y70094D01*
X871218Y70344D01*
X870843Y70594D01*
G01X872385Y72861D02*
X869885D01*
X870385Y72361D01*
G01X872385D02*
Y73361D01*
G01X869885Y75961D02*
X869968Y75628D01*
X870177Y75378D01*
X870427Y75211D01*
X870760Y75086D01*
X871135Y75044D01*
X871510Y75086D01*
X871843Y75211D01*
X872093Y75378D01*
X872302Y75628D01*
X872385Y75961D01*
X872302Y76294D01*
X872093Y76544D01*
X871843Y76711D01*
X871510Y76836D01*
X871135Y76878D01*
X870760Y76836D01*
X870427Y76711D01*
X870177Y76544D01*
X869968Y76294D01*
X869885Y75961D01*
G01X869300Y54800D02*
Y50800D01*
X876700D01*
G01X867700D02*
Y54800D01*
X860300D01*
G01X860133Y46034D02*
Y42034D01*
X867533D01*
G01X867700Y46500D02*
Y50500D01*
X860300D01*
G01X873000Y87800D02*
X877000D01*
Y95200D01*
G01X840917Y79000D02*
Y81500D01*
X841958D01*
X842292Y81375D01*
X842500Y81208D01*
X842583Y80875D01*
X842500Y80542D01*
X842250Y80333D01*
X841958Y80208D01*
X840917D01*
G01X841958D02*
X842583Y79000D01*
G01X844767D02*
X844850Y79542D01*
X844975Y80000D01*
X845142Y80417D01*
X845350Y80875D01*
X845683Y81500D01*
X844017D01*
G01X847950D02*
X847617Y81417D01*
X847367Y81208D01*
X847200Y80958D01*
X847075Y80625D01*
X847033Y80250D01*
X847075Y79875D01*
X847200Y79542D01*
X847367Y79292D01*
X847617Y79083D01*
X847950Y79000D01*
X848283Y79083D01*
X848533Y79292D01*
X848700Y79542D01*
X848825Y79875D01*
X848867Y80250D01*
X848825Y80625D01*
X848700Y80958D01*
X848533Y81208D01*
X848283Y81417D01*
X847950Y81500D01*
G01X850258Y81083D02*
X850508Y81333D01*
X850800Y81458D01*
X851133Y81500D01*
X851550Y81417D01*
X851842Y81208D01*
X851925Y80958D01*
X851883Y80708D01*
X851717Y80500D01*
X850883Y80083D01*
X850508Y79792D01*
X850258Y79375D01*
X850175Y79000D01*
X851925D01*
G01X873425Y125865D02*
Y252087D01*
G01Y117007D02*
Y122165D01*
G01X875275Y115157D02*
G02I-1850J0D01*
G01X874475Y124015D02*
G02I-1450J0D01*
G01X860310Y126908D02*
X862810D01*
G01X860310Y125950D02*
Y127866D01*
G01X862810Y129175D02*
X860310D01*
Y130175D01*
X860435Y130508D01*
X860727Y130758D01*
X861060Y130841D01*
X861393Y130758D01*
X861643Y130550D01*
X861768Y130175D01*
Y129175D01*
G01X860727Y132316D02*
X860477Y132566D01*
X860352Y132858D01*
X860310Y133191D01*
X860393Y133608D01*
X860602Y133900D01*
X860852Y133983D01*
X861102Y133941D01*
X861310Y133775D01*
X861727Y132941D01*
X862018Y132566D01*
X862435Y132316D01*
X862810Y132233D01*
Y133983D01*
G01X861768Y135416D02*
X861477Y135708D01*
X861310Y135958D01*
X861227Y136291D01*
X861310Y136583D01*
X861477Y136791D01*
X861727Y136958D01*
X862018Y137000D01*
X862268Y136958D01*
X862518Y136791D01*
X862727Y136541D01*
X862810Y136250D01*
X862727Y135916D01*
X862477Y135625D01*
X862102Y135458D01*
X861685Y135416D01*
X861143Y135500D01*
X860852Y135625D01*
X860560Y135833D01*
X860352Y136125D01*
X860310Y136416D01*
X860393Y136708D01*
X860602Y136916D01*
G01X862810Y139225D02*
X862268Y139308D01*
X861810Y139433D01*
X861393Y139600D01*
X860935Y139808D01*
X860310Y140141D01*
Y138475D01*
G01X845730Y127428D02*
X848230D01*
G01X845730Y126470D02*
Y128386D01*
G01X848230Y129695D02*
X845730D01*
Y130695D01*
X845855Y131028D01*
X846147Y131278D01*
X846480Y131361D01*
X846813Y131278D01*
X847063Y131070D01*
X847188Y130695D01*
Y129695D01*
G01X846147Y132836D02*
X845897Y133086D01*
X845772Y133378D01*
X845730Y133711D01*
X845813Y134128D01*
X846022Y134420D01*
X846272Y134503D01*
X846522Y134461D01*
X846730Y134295D01*
X847147Y133461D01*
X847438Y133086D01*
X847855Y132836D01*
X848230Y132753D01*
Y134503D01*
G01Y136645D02*
X847688Y136728D01*
X847230Y136853D01*
X846813Y137020D01*
X846355Y137228D01*
X845730Y137561D01*
Y135895D01*
G01X848230Y139745D02*
X847688Y139828D01*
X847230Y139953D01*
X846813Y140120D01*
X846355Y140328D01*
X845730Y140661D01*
Y138995D01*
G01X853510Y126940D02*
X856010D01*
G01X853510Y125982D02*
Y127898D01*
G01X856010Y129207D02*
X853510D01*
Y130207D01*
X853635Y130540D01*
X853927Y130790D01*
X854260Y130873D01*
X854593Y130790D01*
X854843Y130582D01*
X854968Y130207D01*
Y129207D01*
G01X855510Y132223D02*
X855802Y132473D01*
X855968Y132807D01*
X856010Y133182D01*
X855968Y133515D01*
X855760Y133848D01*
X855510Y134057D01*
X855260Y134098D01*
X854968Y134015D01*
X854760Y133723D01*
X854677Y133432D01*
Y133057D01*
G01Y133432D02*
X854552Y133682D01*
X854343Y133890D01*
X854093Y133973D01*
X853843Y133890D01*
X853635Y133682D01*
X853510Y133307D01*
X853552Y132932D01*
X853718Y132557D01*
G01X856010Y136240D02*
X853510D01*
X854010Y135740D01*
G01X856010D02*
Y136740D01*
G01Y139340D02*
X853510D01*
X854010Y138840D01*
G01X856010D02*
Y139840D01*
G01X843312Y110790D02*
X840812D01*
Y111831D01*
X840937Y112165D01*
X841104Y112373D01*
X841437Y112456D01*
X841770Y112373D01*
X841979Y112123D01*
X842104Y111831D01*
Y110790D01*
G01Y111831D02*
X843312Y112456D01*
G01Y114640D02*
X842770Y114723D01*
X842312Y114848D01*
X841895Y115015D01*
X841437Y115223D01*
X840812Y115556D01*
Y113890D01*
G01X843312Y118323D02*
X840812D01*
X842604Y116781D01*
Y118865D01*
G01X843020Y120215D02*
X843229Y120506D01*
X843312Y120840D01*
X843229Y121173D01*
X842979Y121465D01*
X842604Y121673D01*
X842229Y121756D01*
X841770D01*
X841395Y121673D01*
X841062Y121465D01*
X840895Y121215D01*
X840812Y120923D01*
X840895Y120590D01*
X841062Y120340D01*
X841312Y120173D01*
X841645Y120090D01*
X841937Y120173D01*
X842229Y120381D01*
X842395Y120631D01*
X842437Y120923D01*
X842354Y121256D01*
X842145Y121506D01*
X841770Y121756D01*
G01X873425Y260945D02*
Y255787D01*
G01X875275Y262795D02*
G02I-1850J0D01*
G01X874475Y253937D02*
G02I-1450J0D01*
G01X844100Y395367D02*
X841600D01*
Y396408D01*
X841725Y396742D01*
X841892Y396950D01*
X842225Y397033D01*
X842558Y396950D01*
X842767Y396700D01*
X842892Y396408D01*
Y395367D01*
G01Y396408D02*
X844100Y397033D01*
G01Y399300D02*
X844058Y399592D01*
X843933Y399925D01*
X843725Y400133D01*
X843433Y400217D01*
X843142Y400133D01*
X842892Y399883D01*
X842767Y399508D01*
Y399092D01*
X842683Y398842D01*
X842475Y398633D01*
X842183Y398550D01*
X841892Y398675D01*
X841683Y398967D01*
X841600Y399300D01*
X841683Y399633D01*
X841892Y399925D01*
X842183Y400050D01*
X842475Y399967D01*
X842683Y399758D01*
X842767Y399508D01*
Y399092D01*
X842892Y398717D01*
X843142Y398467D01*
X843433Y398383D01*
X843725Y398467D01*
X843933Y398675D01*
X844058Y399008D01*
X844100Y399300D01*
G01X843725Y401483D02*
X843933Y401733D01*
X844058Y402025D01*
X844100Y402400D01*
X844017Y402775D01*
X843850Y403067D01*
X843558Y403275D01*
X843225Y403317D01*
X842892Y403233D01*
X842683Y403025D01*
X842517Y402733D01*
X842475Y402442D01*
X842517Y402150D01*
X842683Y401775D01*
X841600Y401900D01*
Y403025D01*
G01X842142Y386667D02*
X842017Y386417D01*
X841934Y386125D01*
Y385792D01*
X842059Y385417D01*
X842267Y385125D01*
X842517Y384917D01*
X842934Y384750D01*
X843309Y384708D01*
X843684Y384792D01*
X843934Y384917D01*
X844184Y385167D01*
X844351Y385458D01*
X844434Y385750D01*
Y386042D01*
X844351Y386333D01*
X844226Y386583D01*
X844059Y386792D01*
G01X844434Y389350D02*
X841934D01*
X843726Y387808D01*
Y389892D01*
G01X860643Y735778D02*
X860393Y735903D01*
X860101Y735986D01*
X859768D01*
X859393Y735861D01*
X859101Y735653D01*
X858893Y735403D01*
X858726Y734986D01*
X858684Y734611D01*
X858768Y734236D01*
X858893Y733986D01*
X859143Y733736D01*
X859434Y733569D01*
X859726Y733486D01*
X860018D01*
X860309Y733569D01*
X860559Y733694D01*
X860768Y733861D01*
G01X863326Y733486D02*
Y735986D01*
X861784Y734194D01*
X863868D01*
G01X865926Y733486D02*
Y735986D01*
X865426Y735486D01*
G01Y733486D02*
X866426D01*
G01X868234Y735569D02*
X868484Y735819D01*
X868776Y735944D01*
X869109Y735986D01*
X869526Y735903D01*
X869818Y735694D01*
X869901Y735444D01*
X869859Y735194D01*
X869693Y734986D01*
X868859Y734569D01*
X868484Y734278D01*
X868234Y733861D01*
X868151Y733486D01*
X869901D01*
G01X872126Y735986D02*
X871793Y735903D01*
X871543Y735694D01*
X871376Y735444D01*
X871251Y735111D01*
X871209Y734736D01*
X871251Y734361D01*
X871376Y734028D01*
X871543Y733778D01*
X871793Y733569D01*
X872126Y733486D01*
X872459Y733569D01*
X872709Y733778D01*
X872876Y734028D01*
X873001Y734361D01*
X873043Y734736D01*
X873001Y735111D01*
X872876Y735444D01*
X872709Y735694D01*
X872459Y735903D01*
X872126Y735986D01*
G01X842961Y742152D02*
X840461D01*
Y743193D01*
X840586Y743527D01*
X840753Y743735D01*
X841086Y743818D01*
X841419Y743735D01*
X841628Y743485D01*
X841753Y743193D01*
Y742152D01*
G01Y743193D02*
X842961Y743818D01*
G01Y746002D02*
X842419Y746085D01*
X841961Y746210D01*
X841544Y746377D01*
X841086Y746585D01*
X840461Y746918D01*
Y745252D01*
G01X842669Y748477D02*
X842878Y748768D01*
X842961Y749102D01*
X842878Y749435D01*
X842628Y749727D01*
X842253Y749935D01*
X841878Y750018D01*
X841419D01*
X841044Y749935D01*
X840711Y749727D01*
X840544Y749477D01*
X840461Y749185D01*
X840544Y748852D01*
X840711Y748602D01*
X840961Y748435D01*
X841294Y748352D01*
X841586Y748435D01*
X841878Y748643D01*
X842044Y748893D01*
X842086Y749185D01*
X842003Y749518D01*
X841794Y749768D01*
X841419Y750018D01*
G01X842961Y752285D02*
X842919Y752577D01*
X842794Y752910D01*
X842586Y753118D01*
X842294Y753202D01*
X842003Y753118D01*
X841753Y752868D01*
X841628Y752493D01*
Y752077D01*
X841544Y751827D01*
X841336Y751618D01*
X841044Y751535D01*
X840753Y751660D01*
X840544Y751952D01*
X840461Y752285D01*
X840544Y752618D01*
X840753Y752910D01*
X841044Y753035D01*
X841336Y752952D01*
X841544Y752743D01*
X841628Y752493D01*
Y752077D01*
X841753Y751702D01*
X842003Y751452D01*
X842294Y751368D01*
X842586Y751452D01*
X842794Y751660D01*
X842919Y751993D01*
X842961Y752285D01*
G01X840461Y755385D02*
X840544Y755052D01*
X840753Y754802D01*
X841003Y754635D01*
X841336Y754510D01*
X841711Y754468D01*
X842086Y754510D01*
X842419Y754635D01*
X842669Y754802D01*
X842878Y755052D01*
X842961Y755385D01*
X842878Y755718D01*
X842669Y755968D01*
X842419Y756135D01*
X842086Y756260D01*
X841711Y756302D01*
X841336Y756260D01*
X841003Y756135D01*
X840753Y755968D01*
X840544Y755718D01*
X840461Y755385D01*
G01X875406Y754024D02*
X871406D01*
Y746624D01*
G01Y754098D02*
X867406D01*
Y746698D01*
G01X851792Y741848D02*
X849292D01*
Y742889D01*
X849417Y743223D01*
X849584Y743431D01*
X849917Y743514D01*
X850250Y743431D01*
X850459Y743181D01*
X850584Y742889D01*
Y741848D01*
G01Y742889D02*
X851792Y743514D01*
G01Y745698D02*
X851250Y745781D01*
X850792Y745906D01*
X850375Y746073D01*
X849917Y746281D01*
X849292Y746614D01*
Y744948D01*
G01X851500Y748173D02*
X851709Y748464D01*
X851792Y748798D01*
X851709Y749131D01*
X851459Y749423D01*
X851084Y749631D01*
X850709Y749714D01*
X850250D01*
X849875Y749631D01*
X849542Y749423D01*
X849375Y749173D01*
X849292Y748881D01*
X849375Y748548D01*
X849542Y748298D01*
X849792Y748131D01*
X850125Y748048D01*
X850417Y748131D01*
X850709Y748339D01*
X850875Y748589D01*
X850917Y748881D01*
X850834Y749214D01*
X850625Y749464D01*
X850250Y749714D01*
G01X851792Y752481D02*
X849292D01*
X851084Y750939D01*
Y753023D01*
G01X849709Y754289D02*
X849459Y754539D01*
X849334Y754831D01*
X849292Y755164D01*
X849375Y755581D01*
X849584Y755873D01*
X849834Y755956D01*
X850084Y755914D01*
X850292Y755748D01*
X850709Y754914D01*
X851000Y754539D01*
X851417Y754289D01*
X851792Y754206D01*
Y755956D01*
G01X847408Y742091D02*
X844908D01*
Y743132D01*
X845033Y743466D01*
X845200Y743674D01*
X845533Y743757D01*
X845866Y743674D01*
X846075Y743424D01*
X846200Y743132D01*
Y742091D01*
G01Y743132D02*
X847408Y743757D01*
G01Y745941D02*
X846866Y746024D01*
X846408Y746149D01*
X845991Y746316D01*
X845533Y746524D01*
X844908Y746857D01*
Y745191D01*
G01X847116Y748416D02*
X847325Y748707D01*
X847408Y749041D01*
X847325Y749374D01*
X847075Y749666D01*
X846700Y749874D01*
X846325Y749957D01*
X845866D01*
X845491Y749874D01*
X845158Y749666D01*
X844991Y749416D01*
X844908Y749124D01*
X844991Y748791D01*
X845158Y748541D01*
X845408Y748374D01*
X845741Y748291D01*
X846033Y748374D01*
X846325Y748582D01*
X846491Y748832D01*
X846533Y749124D01*
X846450Y749457D01*
X846241Y749707D01*
X845866Y749957D01*
G01X845325Y751432D02*
X845075Y751682D01*
X844950Y751974D01*
X844908Y752307D01*
X844991Y752724D01*
X845200Y753016D01*
X845450Y753099D01*
X845700Y753057D01*
X845908Y752891D01*
X846325Y752057D01*
X846616Y751682D01*
X847033Y751432D01*
X847408Y751349D01*
Y753099D01*
G01X847116Y754616D02*
X847325Y754907D01*
X847408Y755241D01*
X847325Y755574D01*
X847075Y755866D01*
X846700Y756074D01*
X846325Y756157D01*
X845866D01*
X845491Y756074D01*
X845158Y755866D01*
X844991Y755616D01*
X844908Y755324D01*
X844991Y754991D01*
X845158Y754741D01*
X845408Y754574D01*
X845741Y754491D01*
X846033Y754574D01*
X846325Y754782D01*
X846491Y755032D01*
X846533Y755324D01*
X846450Y755657D01*
X846241Y755907D01*
X845866Y756157D01*
G01X867406Y754098D02*
X863406D01*
Y746698D01*
G01X855406D02*
X859406D01*
Y754098D01*
G01Y746698D02*
X863406D01*
Y754098D01*
G01X841596Y779153D02*
Y777361D01*
X841763Y776986D01*
X842096Y776736D01*
X842513Y776653D01*
X842930Y776736D01*
X843263Y776986D01*
X843430Y777361D01*
Y779153D01*
G01X844821Y778736D02*
X845071Y778986D01*
X845363Y779111D01*
X845696Y779153D01*
X846113Y779070D01*
X846405Y778861D01*
X846488Y778611D01*
X846446Y778361D01*
X846280Y778153D01*
X845446Y777736D01*
X845071Y777445D01*
X844821Y777028D01*
X844738Y776653D01*
X846488D01*
G01X848713Y779153D02*
X848380Y779070D01*
X848130Y778861D01*
X847963Y778611D01*
X847838Y778278D01*
X847796Y777903D01*
X847838Y777528D01*
X847963Y777195D01*
X848130Y776945D01*
X848380Y776736D01*
X848713Y776653D01*
X849046Y776736D01*
X849296Y776945D01*
X849463Y777195D01*
X849588Y777528D01*
X849630Y777903D01*
X849588Y778278D01*
X849463Y778611D01*
X849296Y778861D01*
X849046Y779070D01*
X848713Y779153D01*
G01X851813D02*
X851480Y779070D01*
X851230Y778861D01*
X851063Y778611D01*
X850938Y778278D01*
X850896Y777903D01*
X850938Y777528D01*
X851063Y777195D01*
X851230Y776945D01*
X851480Y776736D01*
X851813Y776653D01*
X852146Y776736D01*
X852396Y776945D01*
X852563Y777195D01*
X852688Y777528D01*
X852730Y777903D01*
X852688Y778278D01*
X852563Y778611D01*
X852396Y778861D01*
X852146Y779070D01*
X851813Y779153D01*
G01X889406Y768398D02*
X858706D01*
G01Y782398D02*
X889406D01*
G01X858706D02*
Y768398D01*
G01X859806Y775398D02*
X858706Y776498D01*
G01X859806Y775398D02*
X858706Y774298D01*
G01X867756Y795698D02*
X871756D01*
Y803098D01*
G01X846850Y797179D02*
X844350D01*
Y798220D01*
X844475Y798554D01*
X844642Y798762D01*
X844975Y798845D01*
X845308Y798762D01*
X845517Y798512D01*
X845642Y798220D01*
Y797179D01*
G01Y798220D02*
X846850Y798845D01*
G01Y801029D02*
X846308Y801112D01*
X845850Y801237D01*
X845433Y801404D01*
X844975Y801612D01*
X844350Y801945D01*
Y800279D01*
G01X846558Y803504D02*
X846767Y803795D01*
X846850Y804129D01*
X846767Y804462D01*
X846517Y804754D01*
X846142Y804962D01*
X845767Y805045D01*
X845308D01*
X844933Y804962D01*
X844600Y804754D01*
X844433Y804504D01*
X844350Y804212D01*
X844433Y803879D01*
X844600Y803629D01*
X844850Y803462D01*
X845183Y803379D01*
X845475Y803462D01*
X845767Y803670D01*
X845933Y803920D01*
X845975Y804212D01*
X845892Y804545D01*
X845683Y804795D01*
X845308Y805045D01*
G01X846850Y807229D02*
X846308Y807312D01*
X845850Y807437D01*
X845433Y807604D01*
X844975Y807812D01*
X844350Y808145D01*
Y806479D01*
G01X846850Y810329D02*
X846308Y810412D01*
X845850Y810537D01*
X845433Y810704D01*
X844975Y810912D01*
X844350Y811245D01*
Y809579D01*
G01X871850Y795700D02*
X875850D01*
Y803100D01*
G01X842893Y797239D02*
X840393D01*
Y798280D01*
X840518Y798614D01*
X840685Y798822D01*
X841018Y798905D01*
X841351Y798822D01*
X841560Y798572D01*
X841685Y798280D01*
Y797239D01*
G01Y798280D02*
X842893Y798905D01*
G01Y801089D02*
X842351Y801172D01*
X841893Y801297D01*
X841476Y801464D01*
X841018Y801672D01*
X840393Y802005D01*
Y800339D01*
G01X842601Y803564D02*
X842810Y803855D01*
X842893Y804189D01*
X842810Y804522D01*
X842560Y804814D01*
X842185Y805022D01*
X841810Y805105D01*
X841351D01*
X840976Y805022D01*
X840643Y804814D01*
X840476Y804564D01*
X840393Y804272D01*
X840476Y803939D01*
X840643Y803689D01*
X840893Y803522D01*
X841226Y803439D01*
X841518Y803522D01*
X841810Y803730D01*
X841976Y803980D01*
X842018Y804272D01*
X841935Y804605D01*
X841726Y804855D01*
X841351Y805105D01*
G01X842393Y806455D02*
X842685Y806705D01*
X842851Y807039D01*
X842893Y807414D01*
X842851Y807747D01*
X842643Y808080D01*
X842393Y808289D01*
X842143Y808330D01*
X841851Y808247D01*
X841643Y807955D01*
X841560Y807664D01*
Y807289D01*
G01Y807664D02*
X841435Y807914D01*
X841226Y808122D01*
X840976Y808205D01*
X840726Y808122D01*
X840518Y807914D01*
X840393Y807539D01*
X840435Y807164D01*
X840601Y806789D01*
G01X842893Y810972D02*
X840393D01*
X842185Y809430D01*
Y811514D01*
G01X863406Y803098D02*
X859406D01*
Y795698D01*
G01Y803098D02*
X855406D01*
Y795698D01*
G01X867478Y803131D02*
X863478D01*
Y795731D01*
G01X871578Y813954D02*
X869078D01*
Y814995D01*
X869203Y815329D01*
X869370Y815537D01*
X869703Y815620D01*
X870036Y815537D01*
X870245Y815287D01*
X870370Y814995D01*
Y813954D01*
G01Y814995D02*
X871578Y815620D01*
G01X871286Y817179D02*
X871495Y817470D01*
X871578Y817804D01*
X871495Y818137D01*
X871245Y818429D01*
X870870Y818637D01*
X870495Y818720D01*
X870036D01*
X869661Y818637D01*
X869328Y818429D01*
X869161Y818179D01*
X869078Y817887D01*
X869161Y817554D01*
X869328Y817304D01*
X869578Y817137D01*
X869911Y817054D01*
X870203Y817137D01*
X870495Y817345D01*
X870661Y817595D01*
X870703Y817887D01*
X870620Y818220D01*
X870411Y818470D01*
X870036Y818720D01*
G01X869078Y820987D02*
X869161Y820654D01*
X869370Y820404D01*
X869620Y820237D01*
X869953Y820112D01*
X870328Y820070D01*
X870703Y820112D01*
X871036Y820237D01*
X871286Y820404D01*
X871495Y820654D01*
X871578Y820987D01*
X871495Y821320D01*
X871286Y821570D01*
X871036Y821737D01*
X870703Y821862D01*
X870328Y821904D01*
X869953Y821862D01*
X869620Y821737D01*
X869370Y821570D01*
X869161Y821320D01*
X869078Y820987D01*
G01X871578Y824587D02*
X869078D01*
X870870Y823045D01*
Y825129D01*
G01X869495Y826395D02*
X869245Y826645D01*
X869120Y826937D01*
X869078Y827270D01*
X869161Y827687D01*
X869370Y827979D01*
X869620Y828062D01*
X869870Y828020D01*
X870078Y827854D01*
X870495Y827020D01*
X870786Y826645D01*
X871203Y826395D01*
X871578Y826312D01*
Y828062D01*
G01X868900Y803400D02*
X872900D01*
Y810800D01*
G01X840665Y816968D02*
X840540Y816718D01*
X840457Y816426D01*
Y816093D01*
X840582Y815718D01*
X840790Y815426D01*
X841040Y815218D01*
X841457Y815051D01*
X841832Y815009D01*
X842207Y815093D01*
X842457Y815218D01*
X842707Y815468D01*
X842874Y815759D01*
X842957Y816051D01*
Y816343D01*
X842874Y816634D01*
X842749Y816884D01*
X842582Y817093D01*
G01X842957Y819151D02*
X840457D01*
X840957Y818651D01*
G01X842957D02*
Y819651D01*
G01Y822251D02*
X840457D01*
X840957Y821751D01*
G01X842957D02*
Y822751D01*
G01X840457Y825351D02*
X840540Y825018D01*
X840749Y824768D01*
X840999Y824601D01*
X841332Y824476D01*
X841707Y824434D01*
X842082Y824476D01*
X842415Y824601D01*
X842665Y824768D01*
X842874Y825018D01*
X842957Y825351D01*
X842874Y825684D01*
X842665Y825934D01*
X842415Y826101D01*
X842082Y826226D01*
X841707Y826268D01*
X841332Y826226D01*
X840999Y826101D01*
X840749Y825934D01*
X840540Y825684D01*
X840457Y825351D01*
G01X849873Y816238D02*
X849748Y815988D01*
X849665Y815696D01*
Y815363D01*
X849790Y814988D01*
X849998Y814696D01*
X850248Y814488D01*
X850665Y814321D01*
X851040Y814279D01*
X851415Y814363D01*
X851665Y814488D01*
X851915Y814738D01*
X852082Y815029D01*
X852165Y815321D01*
Y815613D01*
X852082Y815904D01*
X851957Y816154D01*
X851790Y816363D01*
G01X852165Y818421D02*
X849665D01*
X850165Y817921D01*
G01X852165D02*
Y818921D01*
G01X849665Y821521D02*
X849748Y821188D01*
X849957Y820938D01*
X850207Y820771D01*
X850540Y820646D01*
X850915Y820604D01*
X851290Y820646D01*
X851623Y820771D01*
X851873Y820938D01*
X852082Y821188D01*
X852165Y821521D01*
X852082Y821854D01*
X851873Y822104D01*
X851623Y822271D01*
X851290Y822396D01*
X850915Y822438D01*
X850540Y822396D01*
X850207Y822271D01*
X849957Y822104D01*
X849748Y821854D01*
X849665Y821521D01*
G01X851873Y823913D02*
X852082Y824204D01*
X852165Y824538D01*
X852082Y824871D01*
X851832Y825163D01*
X851457Y825371D01*
X851082Y825454D01*
X850623D01*
X850248Y825371D01*
X849915Y825163D01*
X849748Y824913D01*
X849665Y824621D01*
X849748Y824288D01*
X849915Y824038D01*
X850165Y823871D01*
X850498Y823788D01*
X850790Y823871D01*
X851082Y824079D01*
X851248Y824329D01*
X851290Y824621D01*
X851207Y824954D01*
X850998Y825204D01*
X850623Y825454D01*
G01X853873Y816238D02*
X853748Y815988D01*
X853665Y815696D01*
Y815363D01*
X853790Y814988D01*
X853998Y814696D01*
X854248Y814488D01*
X854665Y814321D01*
X855040Y814279D01*
X855415Y814363D01*
X855665Y814488D01*
X855915Y814738D01*
X856082Y815029D01*
X856165Y815321D01*
Y815613D01*
X856082Y815904D01*
X855957Y816154D01*
X855790Y816363D01*
G01X856165Y818421D02*
X853665D01*
X854165Y817921D01*
G01X856165D02*
Y818921D01*
G01X853665Y821521D02*
X853748Y821188D01*
X853957Y820938D01*
X854207Y820771D01*
X854540Y820646D01*
X854915Y820604D01*
X855290Y820646D01*
X855623Y820771D01*
X855873Y820938D01*
X856082Y821188D01*
X856165Y821521D01*
X856082Y821854D01*
X855873Y822104D01*
X855623Y822271D01*
X855290Y822396D01*
X854915Y822438D01*
X854540Y822396D01*
X854207Y822271D01*
X853957Y822104D01*
X853748Y821854D01*
X853665Y821521D01*
G01X856165Y824621D02*
X856123Y824913D01*
X855998Y825246D01*
X855790Y825454D01*
X855498Y825538D01*
X855207Y825454D01*
X854957Y825204D01*
X854832Y824829D01*
Y824413D01*
X854748Y824163D01*
X854540Y823954D01*
X854248Y823871D01*
X853957Y823996D01*
X853748Y824288D01*
X853665Y824621D01*
X853748Y824954D01*
X853957Y825246D01*
X854248Y825371D01*
X854540Y825288D01*
X854748Y825079D01*
X854832Y824829D01*
Y824413D01*
X854957Y824038D01*
X855207Y823788D01*
X855498Y823704D01*
X855790Y823788D01*
X855998Y823996D01*
X856123Y824329D01*
X856165Y824621D01*
G01X899100Y22600D02*
X902589D01*
Y8000D01*
X899500D01*
Y-6000D01*
X898000D01*
G01X877000Y10400D02*
X885000D01*
Y-2000D01*
X877000D01*
Y10400D01*
G01X962336Y17243D02*
Y6943D01*
X969036D01*
Y-20257D01*
X901436D01*
Y6943D01*
X908136D01*
Y17243D01*
X962336D01*
G01X894000Y19000D02*
X897500D01*
G01X899000Y22600D02*
X900500Y21100D01*
Y24100D01*
X899000Y22600D01*
G01X903757Y25163D02*
Y22663D01*
X905423D01*
G01X908523D02*
X906857D01*
Y25163D01*
X908523D01*
G01X907857Y23955D02*
X906857D01*
G01X909873Y22663D02*
Y25163D01*
X910707D01*
X911040Y25038D01*
X911290Y24871D01*
X911498Y24621D01*
X911665Y24330D01*
X911707Y23913D01*
X911665Y23496D01*
X911498Y23205D01*
X911290Y22955D01*
X911040Y22788D01*
X910707Y22663D01*
X909873D01*
G01X913890D02*
Y25163D01*
X913390Y24663D01*
G01Y22663D02*
X914390D01*
G01X917490D02*
Y25163D01*
X915948Y23371D01*
X918032D01*
G01X898150Y26050D02*
Y19950D01*
G01X886850Y26050D02*
X898150D01*
G01X886850Y19950D02*
Y26050D01*
G01X898150Y19950D02*
X886850D01*
G01X881000Y8700D02*
X882500Y10200D01*
G01X881000Y8700D02*
X879500Y10200D01*
G01X902800Y35000D02*
Y31000D01*
X910200D01*
G01X902800D02*
Y27000D01*
X910200D01*
G01Y35000D02*
Y39000D01*
X902800D01*
G01Y43000D02*
Y39000D01*
X910200D01*
G01X894500Y11300D02*
X898500D01*
Y18700D01*
G01X893301Y18577D02*
X889301D01*
Y11177D01*
G01X884520Y11302D02*
X888520D01*
Y18702D01*
G01X905763Y21066D02*
X905513Y21191D01*
X905221Y21274D01*
X904888D01*
X904513Y21149D01*
X904221Y20941D01*
X904013Y20691D01*
X903846Y20274D01*
X903804Y19899D01*
X903888Y19524D01*
X904013Y19274D01*
X904263Y19024D01*
X904554Y18857D01*
X904846Y18774D01*
X905138D01*
X905429Y18857D01*
X905679Y18982D01*
X905888Y19149D01*
G01X907154Y20857D02*
X907404Y21107D01*
X907696Y21232D01*
X908029Y21274D01*
X908446Y21191D01*
X908738Y20982D01*
X908821Y20732D01*
X908779Y20482D01*
X908613Y20274D01*
X907779Y19857D01*
X907404Y19566D01*
X907154Y19149D01*
X907071Y18774D01*
X908821D01*
G01X911546D02*
Y21274D01*
X910004Y19482D01*
X912088D01*
G01X913438Y19066D02*
X913729Y18857D01*
X914063Y18774D01*
X914396Y18857D01*
X914688Y19107D01*
X914896Y19482D01*
X914979Y19857D01*
Y20316D01*
X914896Y20691D01*
X914688Y21024D01*
X914438Y21191D01*
X914146Y21274D01*
X913813Y21191D01*
X913563Y21024D01*
X913396Y20774D01*
X913313Y20441D01*
X913396Y20149D01*
X913604Y19857D01*
X913854Y19691D01*
X914146Y19649D01*
X914479Y19732D01*
X914729Y19941D01*
X914979Y20316D01*
G01X879400Y49300D02*
Y30100D01*
X890600D01*
Y49300D01*
X879400D01*
Y48900D01*
G01X884000Y12000D02*
Y25000D01*
G01X882100Y67550D02*
X896100D01*
G01X882100Y54250D02*
Y67550D01*
G01X896100Y54250D02*
X882100D01*
G01X896100Y67550D02*
Y54250D01*
G01X894214Y70324D02*
X891714D01*
Y71365D01*
X891839Y71699D01*
X892006Y71907D01*
X892339Y71990D01*
X892672Y71907D01*
X892881Y71657D01*
X893006Y71365D01*
Y70324D01*
G01Y71365D02*
X894214Y71990D01*
G01Y74174D02*
X893672Y74257D01*
X893214Y74382D01*
X892797Y74549D01*
X892339Y74757D01*
X891714Y75090D01*
Y73424D01*
G01X893922Y76649D02*
X894131Y76940D01*
X894214Y77274D01*
X894131Y77607D01*
X893881Y77899D01*
X893506Y78107D01*
X893131Y78190D01*
X892672D01*
X892297Y78107D01*
X891964Y77899D01*
X891797Y77649D01*
X891714Y77357D01*
X891797Y77024D01*
X891964Y76774D01*
X892214Y76607D01*
X892547Y76524D01*
X892839Y76607D01*
X893131Y76815D01*
X893297Y77065D01*
X893339Y77357D01*
X893256Y77690D01*
X893047Y77940D01*
X892672Y78190D01*
G01X891714Y80457D02*
X891797Y80124D01*
X892006Y79874D01*
X892256Y79707D01*
X892589Y79582D01*
X892964Y79540D01*
X893339Y79582D01*
X893672Y79707D01*
X893922Y79874D01*
X894131Y80124D01*
X894214Y80457D01*
X894131Y80790D01*
X893922Y81040D01*
X893672Y81207D01*
X893339Y81332D01*
X892964Y81374D01*
X892589Y81332D01*
X892256Y81207D01*
X892006Y81040D01*
X891797Y80790D01*
X891714Y80457D01*
G01X893922Y82849D02*
X894131Y83140D01*
X894214Y83474D01*
X894131Y83807D01*
X893881Y84099D01*
X893506Y84307D01*
X893131Y84390D01*
X892672D01*
X892297Y84307D01*
X891964Y84099D01*
X891797Y83849D01*
X891714Y83557D01*
X891797Y83224D01*
X891964Y82974D01*
X892214Y82807D01*
X892547Y82724D01*
X892839Y82807D01*
X893131Y83015D01*
X893297Y83265D01*
X893339Y83557D01*
X893256Y83890D01*
X893047Y84140D01*
X892672Y84390D01*
G01X897200Y59700D02*
X901200D01*
Y67100D01*
G01X904558Y54937D02*
Y57437D01*
X905599D01*
X905933Y57312D01*
X906141Y57145D01*
X906224Y56812D01*
X906141Y56479D01*
X905891Y56270D01*
X905599Y56145D01*
X904558D01*
G01X905599D02*
X906224Y54937D01*
G01X907783Y55229D02*
X908074Y55020D01*
X908408Y54937D01*
X908741Y55020D01*
X909033Y55270D01*
X909241Y55645D01*
X909324Y56020D01*
Y56479D01*
X909241Y56854D01*
X909033Y57187D01*
X908783Y57354D01*
X908491Y57437D01*
X908158Y57354D01*
X907908Y57187D01*
X907741Y56937D01*
X907658Y56604D01*
X907741Y56312D01*
X907949Y56020D01*
X908199Y55854D01*
X908491Y55812D01*
X908824Y55895D01*
X909074Y56104D01*
X909324Y56479D01*
G01X910674Y55312D02*
X910924Y55104D01*
X911216Y54979D01*
X911591Y54937D01*
X911966Y55020D01*
X912258Y55187D01*
X912466Y55479D01*
X912508Y55812D01*
X912424Y56145D01*
X912216Y56354D01*
X911924Y56520D01*
X911633Y56562D01*
X911341Y56520D01*
X910966Y56354D01*
X911091Y57437D01*
X912216D01*
G01X913774Y55437D02*
X914024Y55145D01*
X914358Y54979D01*
X914733Y54937D01*
X915066Y54979D01*
X915399Y55187D01*
X915608Y55437D01*
X915649Y55687D01*
X915566Y55979D01*
X915274Y56187D01*
X914983Y56270D01*
X914608D01*
G01X914983D02*
X915233Y56395D01*
X915441Y56604D01*
X915524Y56854D01*
X915441Y57104D01*
X915233Y57312D01*
X914858Y57437D01*
X914483Y57395D01*
X914108Y57229D01*
G01X906030Y58905D02*
Y61405D01*
X907071D01*
X907405Y61280D01*
X907613Y61113D01*
X907696Y60780D01*
X907613Y60447D01*
X907363Y60238D01*
X907071Y60113D01*
X906030D01*
G01X907071D02*
X907696Y58905D01*
G01X909171Y59947D02*
X909463Y60238D01*
X909713Y60405D01*
X910046Y60488D01*
X910338Y60405D01*
X910546Y60238D01*
X910713Y59988D01*
X910755Y59697D01*
X910713Y59447D01*
X910546Y59197D01*
X910296Y58988D01*
X910005Y58905D01*
X909671Y58988D01*
X909380Y59238D01*
X909213Y59613D01*
X909171Y60030D01*
X909255Y60572D01*
X909380Y60863D01*
X909588Y61155D01*
X909880Y61363D01*
X910171Y61405D01*
X910463Y61322D01*
X910671Y61113D01*
G01X912146Y59280D02*
X912396Y59072D01*
X912688Y58947D01*
X913063Y58905D01*
X913438Y58988D01*
X913730Y59155D01*
X913938Y59447D01*
X913980Y59780D01*
X913896Y60113D01*
X913688Y60322D01*
X913396Y60488D01*
X913105Y60530D01*
X912813Y60488D01*
X912438Y60322D01*
X912563Y61405D01*
X913688D01*
G01X915246Y59405D02*
X915496Y59113D01*
X915830Y58947D01*
X916205Y58905D01*
X916538Y58947D01*
X916871Y59155D01*
X917080Y59405D01*
X917121Y59655D01*
X917038Y59947D01*
X916746Y60155D01*
X916455Y60238D01*
X916080D01*
G01X916455D02*
X916705Y60363D01*
X916913Y60572D01*
X916996Y60822D01*
X916913Y61072D01*
X916705Y61280D01*
X916330Y61405D01*
X915955Y61363D01*
X915580Y61197D01*
G01X904648Y63008D02*
Y65508D01*
X905689D01*
X906023Y65383D01*
X906231Y65216D01*
X906314Y64883D01*
X906231Y64550D01*
X905981Y64341D01*
X905689Y64216D01*
X904648D01*
G01X905689D02*
X906314Y63008D01*
G01X907789Y64050D02*
X908081Y64341D01*
X908331Y64508D01*
X908664Y64591D01*
X908956Y64508D01*
X909164Y64341D01*
X909331Y64091D01*
X909373Y63800D01*
X909331Y63550D01*
X909164Y63300D01*
X908914Y63091D01*
X908623Y63008D01*
X908289Y63091D01*
X907998Y63341D01*
X907831Y63716D01*
X907789Y64133D01*
X907873Y64675D01*
X907998Y64966D01*
X908206Y65258D01*
X908498Y65466D01*
X908789Y65508D01*
X909081Y65425D01*
X909289Y65216D01*
G01X910764Y63383D02*
X911014Y63175D01*
X911306Y63050D01*
X911681Y63008D01*
X912056Y63091D01*
X912348Y63258D01*
X912556Y63550D01*
X912598Y63883D01*
X912514Y64216D01*
X912306Y64425D01*
X912014Y64591D01*
X911723Y64633D01*
X911431Y64591D01*
X911056Y64425D01*
X911181Y65508D01*
X912306D01*
G01X913989Y65091D02*
X914239Y65341D01*
X914531Y65466D01*
X914864Y65508D01*
X915281Y65425D01*
X915573Y65216D01*
X915656Y64966D01*
X915614Y64716D01*
X915448Y64508D01*
X914614Y64091D01*
X914239Y63800D01*
X913989Y63383D01*
X913906Y63008D01*
X915656D01*
G01X874593Y64528D02*
X874468Y64278D01*
X874385Y63986D01*
Y63653D01*
X874510Y63278D01*
X874718Y62986D01*
X874968Y62778D01*
X875385Y62611D01*
X875760Y62569D01*
X876135Y62653D01*
X876385Y62778D01*
X876635Y63028D01*
X876802Y63319D01*
X876885Y63611D01*
Y63903D01*
X876802Y64194D01*
X876677Y64444D01*
X876510Y64653D01*
G01X874802Y65919D02*
X874552Y66169D01*
X874427Y66461D01*
X874385Y66794D01*
X874468Y67211D01*
X874677Y67503D01*
X874927Y67586D01*
X875177Y67544D01*
X875385Y67378D01*
X875802Y66544D01*
X876093Y66169D01*
X876510Y65919D01*
X876885Y65836D01*
Y67586D01*
G01Y69728D02*
X876343Y69811D01*
X875885Y69936D01*
X875468Y70103D01*
X875010Y70311D01*
X874385Y70644D01*
Y68978D01*
G01X876885Y72911D02*
X874385D01*
X874885Y72411D01*
G01X876885D02*
Y73411D01*
G01X907022Y69136D02*
X906772Y69261D01*
X906480Y69344D01*
X906147D01*
X905772Y69219D01*
X905480Y69011D01*
X905272Y68761D01*
X905105Y68344D01*
X905063Y67969D01*
X905147Y67594D01*
X905272Y67344D01*
X905522Y67094D01*
X905813Y66927D01*
X906105Y66844D01*
X906397D01*
X906688Y66927D01*
X906938Y67052D01*
X907147Y67219D01*
G01X909122Y66844D02*
X909205Y67386D01*
X909330Y67844D01*
X909497Y68261D01*
X909705Y68719D01*
X910038Y69344D01*
X908372D01*
G01X911513Y68927D02*
X911763Y69177D01*
X912055Y69302D01*
X912388Y69344D01*
X912805Y69261D01*
X913097Y69052D01*
X913180Y68802D01*
X913138Y68552D01*
X912972Y68344D01*
X912138Y67927D01*
X911763Y67636D01*
X911513Y67219D01*
X911430Y66844D01*
X913180D01*
G01X915405D02*
X915697Y66886D01*
X916030Y67011D01*
X916238Y67219D01*
X916322Y67511D01*
X916238Y67802D01*
X915988Y68052D01*
X915613Y68177D01*
X915197D01*
X914947Y68261D01*
X914738Y68469D01*
X914655Y68761D01*
X914780Y69052D01*
X915072Y69261D01*
X915405Y69344D01*
X915738Y69261D01*
X916030Y69052D01*
X916155Y68761D01*
X916072Y68469D01*
X915863Y68261D01*
X915613Y68177D01*
X915197D01*
X914822Y68052D01*
X914572Y67802D01*
X914488Y67511D01*
X914572Y67219D01*
X914780Y67011D01*
X915113Y66886D01*
X915405Y66844D01*
G01X907022Y73328D02*
X906772Y73453D01*
X906480Y73536D01*
X906147D01*
X905772Y73411D01*
X905480Y73203D01*
X905272Y72953D01*
X905105Y72536D01*
X905063Y72161D01*
X905147Y71786D01*
X905272Y71536D01*
X905522Y71286D01*
X905813Y71119D01*
X906105Y71036D01*
X906397D01*
X906688Y71119D01*
X906938Y71244D01*
X907147Y71411D01*
G01X909122Y71036D02*
X909205Y71578D01*
X909330Y72036D01*
X909497Y72453D01*
X909705Y72911D01*
X910038Y73536D01*
X908372D01*
G01X911513Y73119D02*
X911763Y73369D01*
X912055Y73494D01*
X912388Y73536D01*
X912805Y73453D01*
X913097Y73244D01*
X913180Y72994D01*
X913138Y72744D01*
X912972Y72536D01*
X912138Y72119D01*
X911763Y71828D01*
X911513Y71411D01*
X911430Y71036D01*
X913180D01*
G01X915322D02*
X915405Y71578D01*
X915530Y72036D01*
X915697Y72453D01*
X915905Y72911D01*
X916238Y73536D01*
X914572D01*
G01X899737Y48564D02*
X901529D01*
X901904Y48731D01*
X902154Y49064D01*
X902237Y49481D01*
X902154Y49898D01*
X901904Y50231D01*
X901529Y50398D01*
X899737D01*
G01X902237Y52581D02*
X899737D01*
X900237Y52081D01*
G01X902237D02*
Y53081D01*
G01X899737Y55681D02*
X899820Y55348D01*
X900029Y55098D01*
X900279Y54931D01*
X900612Y54806D01*
X900987Y54764D01*
X901362Y54806D01*
X901695Y54931D01*
X901945Y55098D01*
X902154Y55348D01*
X902237Y55681D01*
X902154Y56014D01*
X901945Y56264D01*
X901695Y56431D01*
X901362Y56556D01*
X900987Y56598D01*
X900612Y56556D01*
X900279Y56431D01*
X900029Y56264D01*
X899820Y56014D01*
X899737Y55681D01*
G01X887000Y49200D02*
X885200Y47100D01*
X883000Y49200D01*
G01X878554Y83858D02*
Y82066D01*
X878721Y81691D01*
X879054Y81441D01*
X879471Y81358D01*
X879888Y81441D01*
X880221Y81691D01*
X880388Y82066D01*
Y83858D01*
G01X882571Y81358D02*
X882863Y81400D01*
X883196Y81525D01*
X883404Y81733D01*
X883488Y82025D01*
X883404Y82316D01*
X883154Y82566D01*
X882779Y82691D01*
X882363D01*
X882113Y82775D01*
X881904Y82983D01*
X881821Y83275D01*
X881946Y83566D01*
X882238Y83775D01*
X882571Y83858D01*
X882904Y83775D01*
X883196Y83566D01*
X883321Y83275D01*
X883238Y82983D01*
X883029Y82775D01*
X882779Y82691D01*
X882363D01*
X881988Y82566D01*
X881738Y82316D01*
X881654Y82025D01*
X881738Y81733D01*
X881946Y81525D01*
X882279Y81400D01*
X882571Y81358D01*
G01X884879Y83441D02*
X885129Y83691D01*
X885421Y83816D01*
X885754Y83858D01*
X886171Y83775D01*
X886463Y83566D01*
X886546Y83316D01*
X886504Y83066D01*
X886338Y82858D01*
X885504Y82441D01*
X885129Y82150D01*
X884879Y81733D01*
X884796Y81358D01*
X886546D01*
G01X907597Y96654D02*
X905097D01*
Y97695D01*
X905222Y98029D01*
X905389Y98237D01*
X905722Y98320D01*
X906055Y98237D01*
X906264Y97987D01*
X906389Y97695D01*
Y96654D01*
G01Y97695D02*
X907597Y98320D01*
G01X907097Y99670D02*
X907389Y99920D01*
X907555Y100254D01*
X907597Y100629D01*
X907555Y100962D01*
X907347Y101295D01*
X907097Y101504D01*
X906847Y101545D01*
X906555Y101462D01*
X906347Y101170D01*
X906264Y100879D01*
Y100504D01*
G01Y100879D02*
X906139Y101129D01*
X905930Y101337D01*
X905680Y101420D01*
X905430Y101337D01*
X905222Y101129D01*
X905097Y100754D01*
X905139Y100379D01*
X905305Y100004D01*
G01X907597Y103604D02*
X907055Y103687D01*
X906597Y103812D01*
X906180Y103979D01*
X905722Y104187D01*
X905097Y104520D01*
Y102854D01*
G01X907597Y106787D02*
X905097D01*
X905597Y106287D01*
G01X907597D02*
Y107287D01*
G01Y109804D02*
X907055Y109887D01*
X906597Y110012D01*
X906180Y110179D01*
X905722Y110387D01*
X905097Y110720D01*
Y109054D01*
G01X904500Y87800D02*
X908500D01*
Y95200D01*
G01X893813Y96725D02*
X891313D01*
Y97766D01*
X891438Y98100D01*
X891605Y98308D01*
X891938Y98391D01*
X892271Y98308D01*
X892480Y98058D01*
X892605Y97766D01*
Y96725D01*
G01Y97766D02*
X893813Y98391D01*
G01X893313Y99741D02*
X893605Y99991D01*
X893771Y100325D01*
X893813Y100700D01*
X893771Y101033D01*
X893563Y101366D01*
X893313Y101575D01*
X893063Y101616D01*
X892771Y101533D01*
X892563Y101241D01*
X892480Y100950D01*
Y100575D01*
G01Y100950D02*
X892355Y101200D01*
X892146Y101408D01*
X891896Y101491D01*
X891646Y101408D01*
X891438Y101200D01*
X891313Y100825D01*
X891355Y100450D01*
X891521Y100075D01*
G01X893813Y103675D02*
X893271Y103758D01*
X892813Y103883D01*
X892396Y104050D01*
X891938Y104258D01*
X891313Y104591D01*
Y102925D01*
G01X893813Y106858D02*
X891313D01*
X891813Y106358D01*
G01X893813D02*
Y107358D01*
G01X893521Y109250D02*
X893730Y109541D01*
X893813Y109875D01*
X893730Y110208D01*
X893480Y110500D01*
X893105Y110708D01*
X892730Y110791D01*
X892271D01*
X891896Y110708D01*
X891563Y110500D01*
X891396Y110250D01*
X891313Y109958D01*
X891396Y109625D01*
X891563Y109375D01*
X891813Y109208D01*
X892146Y109125D01*
X892438Y109208D01*
X892730Y109416D01*
X892896Y109666D01*
X892938Y109958D01*
X892855Y110291D01*
X892646Y110541D01*
X892271Y110791D01*
G01X891000Y87800D02*
X895000D01*
Y95200D01*
G01X898241Y96725D02*
X895741D01*
Y97766D01*
X895866Y98100D01*
X896033Y98308D01*
X896366Y98391D01*
X896699Y98308D01*
X896908Y98058D01*
X897033Y97766D01*
Y96725D01*
G01Y97766D02*
X898241Y98391D01*
G01X897741Y99741D02*
X898033Y99991D01*
X898199Y100325D01*
X898241Y100700D01*
X898199Y101033D01*
X897991Y101366D01*
X897741Y101575D01*
X897491Y101616D01*
X897199Y101533D01*
X896991Y101241D01*
X896908Y100950D01*
Y100575D01*
G01Y100950D02*
X896783Y101200D01*
X896574Y101408D01*
X896324Y101491D01*
X896074Y101408D01*
X895866Y101200D01*
X895741Y100825D01*
X895783Y100450D01*
X895949Y100075D01*
G01X898241Y103675D02*
X897699Y103758D01*
X897241Y103883D01*
X896824Y104050D01*
X896366Y104258D01*
X895741Y104591D01*
Y102925D01*
G01X896158Y106066D02*
X895908Y106316D01*
X895783Y106608D01*
X895741Y106941D01*
X895824Y107358D01*
X896033Y107650D01*
X896283Y107733D01*
X896533Y107691D01*
X896741Y107525D01*
X897158Y106691D01*
X897449Y106316D01*
X897866Y106066D01*
X898241Y105983D01*
Y107733D01*
G01X895741Y109958D02*
X895824Y109625D01*
X896033Y109375D01*
X896283Y109208D01*
X896616Y109083D01*
X896991Y109041D01*
X897366Y109083D01*
X897699Y109208D01*
X897949Y109375D01*
X898158Y109625D01*
X898241Y109958D01*
X898158Y110291D01*
X897949Y110541D01*
X897699Y110708D01*
X897366Y110833D01*
X896991Y110875D01*
X896616Y110833D01*
X896283Y110708D01*
X896033Y110541D01*
X895824Y110291D01*
X895741Y109958D01*
G01X895500Y87800D02*
X899500D01*
Y95200D01*
G01X884528Y96725D02*
X882028D01*
Y97766D01*
X882153Y98100D01*
X882320Y98308D01*
X882653Y98391D01*
X882986Y98308D01*
X883195Y98058D01*
X883320Y97766D01*
Y96725D01*
G01Y97766D02*
X884528Y98391D01*
G01X884028Y99741D02*
X884320Y99991D01*
X884486Y100325D01*
X884528Y100700D01*
X884486Y101033D01*
X884278Y101366D01*
X884028Y101575D01*
X883778Y101616D01*
X883486Y101533D01*
X883278Y101241D01*
X883195Y100950D01*
Y100575D01*
G01Y100950D02*
X883070Y101200D01*
X882861Y101408D01*
X882611Y101491D01*
X882361Y101408D01*
X882153Y101200D01*
X882028Y100825D01*
X882070Y100450D01*
X882236Y100075D01*
G01X884528Y103675D02*
X883986Y103758D01*
X883528Y103883D01*
X883111Y104050D01*
X882653Y104258D01*
X882028Y104591D01*
Y102925D01*
G01X882445Y106066D02*
X882195Y106316D01*
X882070Y106608D01*
X882028Y106941D01*
X882111Y107358D01*
X882320Y107650D01*
X882570Y107733D01*
X882820Y107691D01*
X883028Y107525D01*
X883445Y106691D01*
X883736Y106316D01*
X884153Y106066D01*
X884528Y105983D01*
Y107733D01*
G01Y109958D02*
X882028D01*
X882528Y109458D01*
G01X884528D02*
Y110458D01*
G01X882000Y87800D02*
X886000D01*
Y95200D01*
G01X880099Y96725D02*
X877599D01*
Y97766D01*
X877724Y98100D01*
X877891Y98308D01*
X878224Y98391D01*
X878557Y98308D01*
X878766Y98058D01*
X878891Y97766D01*
Y96725D01*
G01Y97766D02*
X880099Y98391D01*
G01X879599Y99741D02*
X879891Y99991D01*
X880057Y100325D01*
X880099Y100700D01*
X880057Y101033D01*
X879849Y101366D01*
X879599Y101575D01*
X879349Y101616D01*
X879057Y101533D01*
X878849Y101241D01*
X878766Y100950D01*
Y100575D01*
G01Y100950D02*
X878641Y101200D01*
X878432Y101408D01*
X878182Y101491D01*
X877932Y101408D01*
X877724Y101200D01*
X877599Y100825D01*
X877641Y100450D01*
X877807Y100075D01*
G01X880099Y103675D02*
X879557Y103758D01*
X879099Y103883D01*
X878682Y104050D01*
X878224Y104258D01*
X877599Y104591D01*
Y102925D01*
G01X878016Y106066D02*
X877766Y106316D01*
X877641Y106608D01*
X877599Y106941D01*
X877682Y107358D01*
X877891Y107650D01*
X878141Y107733D01*
X878391Y107691D01*
X878599Y107525D01*
X879016Y106691D01*
X879307Y106316D01*
X879724Y106066D01*
X880099Y105983D01*
Y107733D01*
G01Y110458D02*
X877599D01*
X879391Y108916D01*
Y111000D01*
G01X877500Y87800D02*
X881500D01*
Y95200D01*
G01X902955Y96654D02*
X900455D01*
Y97695D01*
X900580Y98029D01*
X900747Y98237D01*
X901080Y98320D01*
X901413Y98237D01*
X901622Y97987D01*
X901747Y97695D01*
Y96654D01*
G01Y97695D02*
X902955Y98320D01*
G01X902455Y99670D02*
X902747Y99920D01*
X902913Y100254D01*
X902955Y100629D01*
X902913Y100962D01*
X902705Y101295D01*
X902455Y101504D01*
X902205Y101545D01*
X901913Y101462D01*
X901705Y101170D01*
X901622Y100879D01*
Y100504D01*
G01Y100879D02*
X901497Y101129D01*
X901288Y101337D01*
X901038Y101420D01*
X900788Y101337D01*
X900580Y101129D01*
X900455Y100754D01*
X900497Y100379D01*
X900663Y100004D01*
G01X902955Y103604D02*
X902413Y103687D01*
X901955Y103812D01*
X901538Y103979D01*
X901080Y104187D01*
X900455Y104520D01*
Y102854D01*
G01X902955Y106787D02*
X900455D01*
X900955Y106287D01*
G01X902955D02*
Y107287D01*
G01Y109887D02*
X902913Y110179D01*
X902788Y110512D01*
X902580Y110720D01*
X902288Y110804D01*
X901997Y110720D01*
X901747Y110470D01*
X901622Y110095D01*
Y109679D01*
X901538Y109429D01*
X901330Y109220D01*
X901038Y109137D01*
X900747Y109262D01*
X900538Y109554D01*
X900455Y109887D01*
X900538Y110220D01*
X900747Y110512D01*
X901038Y110637D01*
X901330Y110554D01*
X901538Y110345D01*
X901622Y110095D01*
Y109679D01*
X901747Y109304D01*
X901997Y109054D01*
X902288Y108970D01*
X902580Y109054D01*
X902788Y109262D01*
X902913Y109595D01*
X902955Y109887D01*
G01X900000Y87800D02*
X904000D01*
Y95200D01*
G01X888528Y96725D02*
X886028D01*
Y97766D01*
X886153Y98100D01*
X886320Y98308D01*
X886653Y98391D01*
X886986Y98308D01*
X887195Y98058D01*
X887320Y97766D01*
Y96725D01*
G01Y97766D02*
X888528Y98391D01*
G01X888028Y99741D02*
X888320Y99991D01*
X888486Y100325D01*
X888528Y100700D01*
X888486Y101033D01*
X888278Y101366D01*
X888028Y101575D01*
X887778Y101616D01*
X887486Y101533D01*
X887278Y101241D01*
X887195Y100950D01*
Y100575D01*
G01Y100950D02*
X887070Y101200D01*
X886861Y101408D01*
X886611Y101491D01*
X886361Y101408D01*
X886153Y101200D01*
X886028Y100825D01*
X886070Y100450D01*
X886236Y100075D01*
G01X888528Y103675D02*
X887986Y103758D01*
X887528Y103883D01*
X887111Y104050D01*
X886653Y104258D01*
X886028Y104591D01*
Y102925D01*
G01X886445Y106066D02*
X886195Y106316D01*
X886070Y106608D01*
X886028Y106941D01*
X886111Y107358D01*
X886320Y107650D01*
X886570Y107733D01*
X886820Y107691D01*
X887028Y107525D01*
X887445Y106691D01*
X887736Y106316D01*
X888153Y106066D01*
X888528Y105983D01*
Y107733D01*
G01X886445Y109166D02*
X886195Y109416D01*
X886070Y109708D01*
X886028Y110041D01*
X886111Y110458D01*
X886320Y110750D01*
X886570Y110833D01*
X886820Y110791D01*
X887028Y110625D01*
X887445Y109791D01*
X887736Y109416D01*
X888153Y109166D01*
X888528Y109083D01*
Y110833D01*
G01X886500Y87800D02*
X890500D01*
Y95200D01*
G01X876099Y96725D02*
X873599D01*
Y97766D01*
X873724Y98100D01*
X873891Y98308D01*
X874224Y98391D01*
X874557Y98308D01*
X874766Y98058D01*
X874891Y97766D01*
Y96725D01*
G01Y97766D02*
X876099Y98391D01*
G01X875599Y99741D02*
X875891Y99991D01*
X876057Y100325D01*
X876099Y100700D01*
X876057Y101033D01*
X875849Y101366D01*
X875599Y101575D01*
X875349Y101616D01*
X875057Y101533D01*
X874849Y101241D01*
X874766Y100950D01*
Y100575D01*
G01Y100950D02*
X874641Y101200D01*
X874432Y101408D01*
X874182Y101491D01*
X873932Y101408D01*
X873724Y101200D01*
X873599Y100825D01*
X873641Y100450D01*
X873807Y100075D01*
G01X876099Y103675D02*
X875557Y103758D01*
X875099Y103883D01*
X874682Y104050D01*
X874224Y104258D01*
X873599Y104591D01*
Y102925D01*
G01X874016Y106066D02*
X873766Y106316D01*
X873641Y106608D01*
X873599Y106941D01*
X873682Y107358D01*
X873891Y107650D01*
X874141Y107733D01*
X874391Y107691D01*
X874599Y107525D01*
X875016Y106691D01*
X875307Y106316D01*
X875724Y106066D01*
X876099Y105983D01*
Y107733D01*
G01X875599Y109041D02*
X875891Y109291D01*
X876057Y109625D01*
X876099Y110000D01*
X876057Y110333D01*
X875849Y110666D01*
X875599Y110875D01*
X875349Y110916D01*
X875057Y110833D01*
X874849Y110541D01*
X874766Y110250D01*
Y109875D01*
G01Y110250D02*
X874641Y110500D01*
X874432Y110708D01*
X874182Y110791D01*
X873932Y110708D01*
X873724Y110500D01*
X873599Y110125D01*
X873641Y109750D01*
X873807Y109375D01*
G01X880338Y79150D02*
X880088Y79275D01*
X879796Y79358D01*
X879463D01*
X879088Y79233D01*
X878796Y79025D01*
X878588Y78775D01*
X878421Y78358D01*
X878379Y77983D01*
X878463Y77608D01*
X878588Y77358D01*
X878838Y77108D01*
X879129Y76941D01*
X879421Y76858D01*
X879713D01*
X880004Y76941D01*
X880254Y77066D01*
X880463Y77233D01*
G01X881604Y77358D02*
X881854Y77066D01*
X882188Y76900D01*
X882563Y76858D01*
X882896Y76900D01*
X883229Y77108D01*
X883438Y77358D01*
X883479Y77608D01*
X883396Y77900D01*
X883104Y78108D01*
X882813Y78191D01*
X882438D01*
G01X882813D02*
X883063Y78316D01*
X883271Y78525D01*
X883354Y78775D01*
X883271Y79025D01*
X883063Y79233D01*
X882688Y79358D01*
X882313Y79316D01*
X881938Y79150D01*
G01X885538Y76858D02*
X885621Y77400D01*
X885746Y77858D01*
X885913Y78275D01*
X886121Y78733D01*
X886454Y79358D01*
X884788D01*
G01X889221Y76858D02*
Y79358D01*
X887679Y77566D01*
X889763D01*
G01X875275Y115157D02*
X880433D01*
G01X1010355D02*
X884133D01*
G01X883733Y114757D02*
G02I-1450J0D01*
G01X875275Y262795D02*
X880433D01*
G01X1010355D02*
X884133D01*
G01X883733Y263195D02*
G02I-1450J0D01*
G01X905000Y300700D02*
X907500D01*
G01X905000Y299742D02*
Y301658D01*
G01X907500Y302967D02*
X905000D01*
Y303967D01*
X905125Y304300D01*
X905417Y304550D01*
X905750Y304633D01*
X906083Y304550D01*
X906333Y304342D01*
X906458Y303967D01*
Y302967D01*
G01X907500Y306900D02*
X905000D01*
X905500Y306400D01*
G01X907500D02*
Y307400D01*
G01Y309917D02*
X906958Y310000D01*
X906500Y310125D01*
X906083Y310292D01*
X905625Y310500D01*
X905000Y310833D01*
Y309167D01*
G01X907500Y313100D02*
X905000D01*
X905500Y312600D01*
G01X907500D02*
Y313600D01*
G01X896248Y291193D02*
X893748D01*
Y292234D01*
X893873Y292568D01*
X894040Y292776D01*
X894373Y292859D01*
X894706Y292776D01*
X894915Y292526D01*
X895040Y292234D01*
Y291193D01*
G01Y292234D02*
X896248Y292859D01*
G01X895873Y294209D02*
X896081Y294459D01*
X896206Y294751D01*
X896248Y295126D01*
X896165Y295501D01*
X895998Y295793D01*
X895706Y296001D01*
X895373Y296043D01*
X895040Y295959D01*
X894831Y295751D01*
X894665Y295459D01*
X894623Y295168D01*
X894665Y294876D01*
X894831Y294501D01*
X893748Y294626D01*
Y295751D01*
G01X896248Y298226D02*
X896206Y298518D01*
X896081Y298851D01*
X895873Y299059D01*
X895581Y299143D01*
X895290Y299059D01*
X895040Y298809D01*
X894915Y298434D01*
Y298018D01*
X894831Y297768D01*
X894623Y297559D01*
X894331Y297476D01*
X894040Y297601D01*
X893831Y297893D01*
X893748Y298226D01*
X893831Y298559D01*
X894040Y298851D01*
X894331Y298976D01*
X894623Y298893D01*
X894831Y298684D01*
X894915Y298434D01*
Y298018D01*
X895040Y297643D01*
X895290Y297393D01*
X895581Y297309D01*
X895873Y297393D01*
X896081Y297601D01*
X896206Y297934D01*
X896248Y298226D01*
G01Y301326D02*
X896206Y301618D01*
X896081Y301951D01*
X895873Y302159D01*
X895581Y302243D01*
X895290Y302159D01*
X895040Y301909D01*
X894915Y301534D01*
Y301118D01*
X894831Y300868D01*
X894623Y300659D01*
X894331Y300576D01*
X894040Y300701D01*
X893831Y300993D01*
X893748Y301326D01*
X893831Y301659D01*
X894040Y301951D01*
X894331Y302076D01*
X894623Y301993D01*
X894831Y301784D01*
X894915Y301534D01*
Y301118D01*
X895040Y300743D01*
X895290Y300493D01*
X895581Y300409D01*
X895873Y300493D01*
X896081Y300701D01*
X896206Y301034D01*
X896248Y301326D01*
G01X893000Y303900D02*
X897000D01*
Y311300D01*
G01X892248Y291193D02*
X889748D01*
Y292234D01*
X889873Y292568D01*
X890040Y292776D01*
X890373Y292859D01*
X890706Y292776D01*
X890915Y292526D01*
X891040Y292234D01*
Y291193D01*
G01Y292234D02*
X892248Y292859D01*
G01X891873Y294209D02*
X892081Y294459D01*
X892206Y294751D01*
X892248Y295126D01*
X892165Y295501D01*
X891998Y295793D01*
X891706Y296001D01*
X891373Y296043D01*
X891040Y295959D01*
X890831Y295751D01*
X890665Y295459D01*
X890623Y295168D01*
X890665Y294876D01*
X890831Y294501D01*
X889748Y294626D01*
Y295751D01*
G01X892248Y298226D02*
X892206Y298518D01*
X892081Y298851D01*
X891873Y299059D01*
X891581Y299143D01*
X891290Y299059D01*
X891040Y298809D01*
X890915Y298434D01*
Y298018D01*
X890831Y297768D01*
X890623Y297559D01*
X890331Y297476D01*
X890040Y297601D01*
X889831Y297893D01*
X889748Y298226D01*
X889831Y298559D01*
X890040Y298851D01*
X890331Y298976D01*
X890623Y298893D01*
X890831Y298684D01*
X890915Y298434D01*
Y298018D01*
X891040Y297643D01*
X891290Y297393D01*
X891581Y297309D01*
X891873Y297393D01*
X892081Y297601D01*
X892206Y297934D01*
X892248Y298226D01*
G01Y301243D02*
X891706Y301326D01*
X891248Y301451D01*
X890831Y301618D01*
X890373Y301826D01*
X889748Y302159D01*
Y300493D01*
G01X889000Y303900D02*
X893000D01*
Y311300D01*
G01X882500Y318933D02*
X884292D01*
X884667Y319100D01*
X884917Y319433D01*
X885000Y319850D01*
X884917Y320267D01*
X884667Y320600D01*
X884292Y320767D01*
X882500D01*
G01X885000Y322950D02*
X882500D01*
X883000Y322450D01*
G01X885000D02*
Y323450D01*
G01X884500Y325133D02*
X884792Y325383D01*
X884958Y325717D01*
X885000Y326092D01*
X884958Y326425D01*
X884750Y326758D01*
X884500Y326967D01*
X884250Y327008D01*
X883958Y326925D01*
X883750Y326633D01*
X883667Y326342D01*
Y325967D01*
G01Y326342D02*
X883542Y326592D01*
X883333Y326800D01*
X883083Y326883D01*
X882833Y326800D01*
X882625Y326592D01*
X882500Y326217D01*
X882542Y325842D01*
X882708Y325467D01*
G01X883958Y328358D02*
X883667Y328650D01*
X883500Y328900D01*
X883417Y329233D01*
X883500Y329525D01*
X883667Y329733D01*
X883917Y329900D01*
X884208Y329942D01*
X884458Y329900D01*
X884708Y329733D01*
X884917Y329483D01*
X885000Y329192D01*
X884917Y328858D01*
X884667Y328567D01*
X884292Y328400D01*
X883875Y328358D01*
X883333Y328442D01*
X883042Y328567D01*
X882750Y328775D01*
X882542Y329067D01*
X882500Y329358D01*
X882583Y329650D01*
X882792Y329858D01*
G01X899750Y322600D02*
Y330600D01*
X887800D01*
Y322600D01*
X899750D01*
G01X887800Y328750D02*
X889800Y326750D01*
X887800Y324750D01*
G01X881617Y343800D02*
Y346300D01*
X882658D01*
X882992Y346175D01*
X883200Y346008D01*
X883283Y345675D01*
X883200Y345342D01*
X882950Y345133D01*
X882658Y345008D01*
X881617D01*
G01X882658D02*
X883283Y343800D01*
G01X884633Y344175D02*
X884883Y343967D01*
X885175Y343842D01*
X885550Y343800D01*
X885925Y343883D01*
X886217Y344050D01*
X886425Y344342D01*
X886467Y344675D01*
X886383Y345008D01*
X886175Y345217D01*
X885883Y345383D01*
X885592Y345425D01*
X885300Y345383D01*
X884925Y345217D01*
X885050Y346300D01*
X886175D01*
G01X887942Y344092D02*
X888233Y343883D01*
X888567Y343800D01*
X888900Y343883D01*
X889192Y344133D01*
X889400Y344508D01*
X889483Y344883D01*
Y345342D01*
X889400Y345717D01*
X889192Y346050D01*
X888942Y346217D01*
X888650Y346300D01*
X888317Y346217D01*
X888067Y346050D01*
X887900Y345800D01*
X887817Y345467D01*
X887900Y345175D01*
X888108Y344883D01*
X888358Y344717D01*
X888650Y344675D01*
X888983Y344758D01*
X889233Y344967D01*
X889483Y345342D01*
G01X891750Y343800D02*
Y346300D01*
X891250Y345800D01*
G01Y343800D02*
X892250D01*
G01X898300Y343600D02*
Y339600D01*
X905700D01*
G01Y343600D02*
Y347600D01*
X898300D01*
G01X881541Y358048D02*
Y360548D01*
X882582D01*
X882916Y360423D01*
X883124Y360256D01*
X883207Y359923D01*
X883124Y359590D01*
X882874Y359381D01*
X882582Y359256D01*
X881541D01*
G01X882582D02*
X883207Y358048D01*
G01X884557Y358423D02*
X884807Y358215D01*
X885099Y358090D01*
X885474Y358048D01*
X885849Y358131D01*
X886141Y358298D01*
X886349Y358590D01*
X886391Y358923D01*
X886307Y359256D01*
X886099Y359465D01*
X885807Y359631D01*
X885516Y359673D01*
X885224Y359631D01*
X884849Y359465D01*
X884974Y360548D01*
X886099D01*
G01X887866Y358340D02*
X888157Y358131D01*
X888491Y358048D01*
X888824Y358131D01*
X889116Y358381D01*
X889324Y358756D01*
X889407Y359131D01*
Y359590D01*
X889324Y359965D01*
X889116Y360298D01*
X888866Y360465D01*
X888574Y360548D01*
X888241Y360465D01*
X887991Y360298D01*
X887824Y360048D01*
X887741Y359715D01*
X887824Y359423D01*
X888032Y359131D01*
X888282Y358965D01*
X888574Y358923D01*
X888907Y359006D01*
X889157Y359215D01*
X889407Y359590D01*
G01X890882Y360131D02*
X891132Y360381D01*
X891424Y360506D01*
X891757Y360548D01*
X892174Y360465D01*
X892466Y360256D01*
X892549Y360006D01*
X892507Y359756D01*
X892341Y359548D01*
X891507Y359131D01*
X891132Y358840D01*
X890882Y358423D01*
X890799Y358048D01*
X892549D01*
G01X905700Y356500D02*
Y360500D01*
X898300D01*
G01X881617Y350800D02*
Y353300D01*
X882658D01*
X882992Y353175D01*
X883200Y353008D01*
X883283Y352675D01*
X883200Y352342D01*
X882950Y352133D01*
X882658Y352008D01*
X881617D01*
G01X882658D02*
X883283Y350800D01*
G01X884633Y351175D02*
X884883Y350967D01*
X885175Y350842D01*
X885550Y350800D01*
X885925Y350883D01*
X886217Y351050D01*
X886425Y351342D01*
X886467Y351675D01*
X886383Y352008D01*
X886175Y352217D01*
X885883Y352383D01*
X885592Y352425D01*
X885300Y352383D01*
X884925Y352217D01*
X885050Y353300D01*
X886175D01*
G01X888650Y350800D02*
X888942Y350842D01*
X889275Y350967D01*
X889483Y351175D01*
X889567Y351467D01*
X889483Y351758D01*
X889233Y352008D01*
X888858Y352133D01*
X888442D01*
X888192Y352217D01*
X887983Y352425D01*
X887900Y352717D01*
X888025Y353008D01*
X888317Y353217D01*
X888650Y353300D01*
X888983Y353217D01*
X889275Y353008D01*
X889400Y352717D01*
X889317Y352425D01*
X889108Y352217D01*
X888858Y352133D01*
X888442D01*
X888067Y352008D01*
X887817Y351758D01*
X887733Y351467D01*
X887817Y351175D01*
X888025Y350967D01*
X888358Y350842D01*
X888650Y350800D01*
G01X890958Y351842D02*
X891250Y352133D01*
X891500Y352300D01*
X891833Y352383D01*
X892125Y352300D01*
X892333Y352133D01*
X892500Y351883D01*
X892542Y351592D01*
X892500Y351342D01*
X892333Y351092D01*
X892083Y350883D01*
X891792Y350800D01*
X891458Y350883D01*
X891167Y351133D01*
X891000Y351508D01*
X890958Y351925D01*
X891042Y352467D01*
X891167Y352758D01*
X891375Y353050D01*
X891667Y353258D01*
X891958Y353300D01*
X892250Y353217D01*
X892458Y353008D01*
G01X905700Y348000D02*
Y352000D01*
X898300D01*
G01X881617Y361800D02*
Y364300D01*
X882658D01*
X882992Y364175D01*
X883200Y364008D01*
X883283Y363675D01*
X883200Y363342D01*
X882950Y363133D01*
X882658Y363008D01*
X881617D01*
G01X882658D02*
X883283Y361800D01*
G01X884633Y362175D02*
X884883Y361967D01*
X885175Y361842D01*
X885550Y361800D01*
X885925Y361883D01*
X886217Y362050D01*
X886425Y362342D01*
X886467Y362675D01*
X886383Y363008D01*
X886175Y363217D01*
X885883Y363383D01*
X885592Y363425D01*
X885300Y363383D01*
X884925Y363217D01*
X885050Y364300D01*
X886175D01*
G01X888650Y361800D02*
X888942Y361842D01*
X889275Y361967D01*
X889483Y362175D01*
X889567Y362467D01*
X889483Y362758D01*
X889233Y363008D01*
X888858Y363133D01*
X888442D01*
X888192Y363217D01*
X887983Y363425D01*
X887900Y363717D01*
X888025Y364008D01*
X888317Y364217D01*
X888650Y364300D01*
X888983Y364217D01*
X889275Y364008D01*
X889400Y363717D01*
X889317Y363425D01*
X889108Y363217D01*
X888858Y363133D01*
X888442D01*
X888067Y363008D01*
X887817Y362758D01*
X887733Y362467D01*
X887817Y362175D01*
X888025Y361967D01*
X888358Y361842D01*
X888650Y361800D01*
G01X890833Y362175D02*
X891083Y361967D01*
X891375Y361842D01*
X891750Y361800D01*
X892125Y361883D01*
X892417Y362050D01*
X892625Y362342D01*
X892667Y362675D01*
X892583Y363008D01*
X892375Y363217D01*
X892083Y363383D01*
X891792Y363425D01*
X891500Y363383D01*
X891125Y363217D01*
X891250Y364300D01*
X892375D01*
G01X898300Y365000D02*
Y361000D01*
X905700D01*
G01X881617Y347300D02*
Y349800D01*
X882658D01*
X882992Y349675D01*
X883200Y349508D01*
X883283Y349175D01*
X883200Y348842D01*
X882950Y348633D01*
X882658Y348508D01*
X881617D01*
G01X882658D02*
X883283Y347300D01*
G01X885550D02*
Y349800D01*
X885050Y349300D01*
G01Y347300D02*
X886050D01*
G01X888567D02*
X888650Y347842D01*
X888775Y348300D01*
X888942Y348717D01*
X889150Y349175D01*
X889483Y349800D01*
X887817D01*
G01X891750Y347300D02*
X892042Y347342D01*
X892375Y347467D01*
X892583Y347675D01*
X892667Y347967D01*
X892583Y348258D01*
X892333Y348508D01*
X891958Y348633D01*
X891542D01*
X891292Y348717D01*
X891083Y348925D01*
X891000Y349217D01*
X891125Y349508D01*
X891417Y349717D01*
X891750Y349800D01*
X892083Y349717D01*
X892375Y349508D01*
X892500Y349217D01*
X892417Y348925D01*
X892208Y348717D01*
X891958Y348633D01*
X891542D01*
X891167Y348508D01*
X890917Y348258D01*
X890833Y347967D01*
X890917Y347675D01*
X891125Y347467D01*
X891458Y347342D01*
X891750Y347300D01*
G01X881617Y354300D02*
Y356800D01*
X882658D01*
X882992Y356675D01*
X883200Y356508D01*
X883283Y356175D01*
X883200Y355842D01*
X882950Y355633D01*
X882658Y355508D01*
X881617D01*
G01X882658D02*
X883283Y354300D01*
G01X885550D02*
Y356800D01*
X885050Y356300D01*
G01Y354300D02*
X886050D01*
G01X888567D02*
X888650Y354842D01*
X888775Y355300D01*
X888942Y355717D01*
X889150Y356175D01*
X889483Y356800D01*
X887817D01*
G01X891667Y354300D02*
X891750Y354842D01*
X891875Y355300D01*
X892042Y355717D01*
X892250Y356175D01*
X892583Y356800D01*
X890917D01*
G01X898300Y356000D02*
Y352000D01*
X905700D01*
G01X880366Y734082D02*
X880116Y734207D01*
X879824Y734290D01*
X879491D01*
X879116Y734165D01*
X878824Y733957D01*
X878616Y733707D01*
X878449Y733290D01*
X878407Y732915D01*
X878491Y732540D01*
X878616Y732290D01*
X878866Y732040D01*
X879157Y731873D01*
X879449Y731790D01*
X879741D01*
X880032Y731873D01*
X880282Y731998D01*
X880491Y732165D01*
G01X883049Y731790D02*
Y734290D01*
X881507Y732498D01*
X883591D01*
G01X885649Y731790D02*
Y734290D01*
X885149Y733790D01*
G01Y731790D02*
X886149D01*
G01X887957Y733873D02*
X888207Y734123D01*
X888499Y734248D01*
X888832Y734290D01*
X889249Y734207D01*
X889541Y733998D01*
X889624Y733748D01*
X889582Y733498D01*
X889416Y733290D01*
X888582Y732873D01*
X888207Y732582D01*
X887957Y732165D01*
X887874Y731790D01*
X889624D01*
G01X892349D02*
Y734290D01*
X890807Y732498D01*
X892891D01*
G01X879406Y754098D02*
X875406D01*
Y746698D01*
G01X907395Y744284D02*
X904895D01*
Y745325D01*
X905020Y745659D01*
X905187Y745867D01*
X905520Y745950D01*
X905853Y745867D01*
X906062Y745617D01*
X906187Y745325D01*
Y744284D01*
G01Y745325D02*
X907395Y745950D01*
G01Y748134D02*
X906853Y748217D01*
X906395Y748342D01*
X905978Y748509D01*
X905520Y748717D01*
X904895Y749050D01*
Y747384D01*
G01X907103Y750609D02*
X907312Y750900D01*
X907395Y751234D01*
X907312Y751567D01*
X907062Y751859D01*
X906687Y752067D01*
X906312Y752150D01*
X905853D01*
X905478Y752067D01*
X905145Y751859D01*
X904978Y751609D01*
X904895Y751317D01*
X904978Y750984D01*
X905145Y750734D01*
X905395Y750567D01*
X905728Y750484D01*
X906020Y750567D01*
X906312Y750775D01*
X906478Y751025D01*
X906520Y751317D01*
X906437Y751650D01*
X906228Y751900D01*
X905853Y752150D01*
G01X907395Y754334D02*
X906853Y754417D01*
X906395Y754542D01*
X905978Y754709D01*
X905520Y754917D01*
X904895Y755250D01*
Y753584D01*
G01X905312Y756725D02*
X905062Y756975D01*
X904937Y757267D01*
X904895Y757600D01*
X904978Y758017D01*
X905187Y758309D01*
X905437Y758392D01*
X905687Y758350D01*
X905895Y758184D01*
X906312Y757350D01*
X906603Y756975D01*
X907020Y756725D01*
X907395Y756642D01*
Y758392D01*
G01X895406Y754098D02*
X891406D01*
Y746698D01*
G01X903253Y744345D02*
X900753D01*
Y745386D01*
X900878Y745720D01*
X901045Y745928D01*
X901378Y746011D01*
X901711Y745928D01*
X901920Y745678D01*
X902045Y745386D01*
Y744345D01*
G01Y745386D02*
X903253Y746011D01*
G01Y748195D02*
X902711Y748278D01*
X902253Y748403D01*
X901836Y748570D01*
X901378Y748778D01*
X900753Y749111D01*
Y747445D01*
G01X902961Y750670D02*
X903170Y750961D01*
X903253Y751295D01*
X903170Y751628D01*
X902920Y751920D01*
X902545Y752128D01*
X902170Y752211D01*
X901711D01*
X901336Y752128D01*
X901003Y751920D01*
X900836Y751670D01*
X900753Y751378D01*
X900836Y751045D01*
X901003Y750795D01*
X901253Y750628D01*
X901586Y750545D01*
X901878Y750628D01*
X902170Y750836D01*
X902336Y751086D01*
X902378Y751378D01*
X902295Y751711D01*
X902086Y751961D01*
X901711Y752211D01*
G01X902878Y753561D02*
X903086Y753811D01*
X903211Y754103D01*
X903253Y754478D01*
X903170Y754853D01*
X903003Y755145D01*
X902711Y755353D01*
X902378Y755395D01*
X902045Y755311D01*
X901836Y755103D01*
X901670Y754811D01*
X901628Y754520D01*
X901670Y754228D01*
X901836Y753853D01*
X900753Y753978D01*
Y755103D01*
G01X903253Y757495D02*
X902711Y757578D01*
X902253Y757703D01*
X901836Y757870D01*
X901378Y758078D01*
X900753Y758411D01*
Y756745D01*
G01X891406Y754098D02*
X887406D01*
Y746698D01*
G01Y754098D02*
X883406D01*
Y746698D01*
G01Y754098D02*
X879406D01*
Y746698D01*
G01X899600Y754000D02*
X895600D01*
Y746600D01*
G01X889406Y782398D02*
Y768398D01*
G01X879776Y813757D02*
X879651Y813507D01*
X879568Y813215D01*
Y812882D01*
X879693Y812507D01*
X879901Y812215D01*
X880151Y812007D01*
X880568Y811840D01*
X880943Y811798D01*
X881318Y811882D01*
X881568Y812007D01*
X881818Y812257D01*
X881985Y812548D01*
X882068Y812840D01*
Y813132D01*
X881985Y813423D01*
X881860Y813673D01*
X881693Y813882D01*
G01X882068Y816440D02*
X879568D01*
X881360Y814898D01*
Y816982D01*
G01X882068Y819040D02*
X879568D01*
X880068Y818540D01*
G01X882068D02*
Y819540D01*
G01X879985Y821348D02*
X879735Y821598D01*
X879610Y821890D01*
X879568Y822223D01*
X879651Y822640D01*
X879860Y822932D01*
X880110Y823015D01*
X880360Y822973D01*
X880568Y822807D01*
X880985Y821973D01*
X881276Y821598D01*
X881693Y821348D01*
X882068Y821265D01*
Y823015D01*
G01Y825240D02*
X882026Y825532D01*
X881901Y825865D01*
X881693Y826073D01*
X881401Y826157D01*
X881110Y826073D01*
X880860Y825823D01*
X880735Y825448D01*
Y825032D01*
X880651Y824782D01*
X880443Y824573D01*
X880151Y824490D01*
X879860Y824615D01*
X879651Y824907D01*
X879568Y825240D01*
X879651Y825573D01*
X879860Y825865D01*
X880151Y825990D01*
X880443Y825907D01*
X880651Y825698D01*
X880735Y825448D01*
Y825032D01*
X880860Y824657D01*
X881110Y824407D01*
X881401Y824323D01*
X881693Y824407D01*
X881901Y824615D01*
X882026Y824948D01*
X882068Y825240D01*
G01X884276Y798348D02*
X888276D01*
Y805748D01*
G01X904207Y788588D02*
X901707D01*
Y789629D01*
X901832Y789963D01*
X901999Y790171D01*
X902332Y790254D01*
X902665Y790171D01*
X902874Y789921D01*
X902999Y789629D01*
Y788588D01*
G01Y789629D02*
X904207Y790254D01*
G01Y792438D02*
X903665Y792521D01*
X903207Y792646D01*
X902790Y792813D01*
X902332Y793021D01*
X901707Y793354D01*
Y791688D01*
G01X903915Y794913D02*
X904124Y795204D01*
X904207Y795538D01*
X904124Y795871D01*
X903874Y796163D01*
X903499Y796371D01*
X903124Y796454D01*
X902665D01*
X902290Y796371D01*
X901957Y796163D01*
X901790Y795913D01*
X901707Y795621D01*
X901790Y795288D01*
X901957Y795038D01*
X902207Y794871D01*
X902540Y794788D01*
X902832Y794871D01*
X903124Y795079D01*
X903290Y795329D01*
X903332Y795621D01*
X903249Y795954D01*
X903040Y796204D01*
X902665Y796454D01*
G01X903165Y797929D02*
X902874Y798221D01*
X902707Y798471D01*
X902624Y798804D01*
X902707Y799096D01*
X902874Y799304D01*
X903124Y799471D01*
X903415Y799513D01*
X903665Y799471D01*
X903915Y799304D01*
X904124Y799054D01*
X904207Y798763D01*
X904124Y798429D01*
X903874Y798138D01*
X903499Y797971D01*
X903082Y797929D01*
X902540Y798013D01*
X902249Y798138D01*
X901957Y798346D01*
X901749Y798638D01*
X901707Y798929D01*
X901790Y799221D01*
X901999Y799429D01*
G01X902124Y801029D02*
X901874Y801279D01*
X901749Y801571D01*
X901707Y801904D01*
X901790Y802321D01*
X901999Y802613D01*
X902249Y802696D01*
X902499Y802654D01*
X902707Y802488D01*
X903124Y801654D01*
X903415Y801279D01*
X903832Y801029D01*
X904207Y800946D01*
Y802696D01*
G01X888406Y795698D02*
X892406D01*
Y803098D01*
G01X875949Y798300D02*
X879949D01*
Y805700D01*
G01X908207Y788588D02*
X905707D01*
Y789629D01*
X905832Y789963D01*
X905999Y790171D01*
X906332Y790254D01*
X906665Y790171D01*
X906874Y789921D01*
X906999Y789629D01*
Y788588D01*
G01Y789629D02*
X908207Y790254D01*
G01Y792438D02*
X907665Y792521D01*
X907207Y792646D01*
X906790Y792813D01*
X906332Y793021D01*
X905707Y793354D01*
Y791688D01*
G01X907915Y794913D02*
X908124Y795204D01*
X908207Y795538D01*
X908124Y795871D01*
X907874Y796163D01*
X907499Y796371D01*
X907124Y796454D01*
X906665D01*
X906290Y796371D01*
X905957Y796163D01*
X905790Y795913D01*
X905707Y795621D01*
X905790Y795288D01*
X905957Y795038D01*
X906207Y794871D01*
X906540Y794788D01*
X906832Y794871D01*
X907124Y795079D01*
X907290Y795329D01*
X907332Y795621D01*
X907249Y795954D01*
X907040Y796204D01*
X906665Y796454D01*
G01X908207Y799221D02*
X905707D01*
X907499Y797679D01*
Y799763D01*
G01X908207Y801738D02*
X907665Y801821D01*
X907207Y801946D01*
X906790Y802113D01*
X906332Y802321D01*
X905707Y802654D01*
Y800988D01*
G01X892406Y795698D02*
X896406D01*
Y803098D01*
G01X880049Y798300D02*
X884049D01*
Y805700D01*
G01X896406Y795698D02*
X900406D01*
Y803098D01*
G01X893405Y807698D02*
Y810198D01*
X894446D01*
X894780Y810073D01*
X894988Y809906D01*
X895071Y809573D01*
X894988Y809240D01*
X894738Y809031D01*
X894446Y808906D01*
X893405D01*
G01X894446D02*
X895071Y807698D01*
G01X896630Y807990D02*
X896921Y807781D01*
X897255Y807698D01*
X897588Y807781D01*
X897880Y808031D01*
X898088Y808406D01*
X898171Y808781D01*
Y809240D01*
X898088Y809615D01*
X897880Y809948D01*
X897630Y810115D01*
X897338Y810198D01*
X897005Y810115D01*
X896755Y809948D01*
X896588Y809698D01*
X896505Y809365D01*
X896588Y809073D01*
X896796Y808781D01*
X897046Y808615D01*
X897338Y808573D01*
X897671Y808656D01*
X897921Y808865D01*
X898171Y809240D01*
G01X900438Y810198D02*
X900105Y810115D01*
X899855Y809906D01*
X899688Y809656D01*
X899563Y809323D01*
X899521Y808948D01*
X899563Y808573D01*
X899688Y808240D01*
X899855Y807990D01*
X900105Y807781D01*
X900438Y807698D01*
X900771Y807781D01*
X901021Y807990D01*
X901188Y808240D01*
X901313Y808573D01*
X901355Y808948D01*
X901313Y809323D01*
X901188Y809656D01*
X901021Y809906D01*
X900771Y810115D01*
X900438Y810198D01*
G01X904038Y807698D02*
Y810198D01*
X902496Y808406D01*
X904580D01*
G01X906638Y807698D02*
Y810198D01*
X906138Y809698D01*
G01Y807698D02*
X907138D01*
G01X891870Y806230D02*
Y810230D01*
X884470D01*
G01X930536Y-20257D02*
Y-18257D01*
G01X939936Y-20257D02*
Y-18257D01*
X930536D01*
G01X931700Y58100D02*
X967100D01*
Y30100D01*
X931700D01*
Y58100D01*
G01X911175Y26209D02*
Y28709D01*
X912216D01*
X912550Y28584D01*
X912758Y28417D01*
X912841Y28084D01*
X912758Y27751D01*
X912508Y27542D01*
X912216Y27417D01*
X911175D01*
G01X912216D02*
X912841Y26209D01*
G01X915108D02*
Y28709D01*
X914608Y28209D01*
G01Y26209D02*
X915608D01*
G01X918125D02*
X918208Y26751D01*
X918333Y27209D01*
X918500Y27626D01*
X918708Y28084D01*
X919041Y28709D01*
X917375D01*
G01X921808Y26209D02*
Y28709D01*
X920266Y26917D01*
X922350D01*
G01X925270Y25540D02*
Y21540D01*
X932670D01*
G01X926260Y29887D02*
X923760D01*
Y30928D01*
X923885Y31262D01*
X924052Y31470D01*
X924385Y31553D01*
X924718Y31470D01*
X924927Y31220D01*
X925052Y30928D01*
Y29887D01*
G01Y30928D02*
X926260Y31553D01*
G01Y33820D02*
X923760D01*
X924260Y33320D01*
G01X926260D02*
Y34320D01*
G01Y36837D02*
X925718Y36920D01*
X925260Y37045D01*
X924843Y37212D01*
X924385Y37420D01*
X923760Y37753D01*
Y36087D01*
G01X925760Y39103D02*
X926052Y39353D01*
X926218Y39687D01*
X926260Y40062D01*
X926218Y40395D01*
X926010Y40728D01*
X925760Y40937D01*
X925510Y40978D01*
X925218Y40895D01*
X925010Y40603D01*
X924927Y40312D01*
Y39937D01*
G01Y40312D02*
X924802Y40562D01*
X924593Y40770D01*
X924343Y40853D01*
X924093Y40770D01*
X923885Y40562D01*
X923760Y40187D01*
X923802Y39812D01*
X923968Y39437D01*
G01X940000Y28700D02*
X936000D01*
Y21300D01*
G01X928468Y33330D02*
X928343Y33080D01*
X928260Y32788D01*
Y32455D01*
X928385Y32080D01*
X928593Y31788D01*
X928843Y31580D01*
X929260Y31413D01*
X929635Y31371D01*
X930010Y31455D01*
X930260Y31580D01*
X930510Y31830D01*
X930677Y32121D01*
X930760Y32413D01*
Y32705D01*
X930677Y32996D01*
X930552Y33246D01*
X930385Y33455D01*
G01X930260Y34596D02*
X930552Y34846D01*
X930718Y35180D01*
X930760Y35555D01*
X930718Y35888D01*
X930510Y36221D01*
X930260Y36430D01*
X930010Y36471D01*
X929718Y36388D01*
X929510Y36096D01*
X929427Y35805D01*
Y35430D01*
G01Y35805D02*
X929302Y36055D01*
X929093Y36263D01*
X928843Y36346D01*
X928593Y36263D01*
X928385Y36055D01*
X928260Y35680D01*
X928302Y35305D01*
X928468Y34930D01*
G01X928677Y37821D02*
X928427Y38071D01*
X928302Y38363D01*
X928260Y38696D01*
X928343Y39113D01*
X928552Y39405D01*
X928802Y39488D01*
X929052Y39446D01*
X929260Y39280D01*
X929677Y38446D01*
X929968Y38071D01*
X930385Y37821D01*
X930760Y37738D01*
Y39488D01*
G01X928677Y40921D02*
X928427Y41171D01*
X928302Y41463D01*
X928260Y41796D01*
X928343Y42213D01*
X928552Y42505D01*
X928802Y42588D01*
X929052Y42546D01*
X929260Y42380D01*
X929677Y41546D01*
X929968Y41171D01*
X930385Y40921D01*
X930760Y40838D01*
Y42588D01*
G01X917208Y48267D02*
X917083Y48017D01*
X917000Y47725D01*
Y47392D01*
X917125Y47017D01*
X917333Y46725D01*
X917583Y46517D01*
X918000Y46350D01*
X918375Y46308D01*
X918750Y46392D01*
X919000Y46517D01*
X919250Y46767D01*
X919417Y47058D01*
X919500Y47350D01*
Y47642D01*
X919417Y47933D01*
X919292Y48183D01*
X919125Y48392D01*
G01X919500Y50950D02*
X917000D01*
X918792Y49408D01*
Y51492D01*
G01X918458Y52758D02*
X918167Y53050D01*
X918000Y53300D01*
X917917Y53633D01*
X918000Y53925D01*
X918167Y54133D01*
X918417Y54300D01*
X918708Y54342D01*
X918958Y54300D01*
X919208Y54133D01*
X919417Y53883D01*
X919500Y53592D01*
X919417Y53258D01*
X919167Y52967D01*
X918792Y52800D01*
X918375Y52758D01*
X917833Y52842D01*
X917542Y52967D01*
X917250Y53175D01*
X917042Y53467D01*
X917000Y53758D01*
X917083Y54050D01*
X917292Y54258D01*
G01X919125Y55733D02*
X919333Y55983D01*
X919458Y56275D01*
X919500Y56650D01*
X919417Y57025D01*
X919250Y57317D01*
X918958Y57525D01*
X918625Y57567D01*
X918292Y57483D01*
X918083Y57275D01*
X917917Y56983D01*
X917875Y56692D01*
X917917Y56400D01*
X918083Y56025D01*
X917000Y56150D01*
Y57275D01*
G01X911519Y42292D02*
Y44792D01*
X912560D01*
X912894Y44667D01*
X913102Y44500D01*
X913185Y44167D01*
X913102Y43834D01*
X912852Y43625D01*
X912560Y43500D01*
X911519D01*
G01X912560D02*
X913185Y42292D01*
G01X914744Y42584D02*
X915035Y42375D01*
X915369Y42292D01*
X915702Y42375D01*
X915994Y42625D01*
X916202Y43000D01*
X916285Y43375D01*
Y43834D01*
X916202Y44209D01*
X915994Y44542D01*
X915744Y44709D01*
X915452Y44792D01*
X915119Y44709D01*
X914869Y44542D01*
X914702Y44292D01*
X914619Y43959D01*
X914702Y43667D01*
X914910Y43375D01*
X915160Y43209D01*
X915452Y43167D01*
X915785Y43250D01*
X916035Y43459D01*
X916285Y43834D01*
G01X917635Y42667D02*
X917885Y42459D01*
X918177Y42334D01*
X918552Y42292D01*
X918927Y42375D01*
X919219Y42542D01*
X919427Y42834D01*
X919469Y43167D01*
X919385Y43500D01*
X919177Y43709D01*
X918885Y43875D01*
X918594Y43917D01*
X918302Y43875D01*
X917927Y43709D01*
X918052Y44792D01*
X919177D01*
G01X920860Y44375D02*
X921110Y44625D01*
X921402Y44750D01*
X921735Y44792D01*
X922152Y44709D01*
X922444Y44500D01*
X922527Y44250D01*
X922485Y44000D01*
X922319Y43792D01*
X921485Y43375D01*
X921110Y43084D01*
X920860Y42667D01*
X920777Y42292D01*
X922527D01*
G01X921886Y63228D02*
X921844Y62895D01*
X921678Y62603D01*
X921428Y62353D01*
X921136Y62186D01*
X920803Y62103D01*
X920469D01*
X920136Y62186D01*
X919844Y62353D01*
X919594Y62603D01*
X919428Y62895D01*
X919386Y63228D01*
X919428Y63561D01*
X919594Y63853D01*
X919844Y64103D01*
X920136Y64270D01*
X920469Y64353D01*
X920803D01*
X921136Y64270D01*
X921428Y64103D01*
X921678Y63853D01*
X921844Y63561D01*
X921886Y63228D01*
G01X921219Y63561D02*
X921886Y64061D01*
G01X919803Y65536D02*
X919553Y65786D01*
X919428Y66078D01*
X919386Y66411D01*
X919469Y66828D01*
X919678Y67120D01*
X919928Y67203D01*
X920178Y67161D01*
X920386Y66995D01*
X920803Y66161D01*
X921094Y65786D01*
X921511Y65536D01*
X921886Y65453D01*
Y67203D01*
G01X919803Y68636D02*
X919553Y68886D01*
X919428Y69178D01*
X919386Y69511D01*
X919469Y69928D01*
X919678Y70220D01*
X919928Y70303D01*
X920178Y70261D01*
X920386Y70095D01*
X920803Y69261D01*
X921094Y68886D01*
X921511Y68636D01*
X921886Y68553D01*
Y70303D01*
G01X932100Y60900D02*
X946100D01*
G01X932100Y73900D02*
Y60900D01*
G01X946100Y73900D02*
X932100D01*
G01X941108Y77637D02*
X941441Y77429D01*
X941816Y77304D01*
X942150D01*
X942483Y77429D01*
X942733Y77637D01*
X942858Y77929D01*
X942775Y78221D01*
X942566Y78471D01*
X942191Y78637D01*
X941691Y78721D01*
X941400Y78887D01*
X941275Y79179D01*
X941358Y79471D01*
X941566Y79679D01*
X941858Y79804D01*
X942150D01*
X942441Y79721D01*
X942691Y79512D01*
G01X944250Y77304D02*
Y79804D01*
X945291D01*
X945625Y79679D01*
X945833Y79512D01*
X945916Y79179D01*
X945833Y78846D01*
X945583Y78637D01*
X945291Y78512D01*
X944250D01*
G01X945291D02*
X945916Y77304D01*
G01X948100D02*
X948183Y77846D01*
X948308Y78304D01*
X948475Y78721D01*
X948683Y79179D01*
X949016Y79804D01*
X947350D01*
G01X950491Y79387D02*
X950741Y79637D01*
X951033Y79762D01*
X951366Y79804D01*
X951783Y79721D01*
X952075Y79512D01*
X952158Y79262D01*
X952116Y79012D01*
X951950Y78804D01*
X951116Y78387D01*
X950741Y78096D01*
X950491Y77679D01*
X950408Y77304D01*
X952158D01*
G01X954383Y79804D02*
X954050Y79721D01*
X953800Y79512D01*
X953633Y79262D01*
X953508Y78929D01*
X953466Y78554D01*
X953508Y78179D01*
X953633Y77846D01*
X953800Y77596D01*
X954050Y77387D01*
X954383Y77304D01*
X954716Y77387D01*
X954966Y77596D01*
X955133Y77846D01*
X955258Y78179D01*
X955300Y78554D01*
X955258Y78929D01*
X955133Y79262D01*
X954966Y79512D01*
X954716Y79721D01*
X954383Y79804D01*
G01X934300Y76600D02*
Y80600D01*
X926900D01*
G01X912500Y97017D02*
X910000D01*
Y98058D01*
X910125Y98392D01*
X910292Y98600D01*
X910625Y98683D01*
X910958Y98600D01*
X911167Y98350D01*
X911292Y98058D01*
Y97017D01*
G01Y98058D02*
X912500Y98683D01*
G01Y100950D02*
X912458Y101242D01*
X912333Y101575D01*
X912125Y101783D01*
X911833Y101867D01*
X911542Y101783D01*
X911292Y101533D01*
X911167Y101158D01*
Y100742D01*
X911083Y100492D01*
X910875Y100283D01*
X910583Y100200D01*
X910292Y100325D01*
X910083Y100617D01*
X910000Y100950D01*
X910083Y101283D01*
X910292Y101575D01*
X910583Y101700D01*
X910875Y101617D01*
X911083Y101408D01*
X911167Y101158D01*
Y100742D01*
X911292Y100367D01*
X911542Y100117D01*
X911833Y100033D01*
X912125Y100117D01*
X912333Y100325D01*
X912458Y100658D01*
X912500Y100950D01*
G01X910417Y103258D02*
X910167Y103508D01*
X910042Y103800D01*
X910000Y104133D01*
X910083Y104550D01*
X910292Y104842D01*
X910542Y104925D01*
X910792Y104883D01*
X911000Y104717D01*
X911417Y103883D01*
X911708Y103508D01*
X912125Y103258D01*
X912500Y103175D01*
Y104925D01*
G01X910000Y107150D02*
X910083Y106817D01*
X910292Y106567D01*
X910542Y106400D01*
X910875Y106275D01*
X911250Y106233D01*
X911625Y106275D01*
X911958Y106400D01*
X912208Y106567D01*
X912417Y106817D01*
X912500Y107150D01*
X912417Y107483D01*
X912208Y107733D01*
X911958Y107900D01*
X911625Y108025D01*
X911250Y108067D01*
X910875Y108025D01*
X910542Y107900D01*
X910292Y107733D01*
X910083Y107483D01*
X910000Y107150D01*
G01X913000Y95200D02*
X909000D01*
Y87800D01*
G01X917000Y97017D02*
X914500D01*
Y98058D01*
X914625Y98392D01*
X914792Y98600D01*
X915125Y98683D01*
X915458Y98600D01*
X915667Y98350D01*
X915792Y98058D01*
Y97017D01*
G01Y98058D02*
X917000Y98683D01*
G01Y100950D02*
X916958Y101242D01*
X916833Y101575D01*
X916625Y101783D01*
X916333Y101867D01*
X916042Y101783D01*
X915792Y101533D01*
X915667Y101158D01*
Y100742D01*
X915583Y100492D01*
X915375Y100283D01*
X915083Y100200D01*
X914792Y100325D01*
X914583Y100617D01*
X914500Y100950D01*
X914583Y101283D01*
X914792Y101575D01*
X915083Y101700D01*
X915375Y101617D01*
X915583Y101408D01*
X915667Y101158D01*
Y100742D01*
X915792Y100367D01*
X916042Y100117D01*
X916333Y100033D01*
X916625Y100117D01*
X916833Y100325D01*
X916958Y100658D01*
X917000Y100950D01*
G01Y104050D02*
X914500D01*
X915000Y103550D01*
G01X917000D02*
Y104550D01*
G01Y107150D02*
X916958Y107442D01*
X916833Y107775D01*
X916625Y107983D01*
X916333Y108067D01*
X916042Y107983D01*
X915792Y107733D01*
X915667Y107358D01*
Y106942D01*
X915583Y106692D01*
X915375Y106483D01*
X915083Y106400D01*
X914792Y106525D01*
X914583Y106817D01*
X914500Y107150D01*
X914583Y107483D01*
X914792Y107775D01*
X915083Y107900D01*
X915375Y107817D01*
X915583Y107608D01*
X915667Y107358D01*
Y106942D01*
X915792Y106567D01*
X916042Y106317D01*
X916333Y106233D01*
X916625Y106317D01*
X916833Y106525D01*
X916958Y106858D01*
X917000Y107150D01*
G01X917500Y95200D02*
X913500D01*
Y87800D01*
G01X921500Y97017D02*
X919000D01*
Y98058D01*
X919125Y98392D01*
X919292Y98600D01*
X919625Y98683D01*
X919958Y98600D01*
X920167Y98350D01*
X920292Y98058D01*
Y97017D01*
G01Y98058D02*
X921500Y98683D01*
G01Y100950D02*
X921458Y101242D01*
X921333Y101575D01*
X921125Y101783D01*
X920833Y101867D01*
X920542Y101783D01*
X920292Y101533D01*
X920167Y101158D01*
Y100742D01*
X920083Y100492D01*
X919875Y100283D01*
X919583Y100200D01*
X919292Y100325D01*
X919083Y100617D01*
X919000Y100950D01*
X919083Y101283D01*
X919292Y101575D01*
X919583Y101700D01*
X919875Y101617D01*
X920083Y101408D01*
X920167Y101158D01*
Y100742D01*
X920292Y100367D01*
X920542Y100117D01*
X920833Y100033D01*
X921125Y100117D01*
X921333Y100325D01*
X921458Y100658D01*
X921500Y100950D01*
G01Y104050D02*
X919000D01*
X919500Y103550D01*
G01X921500D02*
Y104550D01*
G01X920458Y106358D02*
X920167Y106650D01*
X920000Y106900D01*
X919917Y107233D01*
X920000Y107525D01*
X920167Y107733D01*
X920417Y107900D01*
X920708Y107942D01*
X920958Y107900D01*
X921208Y107733D01*
X921417Y107483D01*
X921500Y107192D01*
X921417Y106858D01*
X921167Y106567D01*
X920792Y106400D01*
X920375Y106358D01*
X919833Y106442D01*
X919542Y106567D01*
X919250Y106775D01*
X919042Y107067D01*
X919000Y107358D01*
X919083Y107650D01*
X919292Y107858D01*
G01X922000Y95200D02*
X918000D01*
Y87800D01*
G01X935000Y98917D02*
X932500D01*
Y99958D01*
X932625Y100292D01*
X932792Y100500D01*
X933125Y100583D01*
X933458Y100500D01*
X933667Y100250D01*
X933792Y99958D01*
Y98917D01*
G01Y99958D02*
X935000Y100583D01*
G01Y102850D02*
X934958Y103142D01*
X934833Y103475D01*
X934625Y103683D01*
X934333Y103767D01*
X934042Y103683D01*
X933792Y103433D01*
X933667Y103058D01*
Y102642D01*
X933583Y102392D01*
X933375Y102183D01*
X933083Y102100D01*
X932792Y102225D01*
X932583Y102517D01*
X932500Y102850D01*
X932583Y103183D01*
X932792Y103475D01*
X933083Y103600D01*
X933375Y103517D01*
X933583Y103308D01*
X933667Y103058D01*
Y102642D01*
X933792Y102267D01*
X934042Y102017D01*
X934333Y101933D01*
X934625Y102017D01*
X934833Y102225D01*
X934958Y102558D01*
X935000Y102850D01*
G01Y105950D02*
X932500D01*
X933000Y105450D01*
G01X935000D02*
Y106450D01*
G01Y109550D02*
X932500D01*
X934292Y108008D01*
Y110092D01*
G01X935500Y95200D02*
X931500D01*
Y87800D01*
G01X930500Y97417D02*
X928000D01*
Y98458D01*
X928125Y98792D01*
X928292Y99000D01*
X928625Y99083D01*
X928958Y99000D01*
X929167Y98750D01*
X929292Y98458D01*
Y97417D01*
G01Y98458D02*
X930500Y99083D01*
G01Y101350D02*
X930458Y101642D01*
X930333Y101975D01*
X930125Y102183D01*
X929833Y102267D01*
X929542Y102183D01*
X929292Y101933D01*
X929167Y101558D01*
Y101142D01*
X929083Y100892D01*
X928875Y100683D01*
X928583Y100600D01*
X928292Y100725D01*
X928083Y101017D01*
X928000Y101350D01*
X928083Y101683D01*
X928292Y101975D01*
X928583Y102100D01*
X928875Y102017D01*
X929083Y101808D01*
X929167Y101558D01*
Y101142D01*
X929292Y100767D01*
X929542Y100517D01*
X929833Y100433D01*
X930125Y100517D01*
X930333Y100725D01*
X930458Y101058D01*
X930500Y101350D01*
G01Y104450D02*
X928000D01*
X928500Y103950D01*
G01X930500D02*
Y104950D01*
G01X928417Y106758D02*
X928167Y107008D01*
X928042Y107300D01*
X928000Y107633D01*
X928083Y108050D01*
X928292Y108342D01*
X928542Y108425D01*
X928792Y108383D01*
X929000Y108217D01*
X929417Y107383D01*
X929708Y107008D01*
X930125Y106758D01*
X930500Y106675D01*
Y108425D01*
G01X931000Y95200D02*
X927000D01*
Y87800D01*
G01X926000Y97017D02*
X923500D01*
Y98058D01*
X923625Y98392D01*
X923792Y98600D01*
X924125Y98683D01*
X924458Y98600D01*
X924667Y98350D01*
X924792Y98058D01*
Y97017D01*
G01Y98058D02*
X926000Y98683D01*
G01Y100950D02*
X925958Y101242D01*
X925833Y101575D01*
X925625Y101783D01*
X925333Y101867D01*
X925042Y101783D01*
X924792Y101533D01*
X924667Y101158D01*
Y100742D01*
X924583Y100492D01*
X924375Y100283D01*
X924083Y100200D01*
X923792Y100325D01*
X923583Y100617D01*
X923500Y100950D01*
X923583Y101283D01*
X923792Y101575D01*
X924083Y101700D01*
X924375Y101617D01*
X924583Y101408D01*
X924667Y101158D01*
Y100742D01*
X924792Y100367D01*
X925042Y100117D01*
X925333Y100033D01*
X925625Y100117D01*
X925833Y100325D01*
X925958Y100658D01*
X926000Y100950D01*
G01X923500Y104050D02*
X923583Y103717D01*
X923792Y103467D01*
X924042Y103300D01*
X924375Y103175D01*
X924750Y103133D01*
X925125Y103175D01*
X925458Y103300D01*
X925708Y103467D01*
X925917Y103717D01*
X926000Y104050D01*
X925917Y104383D01*
X925708Y104633D01*
X925458Y104800D01*
X925125Y104925D01*
X924750Y104967D01*
X924375Y104925D01*
X924042Y104800D01*
X923792Y104633D01*
X923583Y104383D01*
X923500Y104050D01*
G01X926000Y107150D02*
X925958Y107442D01*
X925833Y107775D01*
X925625Y107983D01*
X925333Y108067D01*
X925042Y107983D01*
X924792Y107733D01*
X924667Y107358D01*
Y106942D01*
X924583Y106692D01*
X924375Y106483D01*
X924083Y106400D01*
X923792Y106525D01*
X923583Y106817D01*
X923500Y107150D01*
X923583Y107483D01*
X923792Y107775D01*
X924083Y107900D01*
X924375Y107817D01*
X924583Y107608D01*
X924667Y107358D01*
Y106942D01*
X924792Y106567D01*
X925042Y106317D01*
X925333Y106233D01*
X925625Y106317D01*
X925833Y106525D01*
X925958Y106858D01*
X926000Y107150D01*
G01X926500Y95200D02*
X922500D01*
Y87800D01*
G01X939500Y97017D02*
X937000D01*
Y98058D01*
X937125Y98392D01*
X937292Y98600D01*
X937625Y98683D01*
X937958Y98600D01*
X938167Y98350D01*
X938292Y98058D01*
Y97017D01*
G01Y98058D02*
X939500Y98683D01*
G01Y100867D02*
X938958Y100950D01*
X938500Y101075D01*
X938083Y101242D01*
X937625Y101450D01*
X937000Y101783D01*
Y100117D01*
G01X939208Y103342D02*
X939417Y103633D01*
X939500Y103967D01*
X939417Y104300D01*
X939167Y104592D01*
X938792Y104800D01*
X938417Y104883D01*
X937958D01*
X937583Y104800D01*
X937250Y104592D01*
X937083Y104342D01*
X937000Y104050D01*
X937083Y103717D01*
X937250Y103467D01*
X937500Y103300D01*
X937833Y103217D01*
X938125Y103300D01*
X938417Y103508D01*
X938583Y103758D01*
X938625Y104050D01*
X938542Y104383D01*
X938333Y104633D01*
X937958Y104883D01*
G01X938458Y106358D02*
X938167Y106650D01*
X938000Y106900D01*
X937917Y107233D01*
X938000Y107525D01*
X938167Y107733D01*
X938417Y107900D01*
X938708Y107942D01*
X938958Y107900D01*
X939208Y107733D01*
X939417Y107483D01*
X939500Y107192D01*
X939417Y106858D01*
X939167Y106567D01*
X938792Y106400D01*
X938375Y106358D01*
X937833Y106442D01*
X937542Y106567D01*
X937250Y106775D01*
X937042Y107067D01*
X937000Y107358D01*
X937083Y107650D01*
X937292Y107858D01*
G01X940000Y95200D02*
X936000D01*
Y87800D01*
G01X940500D02*
X944500D01*
Y95200D01*
G01X932750Y325000D02*
X933042Y325042D01*
X933375Y325167D01*
X933583Y325375D01*
X933667Y325667D01*
X933583Y325958D01*
X933333Y326208D01*
X932958Y326333D01*
X932542D01*
X932292Y326417D01*
X932083Y326625D01*
X932000Y326917D01*
X932125Y327208D01*
X932417Y327417D01*
X932750Y327500D01*
X933083Y327417D01*
X933375Y327208D01*
X933500Y326917D01*
X933417Y326625D01*
X933208Y326417D01*
X932958Y326333D01*
X932542D01*
X932167Y326208D01*
X931917Y325958D01*
X931833Y325667D01*
X931917Y325375D01*
X932125Y325167D01*
X932458Y325042D01*
X932750Y325000D01*
G01X934975D02*
X936725Y327500D01*
G01X934975D02*
X936725Y325000D01*
G01X939450D02*
Y327500D01*
X937908Y325708D01*
X939992D01*
G01X933250Y340000D02*
Y342500D01*
X931708Y340708D01*
X933792D01*
G01X934975Y340000D02*
X936725Y342500D01*
G01X934975D02*
X936725Y340000D01*
G01X939450D02*
Y342500D01*
X937908Y340708D01*
X939992D01*
G01X931958Y337083D02*
X932208Y337333D01*
X932500Y337458D01*
X932833Y337500D01*
X933250Y337417D01*
X933542Y337208D01*
X933625Y336958D01*
X933583Y336708D01*
X933417Y336500D01*
X932583Y336083D01*
X932208Y335792D01*
X931958Y335375D01*
X931875Y335000D01*
X933625D01*
G01X934975D02*
X936725Y337500D01*
G01X934975D02*
X936725Y335000D01*
G01X938950D02*
Y337500D01*
X938450Y337000D01*
G01Y335000D02*
X939450D01*
G01X941258Y336042D02*
X941550Y336333D01*
X941800Y336500D01*
X942133Y336583D01*
X942425Y336500D01*
X942633Y336333D01*
X942800Y336083D01*
X942842Y335792D01*
X942800Y335542D01*
X942633Y335292D01*
X942383Y335083D01*
X942092Y335000D01*
X941758Y335083D01*
X941467Y335333D01*
X941300Y335708D01*
X941258Y336125D01*
X941342Y336667D01*
X941467Y336958D01*
X941675Y337250D01*
X941967Y337458D01*
X942258Y337500D01*
X942550Y337417D01*
X942758Y337208D01*
G01X933250Y330000D02*
Y332500D01*
X931708Y330708D01*
X933792D01*
G01X934975Y330000D02*
X936725Y332500D01*
G01X934975D02*
X936725Y330000D01*
G01X938950D02*
X939242Y330042D01*
X939575Y330167D01*
X939783Y330375D01*
X939867Y330667D01*
X939783Y330958D01*
X939533Y331208D01*
X939158Y331333D01*
X938742D01*
X938492Y331417D01*
X938283Y331625D01*
X938200Y331917D01*
X938325Y332208D01*
X938617Y332417D01*
X938950Y332500D01*
X939283Y332417D01*
X939575Y332208D01*
X939700Y331917D01*
X939617Y331625D01*
X939408Y331417D01*
X939158Y331333D01*
X938742D01*
X938367Y331208D01*
X938117Y330958D01*
X938033Y330667D01*
X938117Y330375D01*
X938325Y330167D01*
X938658Y330042D01*
X938950Y330000D01*
G01X909208Y327767D02*
X909083Y327517D01*
X909000Y327225D01*
Y326892D01*
X909125Y326517D01*
X909333Y326225D01*
X909583Y326017D01*
X910000Y325850D01*
X910375Y325808D01*
X910750Y325892D01*
X911000Y326017D01*
X911250Y326267D01*
X911417Y326558D01*
X911500Y326850D01*
Y327142D01*
X911417Y327433D01*
X911292Y327683D01*
X911125Y327892D01*
G01X911000Y329033D02*
X911292Y329283D01*
X911458Y329617D01*
X911500Y329992D01*
X911458Y330325D01*
X911250Y330658D01*
X911000Y330867D01*
X910750Y330908D01*
X910458Y330825D01*
X910250Y330533D01*
X910167Y330242D01*
Y329867D01*
G01Y330242D02*
X910042Y330492D01*
X909833Y330700D01*
X909583Y330783D01*
X909333Y330700D01*
X909125Y330492D01*
X909000Y330117D01*
X909042Y329742D01*
X909208Y329367D01*
G01X909417Y332258D02*
X909167Y332508D01*
X909042Y332800D01*
X909000Y333133D01*
X909083Y333550D01*
X909292Y333842D01*
X909542Y333925D01*
X909792Y333883D01*
X910000Y333717D01*
X910417Y332883D01*
X910708Y332508D01*
X911125Y332258D01*
X911500Y332175D01*
Y333925D01*
G01Y336150D02*
X911458Y336442D01*
X911333Y336775D01*
X911125Y336983D01*
X910833Y337067D01*
X910542Y336983D01*
X910292Y336733D01*
X910167Y336358D01*
Y335942D01*
X910083Y335692D01*
X909875Y335483D01*
X909583Y335400D01*
X909292Y335525D01*
X909083Y335817D01*
X909000Y336150D01*
X909083Y336483D01*
X909292Y336775D01*
X909583Y336900D01*
X909875Y336817D01*
X910083Y336608D01*
X910167Y336358D01*
Y335942D01*
X910292Y335567D01*
X910542Y335317D01*
X910833Y335233D01*
X911125Y335317D01*
X911333Y335525D01*
X911458Y335858D01*
X911500Y336150D01*
G01X931667Y355000D02*
Y357500D01*
X932750Y355417D01*
X933833Y357500D01*
Y355000D01*
G01X935850D02*
X935517Y355042D01*
X935225Y355208D01*
X934975Y355458D01*
X934808Y355750D01*
X934725Y356083D01*
Y356417D01*
X934808Y356750D01*
X934975Y357042D01*
X935225Y357292D01*
X935517Y357458D01*
X935850Y357500D01*
X936183Y357458D01*
X936475Y357292D01*
X936725Y357042D01*
X936892Y356750D01*
X936975Y356417D01*
Y356083D01*
X936892Y355750D01*
X936725Y355458D01*
X936475Y355208D01*
X936183Y355042D01*
X935850Y355000D01*
G01X938033D02*
Y357500D01*
X938867D01*
X939200Y357375D01*
X939450Y357208D01*
X939658Y356958D01*
X939825Y356667D01*
X939867Y356250D01*
X939825Y355833D01*
X939658Y355542D01*
X939450Y355292D01*
X939200Y355125D01*
X938867Y355000D01*
X938033D01*
G01X942883D02*
X941217D01*
Y357500D01*
X942883D01*
G01X942217Y356292D02*
X941217D01*
G01X931875Y362333D02*
X932208Y362125D01*
X932583Y362000D01*
X932917D01*
X933250Y362125D01*
X933500Y362333D01*
X933625Y362625D01*
X933542Y362917D01*
X933333Y363167D01*
X932958Y363333D01*
X932458Y363417D01*
X932167Y363583D01*
X932042Y363875D01*
X932125Y364167D01*
X932333Y364375D01*
X932625Y364500D01*
X932917D01*
X933208Y364417D01*
X933458Y364208D01*
G01X934600Y364500D02*
X935183Y362000D01*
X935850Y364500D01*
X936517Y362000D01*
X937100Y364500D01*
G01X941425Y363667D02*
X942675D01*
X941425Y362000D01*
X942675D01*
G01X945150D02*
X944900Y362042D01*
X944650Y362208D01*
X944483Y362500D01*
X944400Y362833D01*
X944483Y363167D01*
X944650Y363458D01*
X944900Y363625D01*
X945150Y363667D01*
X945400Y363625D01*
X945650Y363458D01*
X945817Y363167D01*
X945858Y362833D01*
X945817Y362500D01*
X945650Y362208D01*
X945400Y362042D01*
X945150Y362000D01*
G01X947542D02*
Y363667D01*
G01Y363250D02*
X947708Y363458D01*
X947958Y363625D01*
X948292Y363667D01*
X948583Y363625D01*
X948833Y363458D01*
X948958Y363167D01*
Y362000D01*
G01X951350Y363667D02*
Y362000D01*
G01Y364333D02*
X951267Y364375D01*
Y364458D01*
X951350Y364500D01*
X951433Y364458D01*
Y364375D01*
X951350Y364333D01*
G01X953742Y362000D02*
Y363667D01*
G01Y363250D02*
X953908Y363458D01*
X954158Y363625D01*
X954492Y363667D01*
X954783Y363625D01*
X955033Y363458D01*
X955158Y363167D01*
Y362000D01*
G01X956967Y361375D02*
X957258Y361208D01*
X957592Y361167D01*
X957883Y361208D01*
X958133Y361417D01*
X958300Y361708D01*
Y363667D01*
G01Y363333D02*
X958133Y363500D01*
X957883Y363625D01*
X957592Y363667D01*
X957258Y363583D01*
X957050Y363417D01*
X956883Y363125D01*
X956800Y362833D01*
X956842Y362583D01*
X957008Y362292D01*
X957258Y362083D01*
X957592Y362000D01*
X957842Y362042D01*
X958133Y362208D01*
X958300Y362375D01*
G01X960650Y361917D02*
X960567Y361958D01*
Y362042D01*
X960650Y362083D01*
X960733Y362042D01*
Y361958D01*
X960650Y361917D01*
G01Y363042D02*
X960567Y363083D01*
Y363167D01*
X960650Y363208D01*
X960733Y363167D01*
Y363083D01*
X960650Y363042D01*
G01X932750Y350000D02*
Y352500D01*
X932250Y352000D01*
G01Y350000D02*
X933250D01*
G01X934975D02*
X936725Y352500D01*
G01X934975D02*
X936725Y350000D01*
G01X938950D02*
Y352500D01*
X938450Y352000D01*
G01Y350000D02*
X939450D01*
G01X941258Y351042D02*
X941550Y351333D01*
X941800Y351500D01*
X942133Y351583D01*
X942425Y351500D01*
X942633Y351333D01*
X942800Y351083D01*
X942842Y350792D01*
X942800Y350542D01*
X942633Y350292D01*
X942383Y350083D01*
X942092Y350000D01*
X941758Y350083D01*
X941467Y350333D01*
X941300Y350708D01*
X941258Y351125D01*
X941342Y351667D01*
X941467Y351958D01*
X941675Y352250D01*
X941967Y352458D01*
X942258Y352500D01*
X942550Y352417D01*
X942758Y352208D01*
G01X931958Y347083D02*
X932208Y347333D01*
X932500Y347458D01*
X932833Y347500D01*
X933250Y347417D01*
X933542Y347208D01*
X933625Y346958D01*
X933583Y346708D01*
X933417Y346500D01*
X932583Y346083D01*
X932208Y345792D01*
X931958Y345375D01*
X931875Y345000D01*
X933625D01*
G01X934975D02*
X936725Y347500D01*
G01X934975D02*
X936725Y345000D01*
G01X938950D02*
X939242Y345042D01*
X939575Y345167D01*
X939783Y345375D01*
X939867Y345667D01*
X939783Y345958D01*
X939533Y346208D01*
X939158Y346333D01*
X938742D01*
X938492Y346417D01*
X938283Y346625D01*
X938200Y346917D01*
X938325Y347208D01*
X938617Y347417D01*
X938950Y347500D01*
X939283Y347417D01*
X939575Y347208D01*
X939700Y346917D01*
X939617Y346625D01*
X939408Y346417D01*
X939158Y346333D01*
X938742D01*
X938367Y346208D01*
X938117Y345958D01*
X938033Y345667D01*
X938117Y345375D01*
X938325Y345167D01*
X938658Y345042D01*
X938950Y345000D01*
G01X911414Y744467D02*
X908914D01*
Y745508D01*
X909039Y745842D01*
X909206Y746050D01*
X909539Y746133D01*
X909872Y746050D01*
X910081Y745800D01*
X910206Y745508D01*
Y744467D01*
G01Y745508D02*
X911414Y746133D01*
G01X911122Y747692D02*
X911331Y747983D01*
X911414Y748317D01*
X911331Y748650D01*
X911081Y748942D01*
X910706Y749150D01*
X910331Y749233D01*
X909872D01*
X909497Y749150D01*
X909164Y748942D01*
X908997Y748692D01*
X908914Y748400D01*
X908997Y748067D01*
X909164Y747817D01*
X909414Y747650D01*
X909747Y747567D01*
X910039Y747650D01*
X910331Y747858D01*
X910497Y748108D01*
X910539Y748400D01*
X910456Y748733D01*
X910247Y748983D01*
X909872Y749233D01*
G01X908914Y751500D02*
X908997Y751167D01*
X909206Y750917D01*
X909456Y750750D01*
X909789Y750625D01*
X910164Y750583D01*
X910539Y750625D01*
X910872Y750750D01*
X911122Y750917D01*
X911331Y751167D01*
X911414Y751500D01*
X911331Y751833D01*
X911122Y752083D01*
X910872Y752250D01*
X910539Y752375D01*
X910164Y752417D01*
X909789Y752375D01*
X909456Y752250D01*
X909206Y752083D01*
X908997Y751833D01*
X908914Y751500D01*
G01X910914Y753683D02*
X911206Y753933D01*
X911372Y754267D01*
X911414Y754642D01*
X911372Y754975D01*
X911164Y755308D01*
X910914Y755517D01*
X910664Y755558D01*
X910372Y755475D01*
X910164Y755183D01*
X910081Y754892D01*
Y754517D01*
G01Y754892D02*
X909956Y755142D01*
X909747Y755350D01*
X909497Y755433D01*
X909247Y755350D01*
X909039Y755142D01*
X908914Y754767D01*
X908956Y754392D01*
X909122Y754017D01*
G01X911414Y757617D02*
X910872Y757700D01*
X910414Y757825D01*
X909997Y757992D01*
X909539Y758200D01*
X908914Y758533D01*
Y756867D01*
G01X912207Y788588D02*
X909707D01*
Y789629D01*
X909832Y789963D01*
X909999Y790171D01*
X910332Y790254D01*
X910665Y790171D01*
X910874Y789921D01*
X910999Y789629D01*
Y788588D01*
G01Y789629D02*
X912207Y790254D01*
G01Y792438D02*
X911665Y792521D01*
X911207Y792646D01*
X910790Y792813D01*
X910332Y793021D01*
X909707Y793354D01*
Y791688D01*
G01X911915Y794913D02*
X912124Y795204D01*
X912207Y795538D01*
X912124Y795871D01*
X911874Y796163D01*
X911499Y796371D01*
X911124Y796454D01*
X910665D01*
X910290Y796371D01*
X909957Y796163D01*
X909790Y795913D01*
X909707Y795621D01*
X909790Y795288D01*
X909957Y795038D01*
X910207Y794871D01*
X910540Y794788D01*
X910832Y794871D01*
X911124Y795079D01*
X911290Y795329D01*
X911332Y795621D01*
X911249Y795954D01*
X911040Y796204D01*
X910665Y796454D01*
G01X911707Y797804D02*
X911999Y798054D01*
X912165Y798388D01*
X912207Y798763D01*
X912165Y799096D01*
X911957Y799429D01*
X911707Y799638D01*
X911457Y799679D01*
X911165Y799596D01*
X910957Y799304D01*
X910874Y799013D01*
Y798638D01*
G01Y799013D02*
X910749Y799263D01*
X910540Y799471D01*
X910290Y799554D01*
X910040Y799471D01*
X909832Y799263D01*
X909707Y798888D01*
X909749Y798513D01*
X909915Y798138D01*
G01X910124Y801029D02*
X909874Y801279D01*
X909749Y801571D01*
X909707Y801904D01*
X909790Y802321D01*
X909999Y802613D01*
X910249Y802696D01*
X910499Y802654D01*
X910707Y802488D01*
X911124Y801654D01*
X911415Y801279D01*
X911832Y801029D01*
X912207Y800946D01*
Y802696D01*
G01X950097Y27445D02*
X949847Y27570D01*
X949555Y27653D01*
X949222D01*
X948847Y27528D01*
X948555Y27320D01*
X948347Y27070D01*
X948180Y26653D01*
X948138Y26278D01*
X948222Y25903D01*
X948347Y25653D01*
X948597Y25403D01*
X948888Y25236D01*
X949180Y25153D01*
X949472D01*
X949763Y25236D01*
X950013Y25361D01*
X950222Y25528D01*
G01X951363Y25653D02*
X951613Y25361D01*
X951947Y25195D01*
X952322Y25153D01*
X952655Y25195D01*
X952988Y25403D01*
X953197Y25653D01*
X953238Y25903D01*
X953155Y26195D01*
X952863Y26403D01*
X952572Y26486D01*
X952197D01*
G01X952572D02*
X952822Y26611D01*
X953030Y26820D01*
X953113Y27070D01*
X953030Y27320D01*
X952822Y27528D01*
X952447Y27653D01*
X952072Y27611D01*
X951697Y27445D01*
G01X955380Y25153D02*
Y27653D01*
X954880Y27153D01*
G01Y25153D02*
X955880D01*
G01X957772Y25445D02*
X958063Y25236D01*
X958397Y25153D01*
X958730Y25236D01*
X959022Y25486D01*
X959230Y25861D01*
X959313Y26236D01*
Y26695D01*
X959230Y27070D01*
X959022Y27403D01*
X958772Y27570D01*
X958480Y27653D01*
X958147Y27570D01*
X957897Y27403D01*
X957730Y27153D01*
X957647Y26820D01*
X957730Y26528D01*
X957938Y26236D01*
X958188Y26070D01*
X958480Y26028D01*
X958813Y26111D01*
X959063Y26320D01*
X959313Y26695D01*
G01X949817Y23458D02*
X949567Y23583D01*
X949275Y23666D01*
X948942D01*
X948567Y23541D01*
X948275Y23333D01*
X948067Y23083D01*
X947900Y22666D01*
X947858Y22291D01*
X947942Y21916D01*
X948067Y21666D01*
X948317Y21416D01*
X948608Y21249D01*
X948900Y21166D01*
X949192D01*
X949483Y21249D01*
X949733Y21374D01*
X949942Y21541D01*
G01X951042Y21166D02*
Y23666D01*
X952958Y21166D01*
Y23666D01*
G01X954183Y21666D02*
X954433Y21374D01*
X954767Y21208D01*
X955142Y21166D01*
X955475Y21208D01*
X955808Y21416D01*
X956017Y21666D01*
X956058Y21916D01*
X955975Y22208D01*
X955683Y22416D01*
X955392Y22499D01*
X955017D01*
G01X955392D02*
X955642Y22624D01*
X955850Y22833D01*
X955933Y23083D01*
X955850Y23333D01*
X955642Y23541D01*
X955267Y23666D01*
X954892Y23624D01*
X954517Y23458D01*
G01X957817Y62000D02*
Y59500D01*
X959483D01*
G01X961750D02*
Y62000D01*
X961250Y61500D01*
G01Y59500D02*
X962250D01*
G01X970708Y70513D02*
X970583Y70263D01*
X970500Y69971D01*
Y69638D01*
X970625Y69263D01*
X970833Y68971D01*
X971083Y68763D01*
X971500Y68596D01*
X971875Y68554D01*
X972250Y68638D01*
X972500Y68763D01*
X972750Y69013D01*
X972917Y69304D01*
X973000Y69596D01*
Y69888D01*
X972917Y70179D01*
X972792Y70429D01*
X972625Y70638D01*
G01X973000Y73196D02*
X970500D01*
X972292Y71654D01*
Y73738D01*
G01X973000Y75713D02*
X972458Y75796D01*
X972000Y75921D01*
X971583Y76088D01*
X971125Y76296D01*
X970500Y76629D01*
Y74963D01*
G01X973000Y78813D02*
X972458Y78896D01*
X972000Y79021D01*
X971583Y79188D01*
X971125Y79396D01*
X970500Y79729D01*
Y78063D01*
G01X962900Y74317D02*
X960400D01*
Y75358D01*
X960525Y75692D01*
X960692Y75900D01*
X961025Y75983D01*
X961358Y75900D01*
X961567Y75650D01*
X961692Y75358D01*
Y74317D01*
G01Y75358D02*
X962900Y75983D01*
G01Y78250D02*
X962858Y78542D01*
X962733Y78875D01*
X962525Y79083D01*
X962233Y79167D01*
X961942Y79083D01*
X961692Y78833D01*
X961567Y78458D01*
Y78042D01*
X961483Y77792D01*
X961275Y77583D01*
X960983Y77500D01*
X960692Y77625D01*
X960483Y77917D01*
X960400Y78250D01*
X960483Y78583D01*
X960692Y78875D01*
X960983Y79000D01*
X961275Y78917D01*
X961483Y78708D01*
X961567Y78458D01*
Y78042D01*
X961692Y77667D01*
X961942Y77417D01*
X962233Y77333D01*
X962525Y77417D01*
X962733Y77625D01*
X962858Y77958D01*
X962900Y78250D01*
G01X960817Y80558D02*
X960567Y80808D01*
X960442Y81100D01*
X960400Y81433D01*
X960483Y81850D01*
X960692Y82142D01*
X960942Y82225D01*
X961192Y82183D01*
X961400Y82017D01*
X961817Y81183D01*
X962108Y80808D01*
X962525Y80558D01*
X962900Y80475D01*
Y82225D01*
G01X960817Y83658D02*
X960567Y83908D01*
X960442Y84200D01*
X960400Y84533D01*
X960483Y84950D01*
X960692Y85242D01*
X960942Y85325D01*
X961192Y85283D01*
X961400Y85117D01*
X961817Y84283D01*
X962108Y83908D01*
X962525Y83658D01*
X962900Y83575D01*
Y85325D01*
G01X953400Y67000D02*
X957400D01*
Y74400D01*
G01X961598Y63224D02*
Y65724D01*
X962639D01*
X962973Y65599D01*
X963181Y65432D01*
X963264Y65099D01*
X963181Y64766D01*
X962931Y64557D01*
X962639Y64432D01*
X961598D01*
G01X962639D02*
X963264Y63224D01*
G01X966031D02*
Y65724D01*
X964489Y63932D01*
X966573D01*
G01X967923Y63516D02*
X968214Y63307D01*
X968548Y63224D01*
X968881Y63307D01*
X969173Y63557D01*
X969381Y63932D01*
X969464Y64307D01*
Y64766D01*
X969381Y65141D01*
X969173Y65474D01*
X968923Y65641D01*
X968631Y65724D01*
X968298Y65641D01*
X968048Y65474D01*
X967881Y65224D01*
X967798Y64891D01*
X967881Y64599D01*
X968089Y64307D01*
X968339Y64141D01*
X968631Y64099D01*
X968964Y64182D01*
X969214Y64391D01*
X969464Y64766D01*
G01X972231Y63224D02*
Y65724D01*
X970689Y63932D01*
X972773D01*
G01X960781Y62624D02*
Y66624D01*
X953381D01*
G01X946100Y60900D02*
Y73900D01*
G01X970408Y84913D02*
X970283Y84663D01*
X970200Y84371D01*
Y84038D01*
X970325Y83663D01*
X970533Y83371D01*
X970783Y83163D01*
X971200Y82996D01*
X971575Y82954D01*
X971950Y83038D01*
X972200Y83163D01*
X972450Y83413D01*
X972617Y83704D01*
X972700Y83996D01*
Y84288D01*
X972617Y84579D01*
X972492Y84829D01*
X972325Y85038D01*
G01X972700Y87596D02*
X970200D01*
X971992Y86054D01*
Y88138D01*
G01X971658Y89404D02*
X971367Y89696D01*
X971200Y89946D01*
X971117Y90279D01*
X971200Y90571D01*
X971367Y90779D01*
X971617Y90946D01*
X971908Y90988D01*
X972158Y90946D01*
X972408Y90779D01*
X972617Y90529D01*
X972700Y90238D01*
X972617Y89904D01*
X972367Y89613D01*
X971992Y89446D01*
X971575Y89404D01*
X971033Y89488D01*
X970742Y89613D01*
X970450Y89821D01*
X970242Y90113D01*
X970200Y90404D01*
X970283Y90696D01*
X970492Y90904D01*
G01X972700Y93796D02*
X970200D01*
X971992Y92254D01*
Y94338D01*
G01X972000Y98017D02*
X969500D01*
Y99058D01*
X969625Y99392D01*
X969792Y99600D01*
X970125Y99683D01*
X970458Y99600D01*
X970667Y99350D01*
X970792Y99058D01*
Y98017D01*
G01Y99058D02*
X972000Y99683D01*
G01Y101867D02*
X971458Y101950D01*
X971000Y102075D01*
X970583Y102242D01*
X970125Y102450D01*
X969500Y102783D01*
Y101117D01*
G01X971708Y104342D02*
X971917Y104633D01*
X972000Y104967D01*
X971917Y105300D01*
X971667Y105592D01*
X971292Y105800D01*
X970917Y105883D01*
X970458D01*
X970083Y105800D01*
X969750Y105592D01*
X969583Y105342D01*
X969500Y105050D01*
X969583Y104717D01*
X969750Y104467D01*
X970000Y104300D01*
X970333Y104217D01*
X970625Y104300D01*
X970917Y104508D01*
X971083Y104758D01*
X971125Y105050D01*
X971042Y105383D01*
X970833Y105633D01*
X970458Y105883D01*
G01X971500Y107233D02*
X971792Y107483D01*
X971958Y107817D01*
X972000Y108192D01*
X971958Y108525D01*
X971750Y108858D01*
X971500Y109067D01*
X971250Y109108D01*
X970958Y109025D01*
X970750Y108733D01*
X970667Y108442D01*
Y108067D01*
G01Y108442D02*
X970542Y108692D01*
X970333Y108900D01*
X970083Y108983D01*
X969833Y108900D01*
X969625Y108692D01*
X969500Y108317D01*
X969542Y107942D01*
X969708Y107567D01*
G01X958000Y95200D02*
X954000D01*
Y87800D01*
G01X967500Y98017D02*
X965000D01*
Y99058D01*
X965125Y99392D01*
X965292Y99600D01*
X965625Y99683D01*
X965958Y99600D01*
X966167Y99350D01*
X966292Y99058D01*
Y98017D01*
G01Y99058D02*
X967500Y99683D01*
G01Y101867D02*
X966958Y101950D01*
X966500Y102075D01*
X966083Y102242D01*
X965625Y102450D01*
X965000Y102783D01*
Y101117D01*
G01X967500Y105050D02*
X967458Y105342D01*
X967333Y105675D01*
X967125Y105883D01*
X966833Y105967D01*
X966542Y105883D01*
X966292Y105633D01*
X966167Y105258D01*
Y104842D01*
X966083Y104592D01*
X965875Y104383D01*
X965583Y104300D01*
X965292Y104425D01*
X965083Y104717D01*
X965000Y105050D01*
X965083Y105383D01*
X965292Y105675D01*
X965583Y105800D01*
X965875Y105717D01*
X966083Y105508D01*
X966167Y105258D01*
Y104842D01*
X966292Y104467D01*
X966542Y104217D01*
X966833Y104133D01*
X967125Y104217D01*
X967333Y104425D01*
X967458Y104758D01*
X967500Y105050D01*
G01X967125Y107233D02*
X967333Y107483D01*
X967458Y107775D01*
X967500Y108150D01*
X967417Y108525D01*
X967250Y108817D01*
X966958Y109025D01*
X966625Y109067D01*
X966292Y108983D01*
X966083Y108775D01*
X965917Y108483D01*
X965875Y108192D01*
X965917Y107900D01*
X966083Y107525D01*
X965000Y107650D01*
Y108775D01*
G01X949500Y87800D02*
X953500D01*
Y95200D01*
G01X963000Y98017D02*
X960500D01*
Y99058D01*
X960625Y99392D01*
X960792Y99600D01*
X961125Y99683D01*
X961458Y99600D01*
X961667Y99350D01*
X961792Y99058D01*
Y98017D01*
G01Y99058D02*
X963000Y99683D01*
G01Y101867D02*
X962458Y101950D01*
X962000Y102075D01*
X961583Y102242D01*
X961125Y102450D01*
X960500Y102783D01*
Y101117D01*
G01X963000Y105050D02*
X962958Y105342D01*
X962833Y105675D01*
X962625Y105883D01*
X962333Y105967D01*
X962042Y105883D01*
X961792Y105633D01*
X961667Y105258D01*
Y104842D01*
X961583Y104592D01*
X961375Y104383D01*
X961083Y104300D01*
X960792Y104425D01*
X960583Y104717D01*
X960500Y105050D01*
X960583Y105383D01*
X960792Y105675D01*
X961083Y105800D01*
X961375Y105717D01*
X961583Y105508D01*
X961667Y105258D01*
Y104842D01*
X961792Y104467D01*
X962042Y104217D01*
X962333Y104133D01*
X962625Y104217D01*
X962833Y104425D01*
X962958Y104758D01*
X963000Y105050D01*
G01X962500Y107233D02*
X962792Y107483D01*
X962958Y107817D01*
X963000Y108192D01*
X962958Y108525D01*
X962750Y108858D01*
X962500Y109067D01*
X962250Y109108D01*
X961958Y109025D01*
X961750Y108733D01*
X961667Y108442D01*
Y108067D01*
G01Y108442D02*
X961542Y108692D01*
X961333Y108900D01*
X961083Y108983D01*
X960833Y108900D01*
X960625Y108692D01*
X960500Y108317D01*
X960542Y107942D01*
X960708Y107567D01*
G01X945000Y87800D02*
X949000D01*
Y95200D01*
G01X958200Y96717D02*
X955700D01*
Y97758D01*
X955825Y98092D01*
X955992Y98300D01*
X956325Y98383D01*
X956658Y98300D01*
X956867Y98050D01*
X956992Y97758D01*
Y96717D01*
G01Y97758D02*
X958200Y98383D01*
G01Y100567D02*
X957658Y100650D01*
X957200Y100775D01*
X956783Y100942D01*
X956325Y101150D01*
X955700Y101483D01*
Y99817D01*
G01X958200Y103750D02*
X958158Y104042D01*
X958033Y104375D01*
X957825Y104583D01*
X957533Y104667D01*
X957242Y104583D01*
X956992Y104333D01*
X956867Y103958D01*
Y103542D01*
X956783Y103292D01*
X956575Y103083D01*
X956283Y103000D01*
X955992Y103125D01*
X955783Y103417D01*
X955700Y103750D01*
X955783Y104083D01*
X955992Y104375D01*
X956283Y104500D01*
X956575Y104417D01*
X956783Y104208D01*
X956867Y103958D01*
Y103542D01*
X956992Y103167D01*
X957242Y102917D01*
X957533Y102833D01*
X957825Y102917D01*
X958033Y103125D01*
X958158Y103458D01*
X958200Y103750D01*
G01Y106850D02*
X955700D01*
X956200Y106350D01*
G01X958200D02*
Y107350D01*
G01X977000Y99517D02*
X974500D01*
Y100558D01*
X974625Y100892D01*
X974792Y101100D01*
X975125Y101183D01*
X975458Y101100D01*
X975667Y100850D01*
X975792Y100558D01*
Y99517D01*
G01Y100558D02*
X977000Y101183D01*
G01Y103367D02*
X976458Y103450D01*
X976000Y103575D01*
X975583Y103742D01*
X975125Y103950D01*
X974500Y104283D01*
Y102617D01*
G01X977000Y107050D02*
X974500D01*
X976292Y105508D01*
Y107592D01*
G01X977000Y109650D02*
X974500D01*
X975000Y109150D01*
G01X977000D02*
Y110150D01*
G01X945284Y275928D02*
Y274136D01*
X945451Y273761D01*
X945784Y273511D01*
X946201Y273428D01*
X946618Y273511D01*
X946951Y273761D01*
X947118Y274136D01*
Y275928D01*
G01X949301Y273428D02*
Y275928D01*
X948801Y275428D01*
G01Y273428D02*
X949801D01*
G01X962750Y325000D02*
X962417Y325042D01*
X962125Y325208D01*
X961875Y325458D01*
X961708Y325750D01*
X961625Y326083D01*
Y326417D01*
X961708Y326750D01*
X961875Y327042D01*
X962125Y327292D01*
X962417Y327458D01*
X962750Y327500D01*
X963083Y327458D01*
X963375Y327292D01*
X963625Y327042D01*
X963792Y326750D01*
X963875Y326417D01*
Y326083D01*
X963792Y325750D01*
X963625Y325458D01*
X963375Y325208D01*
X963083Y325042D01*
X962750Y325000D01*
G01X965058D02*
Y327500D01*
X966642D01*
G01X966058Y326292D02*
X965058D01*
G01X968158Y325000D02*
Y327500D01*
X969742D01*
G01X969158Y326292D02*
X968158D01*
G01X962750Y340000D02*
X962417Y340042D01*
X962125Y340208D01*
X961875Y340458D01*
X961708Y340750D01*
X961625Y341083D01*
Y341417D01*
X961708Y341750D01*
X961875Y342042D01*
X962125Y342292D01*
X962417Y342458D01*
X962750Y342500D01*
X963083Y342458D01*
X963375Y342292D01*
X963625Y342042D01*
X963792Y341750D01*
X963875Y341417D01*
Y341083D01*
X963792Y340750D01*
X963625Y340458D01*
X963375Y340208D01*
X963083Y340042D01*
X962750Y340000D01*
G01X965058D02*
Y342500D01*
X966642D01*
G01X966058Y341292D02*
X965058D01*
G01X968158Y340000D02*
Y342500D01*
X969742D01*
G01X969158Y341292D02*
X968158D01*
G01X962750Y335000D02*
X962417Y335042D01*
X962125Y335208D01*
X961875Y335458D01*
X961708Y335750D01*
X961625Y336083D01*
Y336417D01*
X961708Y336750D01*
X961875Y337042D01*
X962125Y337292D01*
X962417Y337458D01*
X962750Y337500D01*
X963083Y337458D01*
X963375Y337292D01*
X963625Y337042D01*
X963792Y336750D01*
X963875Y336417D01*
Y336083D01*
X963792Y335750D01*
X963625Y335458D01*
X963375Y335208D01*
X963083Y335042D01*
X962750Y335000D01*
G01X965058D02*
Y337500D01*
X966642D01*
G01X966058Y336292D02*
X965058D01*
G01X968158Y335000D02*
Y337500D01*
X969742D01*
G01X969158Y336292D02*
X968158D01*
G01X962750Y330000D02*
X962417Y330042D01*
X962125Y330208D01*
X961875Y330458D01*
X961708Y330750D01*
X961625Y331083D01*
Y331417D01*
X961708Y331750D01*
X961875Y332042D01*
X962125Y332292D01*
X962417Y332458D01*
X962750Y332500D01*
X963083Y332458D01*
X963375Y332292D01*
X963625Y332042D01*
X963792Y331750D01*
X963875Y331417D01*
Y331083D01*
X963792Y330750D01*
X963625Y330458D01*
X963375Y330208D01*
X963083Y330042D01*
X962750Y330000D01*
G01X965058D02*
Y332500D01*
X966642D01*
G01X966058Y331292D02*
X965058D01*
G01X968158Y330000D02*
Y332500D01*
X969742D01*
G01X969158Y331292D02*
X968158D01*
G01X958167Y357500D02*
X957333D01*
Y354167D01*
X958167D01*
G01X960017Y357500D02*
Y355000D01*
X961683D01*
G01X964783D02*
X963117D01*
Y357500D01*
X964783D01*
G01X964117Y356292D02*
X963117D01*
G01X966133Y355000D02*
Y357500D01*
X966967D01*
X967300Y357375D01*
X967550Y357208D01*
X967758Y356958D01*
X967925Y356667D01*
X967967Y356250D01*
X967925Y355833D01*
X967758Y355542D01*
X967550Y355292D01*
X967300Y355125D01*
X966967Y355000D01*
X966133D01*
G01X970150D02*
Y357500D01*
X969650Y357000D01*
G01Y355000D02*
X970650D01*
G01X973250D02*
X973542Y355042D01*
X973875Y355167D01*
X974083Y355375D01*
X974167Y355667D01*
X974083Y355958D01*
X973833Y356208D01*
X973458Y356333D01*
X973042D01*
X972792Y356417D01*
X972583Y356625D01*
X972500Y356917D01*
X972625Y357208D01*
X972917Y357417D01*
X973250Y357500D01*
X973583Y357417D01*
X973875Y357208D01*
X974000Y356917D01*
X973917Y356625D01*
X973708Y356417D01*
X973458Y356333D01*
X973042D01*
X972667Y356208D01*
X972417Y355958D01*
X972333Y355667D01*
X972417Y355375D01*
X972625Y355167D01*
X972958Y355042D01*
X973250Y355000D01*
G01X975933Y354167D02*
X976767D01*
Y357500D01*
X975933D01*
G01X962750Y350000D02*
X962417Y350042D01*
X962125Y350208D01*
X961875Y350458D01*
X961708Y350750D01*
X961625Y351083D01*
Y351417D01*
X961708Y351750D01*
X961875Y352042D01*
X962125Y352292D01*
X962417Y352458D01*
X962750Y352500D01*
X963083Y352458D01*
X963375Y352292D01*
X963625Y352042D01*
X963792Y351750D01*
X963875Y351417D01*
Y351083D01*
X963792Y350750D01*
X963625Y350458D01*
X963375Y350208D01*
X963083Y350042D01*
X962750Y350000D01*
G01X964892D02*
Y352500D01*
X966808Y350000D01*
Y352500D01*
G01X962750Y345000D02*
X962417Y345042D01*
X962125Y345208D01*
X961875Y345458D01*
X961708Y345750D01*
X961625Y346083D01*
Y346417D01*
X961708Y346750D01*
X961875Y347042D01*
X962125Y347292D01*
X962417Y347458D01*
X962750Y347500D01*
X963083Y347458D01*
X963375Y347292D01*
X963625Y347042D01*
X963792Y346750D01*
X963875Y346417D01*
Y346083D01*
X963792Y345750D01*
X963625Y345458D01*
X963375Y345208D01*
X963083Y345042D01*
X962750Y345000D01*
G01X965058D02*
Y347500D01*
X966642D01*
G01X966058Y346292D02*
X965058D01*
G01X968158Y345000D02*
Y347500D01*
X969742D01*
G01X969158Y346292D02*
X968158D01*
G01X1018800Y5000D02*
Y9300D01*
X990900D01*
Y11600D01*
X980500D01*
Y23500D01*
X985000D01*
Y35500D01*
X990000D01*
Y52400D01*
X992396D01*
G01X996903Y30207D02*
X1017003D01*
G01X996903Y17807D02*
X1016703D01*
G01X996903Y30207D02*
Y17807D01*
G01X982717Y20587D02*
Y16587D01*
X990117D01*
G01X994411Y12160D02*
Y16160D01*
X987011D01*
G01X1007176Y46962D02*
X1003176D01*
Y39562D01*
G01X994569Y25248D02*
Y29248D01*
X987169D01*
G01X994569Y21121D02*
Y25121D01*
X987169D01*
G01X997405Y52400D02*
X1003600D01*
G01X978708Y70013D02*
X978583Y69763D01*
X978500Y69471D01*
Y69138D01*
X978625Y68763D01*
X978833Y68471D01*
X979083Y68263D01*
X979500Y68096D01*
X979875Y68054D01*
X980250Y68138D01*
X980500Y68263D01*
X980750Y68513D01*
X980917Y68804D01*
X981000Y69096D01*
Y69388D01*
X980917Y69679D01*
X980792Y69929D01*
X980625Y70138D01*
G01X981000Y72696D02*
X978500D01*
X980292Y71154D01*
Y73238D01*
G01X981000Y75213D02*
X980458Y75296D01*
X980000Y75421D01*
X979583Y75588D01*
X979125Y75796D01*
X978500Y76129D01*
Y74463D01*
G01Y78396D02*
X978583Y78063D01*
X978792Y77813D01*
X979042Y77646D01*
X979375Y77521D01*
X979750Y77479D01*
X980125Y77521D01*
X980458Y77646D01*
X980708Y77813D01*
X980917Y78063D01*
X981000Y78396D01*
X980917Y78729D01*
X980708Y78979D01*
X980458Y79146D01*
X980125Y79271D01*
X979750Y79313D01*
X979375Y79271D01*
X979042Y79146D01*
X978792Y78979D01*
X978583Y78729D01*
X978500Y78396D01*
G01X991365Y61124D02*
X988865D01*
Y62124D01*
X988990Y62457D01*
X989282Y62707D01*
X989615Y62790D01*
X989948Y62707D01*
X990198Y62499D01*
X990323Y62124D01*
Y61124D01*
G01X989073Y65974D02*
X988948Y65724D01*
X988865Y65432D01*
Y65099D01*
X988990Y64724D01*
X989198Y64432D01*
X989448Y64224D01*
X989865Y64057D01*
X990240Y64015D01*
X990615Y64099D01*
X990865Y64224D01*
X991115Y64474D01*
X991282Y64765D01*
X991365Y65057D01*
Y65349D01*
X991282Y65640D01*
X991157Y65890D01*
X990990Y66099D01*
G01X989282Y67365D02*
X989032Y67615D01*
X988907Y67907D01*
X988865Y68240D01*
X988948Y68657D01*
X989157Y68949D01*
X989407Y69032D01*
X989657Y68990D01*
X989865Y68824D01*
X990282Y67990D01*
X990573Y67615D01*
X990990Y67365D01*
X991365Y67282D01*
Y69032D01*
G01X989282Y70465D02*
X989032Y70715D01*
X988907Y71007D01*
X988865Y71340D01*
X988948Y71757D01*
X989157Y72049D01*
X989407Y72132D01*
X989657Y72090D01*
X989865Y71924D01*
X990282Y71090D01*
X990573Y70715D01*
X990990Y70465D01*
X991365Y70382D01*
Y72132D01*
G01Y74857D02*
X988865D01*
X990657Y73315D01*
Y75399D01*
G01X994230Y41044D02*
X998230D01*
Y48444D01*
G01X1002683Y51150D02*
X998683D01*
Y43750D01*
G01X1005300Y73666D02*
X1004967Y73708D01*
X1004675Y73874D01*
X1004425Y74124D01*
X1004258Y74416D01*
X1004175Y74749D01*
Y75083D01*
X1004258Y75416D01*
X1004425Y75708D01*
X1004675Y75958D01*
X1004967Y76124D01*
X1005300Y76166D01*
X1005633Y76124D01*
X1005925Y75958D01*
X1006175Y75708D01*
X1006342Y75416D01*
X1006425Y75083D01*
Y74749D01*
X1006342Y74416D01*
X1006175Y74124D01*
X1005925Y73874D01*
X1005633Y73708D01*
X1005300Y73666D01*
G01X1005633Y74333D02*
X1006133Y73666D01*
G01X1007483Y74166D02*
X1007733Y73874D01*
X1008067Y73708D01*
X1008442Y73666D01*
X1008775Y73708D01*
X1009108Y73916D01*
X1009317Y74166D01*
X1009358Y74416D01*
X1009275Y74708D01*
X1008983Y74916D01*
X1008692Y74999D01*
X1008317D01*
G01X1008692D02*
X1008942Y75124D01*
X1009150Y75333D01*
X1009233Y75583D01*
X1009150Y75833D01*
X1008942Y76041D01*
X1008567Y76166D01*
X1008192Y76124D01*
X1007817Y75958D01*
G01X1010708Y75749D02*
X1010958Y75999D01*
X1011250Y76124D01*
X1011583Y76166D01*
X1012000Y76083D01*
X1012292Y75874D01*
X1012375Y75624D01*
X1012333Y75374D01*
X1012167Y75166D01*
X1011333Y74749D01*
X1010958Y74458D01*
X1010708Y74041D01*
X1010625Y73666D01*
X1012375D01*
G01X1014600Y76166D02*
X1014267Y76083D01*
X1014017Y75874D01*
X1013850Y75624D01*
X1013725Y75291D01*
X1013683Y74916D01*
X1013725Y74541D01*
X1013850Y74208D01*
X1014017Y73958D01*
X1014267Y73749D01*
X1014600Y73666D01*
X1014933Y73749D01*
X1015183Y73958D01*
X1015350Y74208D01*
X1015475Y74541D01*
X1015517Y74916D01*
X1015475Y75291D01*
X1015350Y75624D01*
X1015183Y75874D01*
X1014933Y76083D01*
X1014600Y76166D01*
G01X1016783Y74166D02*
X1017033Y73874D01*
X1017367Y73708D01*
X1017742Y73666D01*
X1018075Y73708D01*
X1018408Y73916D01*
X1018617Y74166D01*
X1018658Y74416D01*
X1018575Y74708D01*
X1018283Y74916D01*
X1017992Y74999D01*
X1017617D01*
G01X1017992D02*
X1018242Y75124D01*
X1018450Y75333D01*
X1018533Y75583D01*
X1018450Y75833D01*
X1018242Y76041D01*
X1017867Y76166D01*
X1017492Y76124D01*
X1017117Y75958D01*
G01X1016900Y52100D02*
Y71300D01*
X1005700D01*
Y52100D01*
X1016900D01*
G01X978408Y84913D02*
X978283Y84663D01*
X978200Y84371D01*
Y84038D01*
X978325Y83663D01*
X978533Y83371D01*
X978783Y83163D01*
X979200Y82996D01*
X979575Y82954D01*
X979950Y83038D01*
X980200Y83163D01*
X980450Y83413D01*
X980617Y83704D01*
X980700Y83996D01*
Y84288D01*
X980617Y84579D01*
X980492Y84829D01*
X980325Y85038D01*
G01X980700Y87596D02*
X978200D01*
X979992Y86054D01*
Y88138D01*
G01X979658Y89404D02*
X979367Y89696D01*
X979200Y89946D01*
X979117Y90279D01*
X979200Y90571D01*
X979367Y90779D01*
X979617Y90946D01*
X979908Y90988D01*
X980158Y90946D01*
X980408Y90779D01*
X980617Y90529D01*
X980700Y90238D01*
X980617Y89904D01*
X980367Y89613D01*
X979992Y89446D01*
X979575Y89404D01*
X979033Y89488D01*
X978742Y89613D01*
X978450Y89821D01*
X978242Y90113D01*
X978200Y90404D01*
X978283Y90696D01*
X978492Y90904D01*
G01X980200Y92379D02*
X980492Y92629D01*
X980658Y92963D01*
X980700Y93338D01*
X980658Y93671D01*
X980450Y94004D01*
X980200Y94213D01*
X979950Y94254D01*
X979658Y94171D01*
X979450Y93879D01*
X979367Y93588D01*
Y93213D01*
G01Y93588D02*
X979242Y93838D01*
X979033Y94046D01*
X978783Y94129D01*
X978533Y94046D01*
X978325Y93838D01*
X978200Y93463D01*
X978242Y93088D01*
X978408Y92713D01*
G01X998000Y99517D02*
X995500D01*
Y100558D01*
X995625Y100892D01*
X995792Y101100D01*
X996125Y101183D01*
X996458Y101100D01*
X996667Y100850D01*
X996792Y100558D01*
Y99517D01*
G01Y100558D02*
X998000Y101183D01*
G01Y103367D02*
X997458Y103450D01*
X997000Y103575D01*
X996583Y103742D01*
X996125Y103950D01*
X995500Y104283D01*
Y102617D01*
G01X998000Y106467D02*
X997458Y106550D01*
X997000Y106675D01*
X996583Y106842D01*
X996125Y107050D01*
X995500Y107383D01*
Y105717D01*
G01X997708Y108942D02*
X997917Y109233D01*
X998000Y109567D01*
X997917Y109900D01*
X997667Y110192D01*
X997292Y110400D01*
X996917Y110483D01*
X996458D01*
X996083Y110400D01*
X995750Y110192D01*
X995583Y109942D01*
X995500Y109650D01*
X995583Y109317D01*
X995750Y109067D01*
X996000Y108900D01*
X996333Y108817D01*
X996625Y108900D01*
X996917Y109108D01*
X997083Y109358D01*
X997125Y109650D01*
X997042Y109983D01*
X996833Y110233D01*
X996458Y110483D01*
G01X1002500Y99517D02*
X1000000D01*
Y100558D01*
X1000125Y100892D01*
X1000292Y101100D01*
X1000625Y101183D01*
X1000958Y101100D01*
X1001167Y100850D01*
X1001292Y100558D01*
Y99517D01*
G01Y100558D02*
X1002500Y101183D01*
G01Y103367D02*
X1001958Y103450D01*
X1001500Y103575D01*
X1001083Y103742D01*
X1000625Y103950D01*
X1000000Y104283D01*
Y102617D01*
G01X1002500Y106467D02*
X1001958Y106550D01*
X1001500Y106675D01*
X1001083Y106842D01*
X1000625Y107050D01*
X1000000Y107383D01*
Y105717D01*
G01X1002500Y109567D02*
X1001958Y109650D01*
X1001500Y109775D01*
X1001083Y109942D01*
X1000625Y110150D01*
X1000000Y110483D01*
Y108817D01*
G01X1007000Y99517D02*
X1004500D01*
Y100558D01*
X1004625Y100892D01*
X1004792Y101100D01*
X1005125Y101183D01*
X1005458Y101100D01*
X1005667Y100850D01*
X1005792Y100558D01*
Y99517D01*
G01Y100558D02*
X1007000Y101183D01*
G01Y103367D02*
X1006458Y103450D01*
X1006000Y103575D01*
X1005583Y103742D01*
X1005125Y103950D01*
X1004500Y104283D01*
Y102617D01*
G01X1005958Y105758D02*
X1005667Y106050D01*
X1005500Y106300D01*
X1005417Y106633D01*
X1005500Y106925D01*
X1005667Y107133D01*
X1005917Y107300D01*
X1006208Y107342D01*
X1006458Y107300D01*
X1006708Y107133D01*
X1006917Y106883D01*
X1007000Y106592D01*
X1006917Y106258D01*
X1006667Y105967D01*
X1006292Y105800D01*
X1005875Y105758D01*
X1005333Y105842D01*
X1005042Y105967D01*
X1004750Y106175D01*
X1004542Y106467D01*
X1004500Y106758D01*
X1004583Y107050D01*
X1004792Y107258D01*
G01X1007000Y110150D02*
X1004500D01*
X1006292Y108608D01*
Y110692D01*
G01X985000Y99517D02*
X982500D01*
Y100558D01*
X982625Y100892D01*
X982792Y101100D01*
X983125Y101183D01*
X983458Y101100D01*
X983667Y100850D01*
X983792Y100558D01*
Y99517D01*
G01Y100558D02*
X985000Y101183D01*
G01Y103367D02*
X984458Y103450D01*
X984000Y103575D01*
X983583Y103742D01*
X983125Y103950D01*
X982500Y104283D01*
Y102617D01*
G01X985000Y107050D02*
X982500D01*
X984292Y105508D01*
Y107592D01*
G01X985000Y109567D02*
X984458Y109650D01*
X984000Y109775D01*
X983583Y109942D01*
X983125Y110150D01*
X982500Y110483D01*
Y108817D01*
G01X989000Y99517D02*
X986500D01*
Y100558D01*
X986625Y100892D01*
X986792Y101100D01*
X987125Y101183D01*
X987458Y101100D01*
X987667Y100850D01*
X987792Y100558D01*
Y99517D01*
G01Y100558D02*
X989000Y101183D01*
G01Y103367D02*
X988458Y103450D01*
X988000Y103575D01*
X987583Y103742D01*
X987125Y103950D01*
X986500Y104283D01*
Y102617D01*
G01X989000Y107050D02*
X986500D01*
X988292Y105508D01*
Y107592D01*
G01X988625Y108733D02*
X988833Y108983D01*
X988958Y109275D01*
X989000Y109650D01*
X988917Y110025D01*
X988750Y110317D01*
X988458Y110525D01*
X988125Y110567D01*
X987792Y110483D01*
X987583Y110275D01*
X987417Y109983D01*
X987375Y109692D01*
X987417Y109400D01*
X987583Y109025D01*
X986500Y109150D01*
Y110275D01*
G01X993500Y99517D02*
X991000D01*
Y100558D01*
X991125Y100892D01*
X991292Y101100D01*
X991625Y101183D01*
X991958Y101100D01*
X992167Y100850D01*
X992292Y100558D01*
Y99517D01*
G01Y100558D02*
X993500Y101183D01*
G01Y103367D02*
X992958Y103450D01*
X992500Y103575D01*
X992083Y103742D01*
X991625Y103950D01*
X991000Y104283D01*
Y102617D01*
G01X993500Y107050D02*
X991000D01*
X992792Y105508D01*
Y107592D01*
G01X993500Y110150D02*
X991000D01*
X992792Y108608D01*
Y110692D01*
G01X981000Y99517D02*
X978500D01*
Y100558D01*
X978625Y100892D01*
X978792Y101100D01*
X979125Y101183D01*
X979458Y101100D01*
X979667Y100850D01*
X979792Y100558D01*
Y99517D01*
G01Y100558D02*
X981000Y101183D01*
G01Y103367D02*
X980458Y103450D01*
X980000Y103575D01*
X979583Y103742D01*
X979125Y103950D01*
X978500Y104283D01*
Y102617D01*
G01X981000Y107050D02*
X978500D01*
X980292Y105508D01*
Y107592D01*
G01X978917Y108858D02*
X978667Y109108D01*
X978542Y109400D01*
X978500Y109733D01*
X978583Y110150D01*
X978792Y110442D01*
X979042Y110525D01*
X979292Y110483D01*
X979500Y110317D01*
X979917Y109483D01*
X980208Y109108D01*
X980625Y108858D01*
X981000Y108775D01*
Y110525D01*
G01X987750Y325000D02*
X987417Y325042D01*
X987125Y325208D01*
X986875Y325458D01*
X986708Y325750D01*
X986625Y326083D01*
Y326417D01*
X986708Y326750D01*
X986875Y327042D01*
X987125Y327292D01*
X987417Y327458D01*
X987750Y327500D01*
X988083Y327458D01*
X988375Y327292D01*
X988625Y327042D01*
X988792Y326750D01*
X988875Y326417D01*
Y326083D01*
X988792Y325750D01*
X988625Y325458D01*
X988375Y325208D01*
X988083Y325042D01*
X987750Y325000D01*
G01X990058D02*
Y327500D01*
X991642D01*
G01X991058Y326292D02*
X990058D01*
G01X993158Y325000D02*
Y327500D01*
X994742D01*
G01X994158Y326292D02*
X993158D01*
G01X987750Y335000D02*
X987417Y335042D01*
X987125Y335208D01*
X986875Y335458D01*
X986708Y335750D01*
X986625Y336083D01*
Y336417D01*
X986708Y336750D01*
X986875Y337042D01*
X987125Y337292D01*
X987417Y337458D01*
X987750Y337500D01*
X988083Y337458D01*
X988375Y337292D01*
X988625Y337042D01*
X988792Y336750D01*
X988875Y336417D01*
Y336083D01*
X988792Y335750D01*
X988625Y335458D01*
X988375Y335208D01*
X988083Y335042D01*
X987750Y335000D01*
G01X990058D02*
Y337500D01*
X991642D01*
G01X991058Y336292D02*
X990058D01*
G01X993158Y335000D02*
Y337500D01*
X994742D01*
G01X994158Y336292D02*
X993158D01*
G01X987750Y340000D02*
X987417Y340042D01*
X987125Y340208D01*
X986875Y340458D01*
X986708Y340750D01*
X986625Y341083D01*
Y341417D01*
X986708Y341750D01*
X986875Y342042D01*
X987125Y342292D01*
X987417Y342458D01*
X987750Y342500D01*
X988083Y342458D01*
X988375Y342292D01*
X988625Y342042D01*
X988792Y341750D01*
X988875Y341417D01*
Y341083D01*
X988792Y340750D01*
X988625Y340458D01*
X988375Y340208D01*
X988083Y340042D01*
X987750Y340000D01*
G01X990058D02*
Y342500D01*
X991642D01*
G01X991058Y341292D02*
X990058D01*
G01X993158Y340000D02*
Y342500D01*
X994742D01*
G01X994158Y341292D02*
X993158D01*
G01X987750Y330000D02*
X987417Y330042D01*
X987125Y330208D01*
X986875Y330458D01*
X986708Y330750D01*
X986625Y331083D01*
Y331417D01*
X986708Y331750D01*
X986875Y332042D01*
X987125Y332292D01*
X987417Y332458D01*
X987750Y332500D01*
X988083Y332458D01*
X988375Y332292D01*
X988625Y332042D01*
X988792Y331750D01*
X988875Y331417D01*
Y331083D01*
X988792Y330750D01*
X988625Y330458D01*
X988375Y330208D01*
X988083Y330042D01*
X987750Y330000D01*
G01X990058D02*
Y332500D01*
X991642D01*
G01X991058Y331292D02*
X990058D01*
G01X993158Y330000D02*
Y332500D01*
X994742D01*
G01X994158Y331292D02*
X993158D01*
G01X983167Y357500D02*
X982333D01*
Y354167D01*
X983167D01*
G01X985017Y357500D02*
Y355000D01*
X986683D01*
G01X989783D02*
X988117D01*
Y357500D01*
X989783D01*
G01X989117Y356292D02*
X988117D01*
G01X991133Y355000D02*
Y357500D01*
X991967D01*
X992300Y357375D01*
X992550Y357208D01*
X992758Y356958D01*
X992925Y356667D01*
X992967Y356250D01*
X992925Y355833D01*
X992758Y355542D01*
X992550Y355292D01*
X992300Y355125D01*
X991967Y355000D01*
X991133D01*
G01X995150D02*
Y357500D01*
X994650Y357000D01*
G01Y355000D02*
X995650D01*
G01X997542Y355292D02*
X997833Y355083D01*
X998167Y355000D01*
X998500Y355083D01*
X998792Y355333D01*
X999000Y355708D01*
X999083Y356083D01*
Y356542D01*
X999000Y356917D01*
X998792Y357250D01*
X998542Y357417D01*
X998250Y357500D01*
X997917Y357417D01*
X997667Y357250D01*
X997500Y357000D01*
X997417Y356667D01*
X997500Y356375D01*
X997708Y356083D01*
X997958Y355917D01*
X998250Y355875D01*
X998583Y355958D01*
X998833Y356167D01*
X999083Y356542D01*
G01X1000933Y354167D02*
X1001767D01*
Y357500D01*
X1000933D01*
G01X1008167D02*
X1007333D01*
Y354167D01*
X1008167D01*
G01X1010017Y357500D02*
Y355000D01*
X1011683D01*
G01X1014783D02*
X1013117D01*
Y357500D01*
X1014783D01*
G01X1014117Y356292D02*
X1013117D01*
G01X1016133Y355000D02*
Y357500D01*
X1016967D01*
X1017300Y357375D01*
X1017550Y357208D01*
X1017758Y356958D01*
X1017925Y356667D01*
X1017967Y356250D01*
X1017925Y355833D01*
X1017758Y355542D01*
X1017550Y355292D01*
X1017300Y355125D01*
X1016967Y355000D01*
X1016133D01*
G01X1019358Y357083D02*
X1019608Y357333D01*
X1019900Y357458D01*
X1020233Y357500D01*
X1020650Y357417D01*
X1020942Y357208D01*
X1021025Y356958D01*
X1020983Y356708D01*
X1020817Y356500D01*
X1019983Y356083D01*
X1019608Y355792D01*
X1019358Y355375D01*
X1019275Y355000D01*
X1021025D01*
G01X1023250Y357500D02*
X1022917Y357417D01*
X1022667Y357208D01*
X1022500Y356958D01*
X1022375Y356625D01*
X1022333Y356250D01*
X1022375Y355875D01*
X1022500Y355542D01*
X1022667Y355292D01*
X1022917Y355083D01*
X1023250Y355000D01*
X1023583Y355083D01*
X1023833Y355292D01*
X1024000Y355542D01*
X1024125Y355875D01*
X1024167Y356250D01*
X1024125Y356625D01*
X1024000Y356958D01*
X1023833Y357208D01*
X1023583Y357417D01*
X1023250Y357500D01*
G01X1025933Y354167D02*
X1026767D01*
Y357500D01*
X1025933D01*
G01X987750Y345000D02*
X987417Y345042D01*
X987125Y345208D01*
X986875Y345458D01*
X986708Y345750D01*
X986625Y346083D01*
Y346417D01*
X986708Y346750D01*
X986875Y347042D01*
X987125Y347292D01*
X987417Y347458D01*
X987750Y347500D01*
X988083Y347458D01*
X988375Y347292D01*
X988625Y347042D01*
X988792Y346750D01*
X988875Y346417D01*
Y346083D01*
X988792Y345750D01*
X988625Y345458D01*
X988375Y345208D01*
X988083Y345042D01*
X987750Y345000D01*
G01X989892D02*
Y347500D01*
X991808Y345000D01*
Y347500D01*
G01X987750Y350000D02*
X987417Y350042D01*
X987125Y350208D01*
X986875Y350458D01*
X986708Y350750D01*
X986625Y351083D01*
Y351417D01*
X986708Y351750D01*
X986875Y352042D01*
X987125Y352292D01*
X987417Y352458D01*
X987750Y352500D01*
X988083Y352458D01*
X988375Y352292D01*
X988625Y352042D01*
X988792Y351750D01*
X988875Y351417D01*
Y351083D01*
X988792Y350750D01*
X988625Y350458D01*
X988375Y350208D01*
X988083Y350042D01*
X987750Y350000D01*
G01X990058D02*
Y352500D01*
X991642D01*
G01X991058Y351292D02*
X990058D01*
G01X993158Y350000D02*
Y352500D01*
X994742D01*
G01X994158Y351292D02*
X993158D01*
G01X1027000Y5100D02*
Y8400D01*
X1029600D01*
G01X1025700Y-500D02*
X1018800D01*
Y2800D01*
G01X1033208Y-24925D02*
Y-17825D01*
X1021408D01*
Y-1225D01*
X1027908D01*
Y7575D01*
X1054308D01*
Y-1225D01*
X1060808D01*
Y-17825D01*
X1049008D01*
Y-24925D01*
X1033208D01*
G01X1026760Y24D02*
Y4024D01*
X1019360D01*
G01X1037073Y8500D02*
X1034400D01*
G01X1095000Y15000D02*
Y-3000D01*
X1070000D01*
Y5086D01*
X1066396D01*
Y8500D01*
X1038325D01*
G01X1031030Y31632D02*
Y29632D01*
G01X1017630Y31632D02*
X1031030D01*
G01X1017630Y29632D02*
Y31632D01*
G01X1031030Y29632D02*
X1017630D01*
G01X1016703Y30207D02*
Y17807D01*
G01X1015703Y24007D02*
X1016703Y25007D01*
G01Y23007D02*
X1015703Y24007D01*
G01X1038816Y31563D02*
Y35563D01*
X1031416D01*
G01X1031621Y28921D02*
Y24921D01*
X1039021D01*
G01X1037592Y9076D02*
Y13076D01*
X1030192D01*
G01X1012676Y46962D02*
X1008676D01*
Y39562D01*
G01X1045367Y9296D02*
Y13296D01*
X1037967D01*
G01X1038895Y59775D02*
Y62275D01*
X1038395Y61775D01*
G01Y59775D02*
X1039395D01*
G01X1041370Y61442D02*
X1042620Y59775D01*
G01Y61442D02*
X1041370Y59775D01*
G01X1045095D02*
Y62275D01*
X1044595Y61775D01*
G01Y59775D02*
X1045595D01*
G01X1047403Y60817D02*
X1047695Y61108D01*
X1047945Y61275D01*
X1048278Y61358D01*
X1048570Y61275D01*
X1048778Y61108D01*
X1048945Y60858D01*
X1048987Y60567D01*
X1048945Y60317D01*
X1048778Y60067D01*
X1048528Y59858D01*
X1048237Y59775D01*
X1047903Y59858D01*
X1047612Y60108D01*
X1047445Y60483D01*
X1047403Y60900D01*
X1047487Y61442D01*
X1047612Y61733D01*
X1047820Y62025D01*
X1048112Y62233D01*
X1048403Y62275D01*
X1048695Y62192D01*
X1048903Y61983D01*
G01X1018500Y50500D02*
X1037000D01*
Y58760D01*
X1052190D01*
G01X1009778Y51109D02*
Y47109D01*
X1017178D01*
G01X1031000Y64300D02*
X1035000D01*
Y71700D01*
G01X1051069Y66298D02*
X1040269D01*
Y71498D01*
X1051069D01*
Y66298D01*
G01X1009300Y52100D02*
X1011300Y54100D01*
X1013300Y52100D01*
G01X1031000Y76967D02*
X1028500D01*
Y77967D01*
X1028625Y78300D01*
X1028917Y78550D01*
X1029250Y78633D01*
X1029583Y78550D01*
X1029833Y78342D01*
X1029958Y77967D01*
Y76967D01*
G01X1028708Y81817D02*
X1028583Y81567D01*
X1028500Y81275D01*
Y80942D01*
X1028625Y80567D01*
X1028833Y80275D01*
X1029083Y80067D01*
X1029500Y79900D01*
X1029875Y79858D01*
X1030250Y79942D01*
X1030500Y80067D01*
X1030750Y80317D01*
X1030917Y80608D01*
X1031000Y80900D01*
Y81192D01*
X1030917Y81483D01*
X1030792Y81733D01*
X1030625Y81942D01*
G01X1028917Y83208D02*
X1028667Y83458D01*
X1028542Y83750D01*
X1028500Y84083D01*
X1028583Y84500D01*
X1028792Y84792D01*
X1029042Y84875D01*
X1029292Y84833D01*
X1029500Y84667D01*
X1029917Y83833D01*
X1030208Y83458D01*
X1030625Y83208D01*
X1031000Y83125D01*
Y84875D01*
G01X1028917Y86308D02*
X1028667Y86558D01*
X1028542Y86850D01*
X1028500Y87183D01*
X1028583Y87600D01*
X1028792Y87892D01*
X1029042Y87975D01*
X1029292Y87933D01*
X1029500Y87767D01*
X1029917Y86933D01*
X1030208Y86558D01*
X1030625Y86308D01*
X1031000Y86225D01*
Y87975D01*
G01X1028917Y89408D02*
X1028667Y89658D01*
X1028542Y89950D01*
X1028500Y90283D01*
X1028583Y90700D01*
X1028792Y90992D01*
X1029042Y91075D01*
X1029292Y91033D01*
X1029500Y90867D01*
X1029917Y90033D01*
X1030208Y89658D01*
X1030625Y89408D01*
X1031000Y89325D01*
Y91075D01*
G01X1035000Y99800D02*
X1039000D01*
Y107200D01*
G01X1039500Y99800D02*
X1043500D01*
Y107200D01*
G01X1011500Y99517D02*
X1009000D01*
Y100558D01*
X1009125Y100892D01*
X1009292Y101100D01*
X1009625Y101183D01*
X1009958Y101100D01*
X1010167Y100850D01*
X1010292Y100558D01*
Y99517D01*
G01Y100558D02*
X1011500Y101183D01*
G01Y103367D02*
X1010958Y103450D01*
X1010500Y103575D01*
X1010083Y103742D01*
X1009625Y103950D01*
X1009000Y104283D01*
Y102617D01*
G01X1010458Y105758D02*
X1010167Y106050D01*
X1010000Y106300D01*
X1009917Y106633D01*
X1010000Y106925D01*
X1010167Y107133D01*
X1010417Y107300D01*
X1010708Y107342D01*
X1010958Y107300D01*
X1011208Y107133D01*
X1011417Y106883D01*
X1011500Y106592D01*
X1011417Y106258D01*
X1011167Y105967D01*
X1010792Y105800D01*
X1010375Y105758D01*
X1009833Y105842D01*
X1009542Y105967D01*
X1009250Y106175D01*
X1009042Y106467D01*
X1009000Y106758D01*
X1009083Y107050D01*
X1009292Y107258D01*
G01X1010458Y108858D02*
X1010167Y109150D01*
X1010000Y109400D01*
X1009917Y109733D01*
X1010000Y110025D01*
X1010167Y110233D01*
X1010417Y110400D01*
X1010708Y110442D01*
X1010958Y110400D01*
X1011208Y110233D01*
X1011417Y109983D01*
X1011500Y109692D01*
X1011417Y109358D01*
X1011167Y109067D01*
X1010792Y108900D01*
X1010375Y108858D01*
X1009833Y108942D01*
X1009542Y109067D01*
X1009250Y109275D01*
X1009042Y109567D01*
X1009000Y109858D01*
X1009083Y110150D01*
X1009292Y110358D01*
G01X1022000Y99800D02*
X1026000D01*
Y107200D01*
G01Y99800D02*
X1030000D01*
Y107200D01*
G01X1030500Y99800D02*
X1034500D01*
Y107200D01*
G01X1018000Y99800D02*
X1022000D01*
Y107200D01*
G01X1013948Y99800D02*
X1017948D01*
Y107200D01*
G01X1035500Y78517D02*
X1033000D01*
Y79558D01*
X1033125Y79892D01*
X1033292Y80100D01*
X1033625Y80183D01*
X1033958Y80100D01*
X1034167Y79850D01*
X1034292Y79558D01*
Y78517D01*
G01Y79558D02*
X1035500Y80183D01*
G01Y82367D02*
X1034958Y82450D01*
X1034500Y82575D01*
X1034083Y82742D01*
X1033625Y82950D01*
X1033000Y83283D01*
Y81617D01*
G01X1035500Y85550D02*
X1033000D01*
X1033500Y85050D01*
G01X1035500D02*
Y86050D01*
G01X1035125Y87733D02*
X1035333Y87983D01*
X1035458Y88275D01*
X1035500Y88650D01*
X1035417Y89025D01*
X1035250Y89317D01*
X1034958Y89525D01*
X1034625Y89567D01*
X1034292Y89483D01*
X1034083Y89275D01*
X1033917Y88983D01*
X1033875Y88692D01*
X1033917Y88400D01*
X1034083Y88025D01*
X1033000Y88150D01*
Y89275D01*
G01X1038660Y80433D02*
Y77933D01*
X1040326D01*
G01X1043426D02*
X1041760D01*
Y80433D01*
X1043426D01*
G01X1042760Y79225D02*
X1041760D01*
G01X1044776Y77933D02*
Y80433D01*
X1045610D01*
X1045943Y80308D01*
X1046193Y80141D01*
X1046401Y79891D01*
X1046568Y79600D01*
X1046610Y79183D01*
X1046568Y78766D01*
X1046401Y78475D01*
X1046193Y78225D01*
X1045943Y78058D01*
X1045610Y77933D01*
X1044776D01*
G01X1048001Y80016D02*
X1048251Y80266D01*
X1048543Y80391D01*
X1048876Y80433D01*
X1049293Y80350D01*
X1049585Y80141D01*
X1049668Y79891D01*
X1049626Y79641D01*
X1049460Y79433D01*
X1048626Y79016D01*
X1048251Y78725D01*
X1048001Y78308D01*
X1047918Y77933D01*
X1049668D01*
G01X1051893D02*
Y80433D01*
X1051393Y79933D01*
G01Y77933D02*
X1052393D01*
G01X1019213Y115157D02*
X1014055D01*
G01X1021063Y125865D02*
Y252087D01*
G01Y117007D02*
Y122165D01*
G01X1022913Y115157D02*
G02I-1850J0D01*
G01X1013655Y114757D02*
G02I-1450J0D01*
G01X1022913Y124015D02*
G02I-1450J0D01*
G01X1026200Y118500D02*
Y116000D01*
G01X1025242Y118500D02*
X1027158D01*
G01X1028467Y116000D02*
Y118500D01*
X1029467D01*
X1029800Y118375D01*
X1030050Y118083D01*
X1030133Y117750D01*
X1030050Y117417D01*
X1029842Y117167D01*
X1029467Y117042D01*
X1028467D01*
G01X1031608Y118083D02*
X1031858Y118333D01*
X1032150Y118458D01*
X1032483Y118500D01*
X1032900Y118417D01*
X1033192Y118208D01*
X1033275Y117958D01*
X1033233Y117708D01*
X1033067Y117500D01*
X1032233Y117083D01*
X1031858Y116792D01*
X1031608Y116375D01*
X1031525Y116000D01*
X1033275D01*
G01X1034792Y116292D02*
X1035083Y116083D01*
X1035417Y116000D01*
X1035750Y116083D01*
X1036042Y116333D01*
X1036250Y116708D01*
X1036333Y117083D01*
Y117542D01*
X1036250Y117917D01*
X1036042Y118250D01*
X1035792Y118417D01*
X1035500Y118500D01*
X1035167Y118417D01*
X1034917Y118250D01*
X1034750Y118000D01*
X1034667Y117667D01*
X1034750Y117375D01*
X1034958Y117083D01*
X1035208Y116917D01*
X1035500Y116875D01*
X1035833Y116958D01*
X1036083Y117167D01*
X1036333Y117542D01*
G01X1038600Y116000D02*
Y118500D01*
X1038100Y118000D01*
G01Y116000D02*
X1039100D01*
G01X1019213Y262795D02*
X1014055D01*
G01X1021063Y260945D02*
Y255787D01*
G01X1022913Y262795D02*
G02I-1850J0D01*
G01X1013655Y263195D02*
G02I-1450J0D01*
G01X1022913Y253937D02*
G02I-1450J0D01*
G01X1037750Y325000D02*
X1037417Y325042D01*
X1037125Y325208D01*
X1036875Y325458D01*
X1036708Y325750D01*
X1036625Y326083D01*
Y326417D01*
X1036708Y326750D01*
X1036875Y327042D01*
X1037125Y327292D01*
X1037417Y327458D01*
X1037750Y327500D01*
X1038083Y327458D01*
X1038375Y327292D01*
X1038625Y327042D01*
X1038792Y326750D01*
X1038875Y326417D01*
Y326083D01*
X1038792Y325750D01*
X1038625Y325458D01*
X1038375Y325208D01*
X1038083Y325042D01*
X1037750Y325000D01*
G01X1040058D02*
Y327500D01*
X1041642D01*
G01X1041058Y326292D02*
X1040058D01*
G01X1043158Y325000D02*
Y327500D01*
X1044742D01*
G01X1044158Y326292D02*
X1043158D01*
G01X1037750Y335000D02*
X1037417Y335042D01*
X1037125Y335208D01*
X1036875Y335458D01*
X1036708Y335750D01*
X1036625Y336083D01*
Y336417D01*
X1036708Y336750D01*
X1036875Y337042D01*
X1037125Y337292D01*
X1037417Y337458D01*
X1037750Y337500D01*
X1038083Y337458D01*
X1038375Y337292D01*
X1038625Y337042D01*
X1038792Y336750D01*
X1038875Y336417D01*
Y336083D01*
X1038792Y335750D01*
X1038625Y335458D01*
X1038375Y335208D01*
X1038083Y335042D01*
X1037750Y335000D01*
G01X1039892D02*
Y337500D01*
X1041808Y335000D01*
Y337500D01*
G01X1037750Y340000D02*
X1037417Y340042D01*
X1037125Y340208D01*
X1036875Y340458D01*
X1036708Y340750D01*
X1036625Y341083D01*
Y341417D01*
X1036708Y341750D01*
X1036875Y342042D01*
X1037125Y342292D01*
X1037417Y342458D01*
X1037750Y342500D01*
X1038083Y342458D01*
X1038375Y342292D01*
X1038625Y342042D01*
X1038792Y341750D01*
X1038875Y341417D01*
Y341083D01*
X1038792Y340750D01*
X1038625Y340458D01*
X1038375Y340208D01*
X1038083Y340042D01*
X1037750Y340000D01*
G01X1040058D02*
Y342500D01*
X1041642D01*
G01X1041058Y341292D02*
X1040058D01*
G01X1043158Y340000D02*
Y342500D01*
X1044742D01*
G01X1044158Y341292D02*
X1043158D01*
G01X1037750Y330000D02*
X1037417Y330042D01*
X1037125Y330208D01*
X1036875Y330458D01*
X1036708Y330750D01*
X1036625Y331083D01*
Y331417D01*
X1036708Y331750D01*
X1036875Y332042D01*
X1037125Y332292D01*
X1037417Y332458D01*
X1037750Y332500D01*
X1038083Y332458D01*
X1038375Y332292D01*
X1038625Y332042D01*
X1038792Y331750D01*
X1038875Y331417D01*
Y331083D01*
X1038792Y330750D01*
X1038625Y330458D01*
X1038375Y330208D01*
X1038083Y330042D01*
X1037750Y330000D01*
G01X1040058D02*
Y332500D01*
X1041642D01*
G01X1041058Y331292D02*
X1040058D01*
G01X1043158Y330000D02*
Y332500D01*
X1044742D01*
G01X1044158Y331292D02*
X1043158D01*
G01X1012750Y325000D02*
X1012417Y325042D01*
X1012125Y325208D01*
X1011875Y325458D01*
X1011708Y325750D01*
X1011625Y326083D01*
Y326417D01*
X1011708Y326750D01*
X1011875Y327042D01*
X1012125Y327292D01*
X1012417Y327458D01*
X1012750Y327500D01*
X1013083Y327458D01*
X1013375Y327292D01*
X1013625Y327042D01*
X1013792Y326750D01*
X1013875Y326417D01*
Y326083D01*
X1013792Y325750D01*
X1013625Y325458D01*
X1013375Y325208D01*
X1013083Y325042D01*
X1012750Y325000D01*
G01X1015058D02*
Y327500D01*
X1016642D01*
G01X1016058Y326292D02*
X1015058D01*
G01X1018158Y325000D02*
Y327500D01*
X1019742D01*
G01X1019158Y326292D02*
X1018158D01*
G01X1012750Y340000D02*
X1012417Y340042D01*
X1012125Y340208D01*
X1011875Y340458D01*
X1011708Y340750D01*
X1011625Y341083D01*
Y341417D01*
X1011708Y341750D01*
X1011875Y342042D01*
X1012125Y342292D01*
X1012417Y342458D01*
X1012750Y342500D01*
X1013083Y342458D01*
X1013375Y342292D01*
X1013625Y342042D01*
X1013792Y341750D01*
X1013875Y341417D01*
Y341083D01*
X1013792Y340750D01*
X1013625Y340458D01*
X1013375Y340208D01*
X1013083Y340042D01*
X1012750Y340000D01*
G01X1014892D02*
Y342500D01*
X1016808Y340000D01*
Y342500D01*
G01X1012750Y335000D02*
X1012417Y335042D01*
X1012125Y335208D01*
X1011875Y335458D01*
X1011708Y335750D01*
X1011625Y336083D01*
Y336417D01*
X1011708Y336750D01*
X1011875Y337042D01*
X1012125Y337292D01*
X1012417Y337458D01*
X1012750Y337500D01*
X1013083Y337458D01*
X1013375Y337292D01*
X1013625Y337042D01*
X1013792Y336750D01*
X1013875Y336417D01*
Y336083D01*
X1013792Y335750D01*
X1013625Y335458D01*
X1013375Y335208D01*
X1013083Y335042D01*
X1012750Y335000D01*
G01X1015058D02*
Y337500D01*
X1016642D01*
G01X1016058Y336292D02*
X1015058D01*
G01X1018158Y335000D02*
Y337500D01*
X1019742D01*
G01X1019158Y336292D02*
X1018158D01*
G01X1012750Y330000D02*
X1012417Y330042D01*
X1012125Y330208D01*
X1011875Y330458D01*
X1011708Y330750D01*
X1011625Y331083D01*
Y331417D01*
X1011708Y331750D01*
X1011875Y332042D01*
X1012125Y332292D01*
X1012417Y332458D01*
X1012750Y332500D01*
X1013083Y332458D01*
X1013375Y332292D01*
X1013625Y332042D01*
X1013792Y331750D01*
X1013875Y331417D01*
Y331083D01*
X1013792Y330750D01*
X1013625Y330458D01*
X1013375Y330208D01*
X1013083Y330042D01*
X1012750Y330000D01*
G01X1015058D02*
Y332500D01*
X1016642D01*
G01X1016058Y331292D02*
X1015058D01*
G01X1018158Y330000D02*
Y332500D01*
X1019742D01*
G01X1019158Y331292D02*
X1018158D01*
G01X1033167Y357500D02*
X1032333D01*
Y354167D01*
X1033167D01*
G01X1035017Y357500D02*
Y355000D01*
X1036683D01*
G01X1039783D02*
X1038117D01*
Y357500D01*
X1039783D01*
G01X1039117Y356292D02*
X1038117D01*
G01X1041133Y355000D02*
Y357500D01*
X1041967D01*
X1042300Y357375D01*
X1042550Y357208D01*
X1042758Y356958D01*
X1042925Y356667D01*
X1042967Y356250D01*
X1042925Y355833D01*
X1042758Y355542D01*
X1042550Y355292D01*
X1042300Y355125D01*
X1041967Y355000D01*
X1041133D01*
G01X1044358Y357083D02*
X1044608Y357333D01*
X1044900Y357458D01*
X1045233Y357500D01*
X1045650Y357417D01*
X1045942Y357208D01*
X1046025Y356958D01*
X1045983Y356708D01*
X1045817Y356500D01*
X1044983Y356083D01*
X1044608Y355792D01*
X1044358Y355375D01*
X1044275Y355000D01*
X1046025D01*
G01X1048250D02*
Y357500D01*
X1047750Y357000D01*
G01Y355000D02*
X1048750D01*
G01X1050933Y354167D02*
X1051767D01*
Y357500D01*
X1050933D01*
G01X1037750Y345000D02*
X1037417Y345042D01*
X1037125Y345208D01*
X1036875Y345458D01*
X1036708Y345750D01*
X1036625Y346083D01*
Y346417D01*
X1036708Y346750D01*
X1036875Y347042D01*
X1037125Y347292D01*
X1037417Y347458D01*
X1037750Y347500D01*
X1038083Y347458D01*
X1038375Y347292D01*
X1038625Y347042D01*
X1038792Y346750D01*
X1038875Y346417D01*
Y346083D01*
X1038792Y345750D01*
X1038625Y345458D01*
X1038375Y345208D01*
X1038083Y345042D01*
X1037750Y345000D01*
G01X1040058D02*
Y347500D01*
X1041642D01*
G01X1041058Y346292D02*
X1040058D01*
G01X1043158Y345000D02*
Y347500D01*
X1044742D01*
G01X1044158Y346292D02*
X1043158D01*
G01X1037750Y350000D02*
X1037417Y350042D01*
X1037125Y350208D01*
X1036875Y350458D01*
X1036708Y350750D01*
X1036625Y351083D01*
Y351417D01*
X1036708Y351750D01*
X1036875Y352042D01*
X1037125Y352292D01*
X1037417Y352458D01*
X1037750Y352500D01*
X1038083Y352458D01*
X1038375Y352292D01*
X1038625Y352042D01*
X1038792Y351750D01*
X1038875Y351417D01*
Y351083D01*
X1038792Y350750D01*
X1038625Y350458D01*
X1038375Y350208D01*
X1038083Y350042D01*
X1037750Y350000D01*
G01X1040058D02*
Y352500D01*
X1041642D01*
G01X1041058Y351292D02*
X1040058D01*
G01X1043158Y350000D02*
Y352500D01*
X1044742D01*
G01X1044158Y351292D02*
X1043158D01*
G01X1012750Y350000D02*
X1012417Y350042D01*
X1012125Y350208D01*
X1011875Y350458D01*
X1011708Y350750D01*
X1011625Y351083D01*
Y351417D01*
X1011708Y351750D01*
X1011875Y352042D01*
X1012125Y352292D01*
X1012417Y352458D01*
X1012750Y352500D01*
X1013083Y352458D01*
X1013375Y352292D01*
X1013625Y352042D01*
X1013792Y351750D01*
X1013875Y351417D01*
Y351083D01*
X1013792Y350750D01*
X1013625Y350458D01*
X1013375Y350208D01*
X1013083Y350042D01*
X1012750Y350000D01*
G01X1015058D02*
Y352500D01*
X1016642D01*
G01X1016058Y351292D02*
X1015058D01*
G01X1018158Y350000D02*
Y352500D01*
X1019742D01*
G01X1019158Y351292D02*
X1018158D01*
G01X1012750Y345000D02*
X1012417Y345042D01*
X1012125Y345208D01*
X1011875Y345458D01*
X1011708Y345750D01*
X1011625Y346083D01*
Y346417D01*
X1011708Y346750D01*
X1011875Y347042D01*
X1012125Y347292D01*
X1012417Y347458D01*
X1012750Y347500D01*
X1013083Y347458D01*
X1013375Y347292D01*
X1013625Y347042D01*
X1013792Y346750D01*
X1013875Y346417D01*
Y346083D01*
X1013792Y345750D01*
X1013625Y345458D01*
X1013375Y345208D01*
X1013083Y345042D01*
X1012750Y345000D01*
G01X1015058D02*
Y347500D01*
X1016642D01*
G01X1016058Y346292D02*
X1015058D01*
G01X1018158Y345000D02*
Y347500D01*
X1019742D01*
G01X1019158Y346292D02*
X1018158D01*
G01X1040479Y816184D02*
X1040354Y815934D01*
X1040271Y815642D01*
Y815309D01*
X1040396Y814934D01*
X1040604Y814642D01*
X1040854Y814434D01*
X1041271Y814267D01*
X1041646Y814225D01*
X1042021Y814309D01*
X1042271Y814434D01*
X1042521Y814684D01*
X1042688Y814975D01*
X1042771Y815267D01*
Y815559D01*
X1042688Y815850D01*
X1042563Y816100D01*
X1042396Y816309D01*
G01X1042771Y818367D02*
X1040271D01*
X1040771Y817867D01*
G01X1042771D02*
Y818867D01*
G01X1040271Y821467D02*
X1040354Y821134D01*
X1040563Y820884D01*
X1040813Y820717D01*
X1041146Y820592D01*
X1041521Y820550D01*
X1041896Y820592D01*
X1042229Y820717D01*
X1042479Y820884D01*
X1042688Y821134D01*
X1042771Y821467D01*
X1042688Y821800D01*
X1042479Y822050D01*
X1042229Y822217D01*
X1041896Y822342D01*
X1041521Y822384D01*
X1041146Y822342D01*
X1040813Y822217D01*
X1040563Y822050D01*
X1040354Y821800D01*
X1040271Y821467D01*
G01X1042771Y824484D02*
X1042229Y824567D01*
X1041771Y824692D01*
X1041354Y824859D01*
X1040896Y825067D01*
X1040271Y825400D01*
Y823734D01*
G01X1062958Y-14150D02*
X1063208Y-13900D01*
X1063500Y-13775D01*
X1063833Y-13733D01*
X1064250Y-13816D01*
X1064542Y-14025D01*
X1064625Y-14275D01*
X1064583Y-14525D01*
X1064417Y-14733D01*
X1063583Y-15150D01*
X1063208Y-15441D01*
X1062958Y-15858D01*
X1062875Y-16233D01*
X1064625D01*
G01X1066308Y-15400D02*
X1067392D01*
G01X1069033Y-15733D02*
X1069283Y-16025D01*
X1069617Y-16191D01*
X1069992Y-16233D01*
X1070325Y-16191D01*
X1070658Y-15983D01*
X1070867Y-15733D01*
X1070908Y-15483D01*
X1070825Y-15191D01*
X1070533Y-14983D01*
X1070242Y-14900D01*
X1069867D01*
G01X1070242D02*
X1070492Y-14775D01*
X1070700Y-14566D01*
X1070783Y-14316D01*
X1070700Y-14066D01*
X1070492Y-13858D01*
X1070117Y-13733D01*
X1069742Y-13775D01*
X1069367Y-13941D01*
G01X1073050Y-16316D02*
X1072967Y-16275D01*
Y-16191D01*
X1073050Y-16150D01*
X1073133Y-16191D01*
Y-16275D01*
X1073050Y-16316D01*
G01Y-15191D02*
X1072967Y-15150D01*
Y-15066D01*
X1073050Y-15025D01*
X1073133Y-15066D01*
Y-15150D01*
X1073050Y-15191D01*
G01X1075275Y-15900D02*
X1075608Y-16108D01*
X1075983Y-16233D01*
X1076317D01*
X1076650Y-16108D01*
X1076900Y-15900D01*
X1077025Y-15608D01*
X1076942Y-15316D01*
X1076733Y-15066D01*
X1076358Y-14900D01*
X1075858Y-14816D01*
X1075567Y-14650D01*
X1075442Y-14358D01*
X1075525Y-14066D01*
X1075733Y-13858D01*
X1076025Y-13733D01*
X1076317D01*
X1076608Y-13816D01*
X1076858Y-14025D01*
G01X1078000Y-13733D02*
X1078583Y-16233D01*
X1079250Y-13733D01*
X1079917Y-16233D01*
X1080500Y-13733D01*
G01X1081850D02*
X1082850D01*
G01X1082350D02*
Y-16233D01*
G01X1081850D02*
X1082850D01*
G01X1085450Y-13733D02*
Y-16233D01*
G01X1084492Y-13733D02*
X1086408D01*
G01X1089467Y-13941D02*
X1089217Y-13816D01*
X1088925Y-13733D01*
X1088592D01*
X1088217Y-13858D01*
X1087925Y-14066D01*
X1087717Y-14316D01*
X1087550Y-14733D01*
X1087508Y-15108D01*
X1087592Y-15483D01*
X1087717Y-15733D01*
X1087967Y-15983D01*
X1088258Y-16150D01*
X1088550Y-16233D01*
X1088842D01*
X1089133Y-16150D01*
X1089383Y-16025D01*
X1089592Y-15858D01*
G01X1090775Y-16233D02*
Y-13733D01*
G01X1092525D02*
Y-16233D01*
G01Y-14983D02*
X1090775D01*
G01X1063367Y-8133D02*
Y-5633D01*
X1064408D01*
X1064742Y-5758D01*
X1064950Y-5925D01*
X1065033Y-6258D01*
X1064950Y-6591D01*
X1064700Y-6800D01*
X1064408Y-6925D01*
X1063367D01*
G01X1064408D02*
X1065033Y-8133D01*
G01X1066425Y-7800D02*
X1066758Y-8008D01*
X1067133Y-8133D01*
X1067467D01*
X1067800Y-8008D01*
X1068050Y-7800D01*
X1068175Y-7508D01*
X1068092Y-7216D01*
X1067883Y-6966D01*
X1067508Y-6800D01*
X1067008Y-6716D01*
X1066717Y-6550D01*
X1066592Y-6258D01*
X1066675Y-5966D01*
X1066883Y-5758D01*
X1067175Y-5633D01*
X1067467D01*
X1067758Y-5716D01*
X1068008Y-5925D01*
G01X1070400Y-5633D02*
Y-8133D01*
G01X1069442Y-5633D02*
X1071358D01*
G01X1075725Y-7800D02*
X1076058Y-8008D01*
X1076433Y-8133D01*
X1076767D01*
X1077100Y-8008D01*
X1077350Y-7800D01*
X1077475Y-7508D01*
X1077392Y-7216D01*
X1077183Y-6966D01*
X1076808Y-6800D01*
X1076308Y-6716D01*
X1076017Y-6550D01*
X1075892Y-6258D01*
X1075975Y-5966D01*
X1076183Y-5758D01*
X1076475Y-5633D01*
X1076767D01*
X1077058Y-5716D01*
X1077308Y-5925D01*
G01X1078450Y-5633D02*
X1079033Y-8133D01*
X1079700Y-5633D01*
X1080367Y-8133D01*
X1080950Y-5633D01*
G01X1063600Y-12133D02*
Y-9633D01*
X1063100Y-10133D01*
G01Y-12133D02*
X1064100D01*
G01X1066158Y-11300D02*
X1067242D01*
G01X1069008Y-10050D02*
X1069258Y-9800D01*
X1069550Y-9675D01*
X1069883Y-9633D01*
X1070300Y-9716D01*
X1070592Y-9925D01*
X1070675Y-10175D01*
X1070633Y-10425D01*
X1070467Y-10633D01*
X1069633Y-11050D01*
X1069258Y-11341D01*
X1069008Y-11758D01*
X1068925Y-12133D01*
X1070675D01*
G01X1072900Y-12216D02*
X1072817Y-12175D01*
Y-12091D01*
X1072900Y-12050D01*
X1072983Y-12091D01*
Y-12175D01*
X1072900Y-12216D01*
G01Y-11091D02*
X1072817Y-11050D01*
Y-10966D01*
X1072900Y-10925D01*
X1072983Y-10966D01*
Y-11050D01*
X1072900Y-11091D01*
G01X1076333Y-10800D02*
X1076500Y-10675D01*
X1076625Y-10466D01*
X1076708Y-10175D01*
X1076625Y-9925D01*
X1076458Y-9758D01*
X1076167Y-9633D01*
X1075042D01*
Y-12133D01*
X1076417D01*
X1076708Y-11966D01*
X1076875Y-11716D01*
X1076958Y-11425D01*
X1076875Y-11133D01*
X1076625Y-10883D01*
X1076333Y-10800D01*
X1075042D01*
G01X1078017Y-12133D02*
Y-9633D01*
X1079100Y-11716D01*
X1080183Y-9633D01*
Y-12133D01*
G01X1083117Y-9841D02*
X1082867Y-9716D01*
X1082575Y-9633D01*
X1082242D01*
X1081867Y-9758D01*
X1081575Y-9966D01*
X1081367Y-10216D01*
X1081200Y-10633D01*
X1081158Y-11008D01*
X1081242Y-11383D01*
X1081367Y-11633D01*
X1081617Y-11883D01*
X1081908Y-12050D01*
X1082200Y-12133D01*
X1082492D01*
X1082783Y-12050D01*
X1083033Y-11925D01*
X1083242Y-11758D01*
G01X1087483Y-12133D02*
Y-9633D01*
X1088317D01*
X1088650Y-9758D01*
X1088900Y-9925D01*
X1089108Y-10175D01*
X1089275Y-10466D01*
X1089317Y-10883D01*
X1089275Y-11300D01*
X1089108Y-11591D01*
X1088900Y-11841D01*
X1088650Y-12008D01*
X1088317Y-12133D01*
X1087483D01*
G01X1092333D02*
X1090667D01*
Y-9633D01*
X1092333D01*
G01X1091667Y-10841D02*
X1090667D01*
G01X1093808Y-12133D02*
Y-9633D01*
X1095392D01*
G01X1094808Y-10841D02*
X1093808D01*
G01X1096658Y-12133D02*
X1097700Y-9633D01*
X1098742Y-12133D01*
G01X1098367Y-11258D02*
X1097033D01*
G01X1099883Y-9633D02*
Y-11425D01*
X1100050Y-11800D01*
X1100383Y-12050D01*
X1100800Y-12133D01*
X1101217Y-12050D01*
X1101550Y-11800D01*
X1101717Y-11425D01*
Y-9633D01*
G01X1103067D02*
Y-12133D01*
X1104733D01*
G01X1107000Y-9633D02*
Y-12133D01*
G01X1106042Y-9633D02*
X1107958D01*
G01X1063100Y-4100D02*
X1109900D01*
Y-17500D01*
X1061800D01*
Y-4100D01*
X1063100D01*
G01X1055975Y1999D02*
X1056308Y1791D01*
X1056683Y1666D01*
X1057017D01*
X1057350Y1791D01*
X1057600Y1999D01*
X1057725Y2291D01*
X1057642Y2583D01*
X1057433Y2833D01*
X1057058Y2999D01*
X1056558Y3083D01*
X1056267Y3249D01*
X1056142Y3541D01*
X1056225Y3833D01*
X1056433Y4041D01*
X1056725Y4166D01*
X1057017D01*
X1057308Y4083D01*
X1057558Y3874D01*
G01X1058700Y4166D02*
X1059283Y1666D01*
X1059950Y4166D01*
X1060617Y1666D01*
X1061200Y4166D01*
G01X1062258Y3749D02*
X1062508Y3999D01*
X1062800Y4124D01*
X1063133Y4166D01*
X1063550Y4083D01*
X1063842Y3874D01*
X1063925Y3624D01*
X1063883Y3374D01*
X1063717Y3166D01*
X1062883Y2749D01*
X1062508Y2458D01*
X1062258Y2041D01*
X1062175Y1666D01*
X1063925D01*
G01X1066150Y4166D02*
X1065817Y4083D01*
X1065567Y3874D01*
X1065400Y3624D01*
X1065275Y3291D01*
X1065233Y2916D01*
X1065275Y2541D01*
X1065400Y2208D01*
X1065567Y1958D01*
X1065817Y1749D01*
X1066150Y1666D01*
X1066483Y1749D01*
X1066733Y1958D01*
X1066900Y2208D01*
X1067025Y2541D01*
X1067067Y2916D01*
X1067025Y3291D01*
X1066900Y3624D01*
X1066733Y3874D01*
X1066483Y4083D01*
X1066150Y4166D01*
G01X1081259Y-1500D02*
Y2500D01*
X1073859D01*
G01X1059933Y14100D02*
X1060400Y14500D01*
X1060750Y15166D01*
X1060983Y16100D01*
X1060750Y16900D01*
X1060283Y17433D01*
X1059467Y17833D01*
X1056317D01*
Y9833D01*
X1060167D01*
X1060983Y10366D01*
X1061450Y11166D01*
X1061683Y12100D01*
X1061450Y13033D01*
X1060750Y13833D01*
X1059933Y14100D01*
X1056317D01*
G01X1059550Y39400D02*
Y25400D01*
G01X1046250Y39400D02*
X1059550D01*
G01X1046250Y25400D02*
Y39400D01*
G01X1059550Y25400D02*
X1046250D01*
G01X1056700Y20200D02*
Y24200D01*
X1049300D01*
G01X1046786Y13208D02*
Y9208D01*
X1054186D01*
G01X1081259Y3500D02*
Y7500D01*
X1073859D01*
G01X1081269Y20450D02*
Y24450D01*
X1073869D01*
G01X1081269Y24950D02*
Y28950D01*
X1073869D01*
G01X1081824Y33054D02*
Y37054D01*
X1074424D01*
G01X1068733Y39223D02*
X1072733D01*
Y46623D01*
G01X1070809Y18742D02*
X1066809D01*
Y11342D01*
G01X1080539Y12070D02*
Y16070D01*
X1073139D01*
G01X1073776Y20266D02*
Y16266D01*
X1081176D01*
G01X1066673Y18945D02*
X1070673D01*
Y26345D01*
G01X1060484Y64846D02*
X1060734Y65096D01*
X1061026Y65221D01*
X1061359Y65263D01*
X1061776Y65180D01*
X1062068Y64971D01*
X1062151Y64721D01*
X1062109Y64471D01*
X1061943Y64263D01*
X1061109Y63846D01*
X1060734Y63555D01*
X1060484Y63138D01*
X1060401Y62763D01*
X1062151D01*
G01X1063751Y64430D02*
X1065001Y62763D01*
G01Y64430D02*
X1063751Y62763D01*
G01X1067476D02*
X1067768Y62805D01*
X1068101Y62930D01*
X1068309Y63138D01*
X1068393Y63430D01*
X1068309Y63721D01*
X1068059Y63971D01*
X1067684Y64096D01*
X1067268D01*
X1067018Y64180D01*
X1066809Y64388D01*
X1066726Y64680D01*
X1066851Y64971D01*
X1067143Y65180D01*
X1067476Y65263D01*
X1067809Y65180D01*
X1068101Y64971D01*
X1068226Y64680D01*
X1068143Y64388D01*
X1067934Y64180D01*
X1067684Y64096D01*
X1067268D01*
X1066893Y63971D01*
X1066643Y63721D01*
X1066559Y63430D01*
X1066643Y63138D01*
X1066851Y62930D01*
X1067184Y62805D01*
X1067476Y62763D01*
G01X1060953Y57979D02*
X1069818D01*
Y62463D01*
X1080008D01*
G01X1060200Y46700D02*
Y50700D01*
X1052800D01*
G01X1081824Y37554D02*
Y41554D01*
X1074424D01*
G01X1075999Y70112D02*
X1076207Y70445D01*
X1076332Y70820D01*
Y71154D01*
X1076207Y71487D01*
X1075999Y71737D01*
X1075707Y71862D01*
X1075415Y71779D01*
X1075165Y71570D01*
X1074999Y71195D01*
X1074915Y70695D01*
X1074749Y70404D01*
X1074457Y70279D01*
X1074165Y70362D01*
X1073957Y70570D01*
X1073832Y70862D01*
Y71154D01*
X1073915Y71445D01*
X1074124Y71695D01*
G01X1076332Y73254D02*
X1073832D01*
Y74295D01*
X1073957Y74629D01*
X1074124Y74837D01*
X1074457Y74920D01*
X1074790Y74837D01*
X1074999Y74587D01*
X1075124Y74295D01*
Y73254D01*
G01Y74295D02*
X1076332Y74920D01*
G01Y77104D02*
X1075790Y77187D01*
X1075332Y77312D01*
X1074915Y77479D01*
X1074457Y77687D01*
X1073832Y78020D01*
Y76354D01*
G01X1074249Y79495D02*
X1073999Y79745D01*
X1073874Y80037D01*
X1073832Y80370D01*
X1073915Y80787D01*
X1074124Y81079D01*
X1074374Y81162D01*
X1074624Y81120D01*
X1074832Y80954D01*
X1075249Y80120D01*
X1075540Y79745D01*
X1075957Y79495D01*
X1076332Y79412D01*
Y81162D01*
G01X1075832Y82470D02*
X1076124Y82720D01*
X1076290Y83054D01*
X1076332Y83429D01*
X1076290Y83762D01*
X1076082Y84095D01*
X1075832Y84304D01*
X1075582Y84345D01*
X1075290Y84262D01*
X1075082Y83970D01*
X1074999Y83679D01*
Y83304D01*
G01Y83679D02*
X1074874Y83929D01*
X1074665Y84137D01*
X1074415Y84220D01*
X1074165Y84137D01*
X1073957Y83929D01*
X1073832Y83554D01*
X1073874Y83179D01*
X1074040Y82804D01*
G01X1072300Y70500D02*
Y66500D01*
X1079700D01*
G01X1057241Y72231D02*
X1057449Y72564D01*
X1057574Y72939D01*
Y73273D01*
X1057449Y73606D01*
X1057241Y73856D01*
X1056949Y73981D01*
X1056657Y73898D01*
X1056407Y73689D01*
X1056241Y73314D01*
X1056157Y72814D01*
X1055991Y72523D01*
X1055699Y72398D01*
X1055407Y72481D01*
X1055199Y72689D01*
X1055074Y72981D01*
Y73273D01*
X1055157Y73564D01*
X1055366Y73814D01*
G01X1057574Y75373D02*
X1055074D01*
Y76414D01*
X1055199Y76748D01*
X1055366Y76956D01*
X1055699Y77039D01*
X1056032Y76956D01*
X1056241Y76706D01*
X1056366Y76414D01*
Y75373D01*
G01Y76414D02*
X1057574Y77039D01*
G01Y79223D02*
X1057032Y79306D01*
X1056574Y79431D01*
X1056157Y79598D01*
X1055699Y79806D01*
X1055074Y80139D01*
Y78473D01*
G01X1055491Y81614D02*
X1055241Y81864D01*
X1055116Y82156D01*
X1055074Y82489D01*
X1055157Y82906D01*
X1055366Y83198D01*
X1055616Y83281D01*
X1055866Y83239D01*
X1056074Y83073D01*
X1056491Y82239D01*
X1056782Y81864D01*
X1057199Y81614D01*
X1057574Y81531D01*
Y83281D01*
G01X1055491Y84714D02*
X1055241Y84964D01*
X1055116Y85256D01*
X1055074Y85589D01*
X1055157Y86006D01*
X1055366Y86298D01*
X1055616Y86381D01*
X1055866Y86339D01*
X1056074Y86173D01*
X1056491Y85339D01*
X1056782Y84964D01*
X1057199Y84714D01*
X1057574Y84631D01*
Y86381D01*
G01X1052660Y71355D02*
Y67355D01*
X1060060D01*
G01X1054924Y59403D02*
X1055257Y59195D01*
X1055632Y59070D01*
X1055966D01*
X1056299Y59195D01*
X1056549Y59403D01*
X1056674Y59695D01*
X1056591Y59987D01*
X1056382Y60237D01*
X1056007Y60403D01*
X1055507Y60487D01*
X1055216Y60653D01*
X1055091Y60945D01*
X1055174Y61237D01*
X1055382Y61445D01*
X1055674Y61570D01*
X1055966D01*
X1056257Y61487D01*
X1056507Y61278D01*
G01X1058066Y59070D02*
Y61570D01*
X1059107D01*
X1059441Y61445D01*
X1059649Y61278D01*
X1059732Y60945D01*
X1059649Y60612D01*
X1059399Y60403D01*
X1059107Y60278D01*
X1058066D01*
G01X1059107D02*
X1059732Y59070D01*
G01X1061916D02*
X1061999Y59612D01*
X1062124Y60070D01*
X1062291Y60487D01*
X1062499Y60945D01*
X1062832Y61570D01*
X1061166D01*
G01X1065099Y59070D02*
Y61570D01*
X1064599Y61070D01*
G01Y59070D02*
X1065599D01*
G01X1068116D02*
X1068199Y59612D01*
X1068324Y60070D01*
X1068491Y60487D01*
X1068699Y60945D01*
X1069032Y61570D01*
X1067366D01*
G01X1054800Y62100D02*
Y66100D01*
X1047400D01*
G01X1060483Y50832D02*
Y46832D01*
X1067883D01*
G01X1070754Y66298D02*
X1059954D01*
Y71498D01*
X1070754D01*
Y66298D01*
G01X1081047Y86626D02*
X1069347D01*
Y117626D01*
X1081047D01*
Y86626D01*
G01X1048500Y99800D02*
X1052500D01*
Y107200D01*
G01X1044000Y99800D02*
X1048000D01*
Y107200D01*
G01X1058650Y78710D02*
Y76210D01*
X1060316D01*
G01X1063416D02*
X1061750D01*
Y78710D01*
X1063416D01*
G01X1062750Y77502D02*
X1061750D01*
G01X1064766Y76210D02*
Y78710D01*
X1065600D01*
X1065933Y78585D01*
X1066183Y78418D01*
X1066391Y78168D01*
X1066558Y77877D01*
X1066600Y77460D01*
X1066558Y77043D01*
X1066391Y76752D01*
X1066183Y76502D01*
X1065933Y76335D01*
X1065600Y76210D01*
X1064766D01*
G01X1067991Y78293D02*
X1068241Y78543D01*
X1068533Y78668D01*
X1068866Y78710D01*
X1069283Y78627D01*
X1069575Y78418D01*
X1069658Y78168D01*
X1069616Y77918D01*
X1069450Y77710D01*
X1068616Y77293D01*
X1068241Y77002D01*
X1067991Y76585D01*
X1067908Y76210D01*
X1069658D01*
G01X1071091Y78293D02*
X1071341Y78543D01*
X1071633Y78668D01*
X1071966Y78710D01*
X1072383Y78627D01*
X1072675Y78418D01*
X1072758Y78168D01*
X1072716Y77918D01*
X1072550Y77710D01*
X1071716Y77293D01*
X1071341Y77002D01*
X1071091Y76585D01*
X1071008Y76210D01*
X1072758D01*
G01X1073778Y231918D02*
Y234418D01*
X1074819D01*
X1075153Y234293D01*
X1075361Y234126D01*
X1075444Y233793D01*
X1075361Y233460D01*
X1075111Y233251D01*
X1074819Y233126D01*
X1073778D01*
G01X1074819D02*
X1075444Y231918D01*
G01X1076919Y232960D02*
X1077211Y233251D01*
X1077461Y233418D01*
X1077794Y233501D01*
X1078086Y233418D01*
X1078294Y233251D01*
X1078461Y233001D01*
X1078503Y232710D01*
X1078461Y232460D01*
X1078294Y232210D01*
X1078044Y232001D01*
X1077753Y231918D01*
X1077419Y232001D01*
X1077128Y232251D01*
X1076961Y232626D01*
X1076919Y233043D01*
X1077003Y233585D01*
X1077128Y233876D01*
X1077336Y234168D01*
X1077628Y234376D01*
X1077919Y234418D01*
X1078211Y234335D01*
X1078419Y234126D01*
G01X1080811Y234418D02*
X1080478Y234335D01*
X1080228Y234126D01*
X1080061Y233876D01*
X1079936Y233543D01*
X1079894Y233168D01*
X1079936Y232793D01*
X1080061Y232460D01*
X1080228Y232210D01*
X1080478Y232001D01*
X1080811Y231918D01*
X1081144Y232001D01*
X1081394Y232210D01*
X1081561Y232460D01*
X1081686Y232793D01*
X1081728Y233168D01*
X1081686Y233543D01*
X1081561Y233876D01*
X1081394Y234126D01*
X1081144Y234335D01*
X1080811Y234418D01*
G01X1083203Y232210D02*
X1083494Y232001D01*
X1083828Y231918D01*
X1084161Y232001D01*
X1084453Y232251D01*
X1084661Y232626D01*
X1084744Y233001D01*
Y233460D01*
X1084661Y233835D01*
X1084453Y234168D01*
X1084203Y234335D01*
X1083911Y234418D01*
X1083578Y234335D01*
X1083328Y234168D01*
X1083161Y233918D01*
X1083078Y233585D01*
X1083161Y233293D01*
X1083369Y233001D01*
X1083619Y232835D01*
X1083911Y232793D01*
X1084244Y232876D01*
X1084494Y233085D01*
X1084744Y233460D01*
G01X1076111Y227418D02*
X1075778Y227460D01*
X1075486Y227626D01*
X1075236Y227876D01*
X1075069Y228168D01*
X1074986Y228501D01*
Y228835D01*
X1075069Y229168D01*
X1075236Y229460D01*
X1075486Y229710D01*
X1075778Y229876D01*
X1076111Y229918D01*
X1076444Y229876D01*
X1076736Y229710D01*
X1076986Y229460D01*
X1077153Y229168D01*
X1077236Y228835D01*
Y228501D01*
X1077153Y228168D01*
X1076986Y227876D01*
X1076736Y227626D01*
X1076444Y227460D01*
X1076111Y227418D01*
G01X1076444Y228085D02*
X1076944Y227418D01*
G01X1078294Y227918D02*
X1078544Y227626D01*
X1078878Y227460D01*
X1079253Y227418D01*
X1079586Y227460D01*
X1079919Y227668D01*
X1080128Y227918D01*
X1080169Y228168D01*
X1080086Y228460D01*
X1079794Y228668D01*
X1079503Y228751D01*
X1079128D01*
G01X1079503D02*
X1079753Y228876D01*
X1079961Y229085D01*
X1080044Y229335D01*
X1079961Y229585D01*
X1079753Y229793D01*
X1079378Y229918D01*
X1079003Y229876D01*
X1078628Y229710D01*
G01X1081394Y227918D02*
X1081644Y227626D01*
X1081978Y227460D01*
X1082353Y227418D01*
X1082686Y227460D01*
X1083019Y227668D01*
X1083228Y227918D01*
X1083269Y228168D01*
X1083186Y228460D01*
X1082894Y228668D01*
X1082603Y228751D01*
X1082228D01*
G01X1082603D02*
X1082853Y228876D01*
X1083061Y229085D01*
X1083144Y229335D01*
X1083061Y229585D01*
X1082853Y229793D01*
X1082478Y229918D01*
X1082103Y229876D01*
X1081728Y229710D01*
G01X1105500Y288000D02*
X1068500D01*
Y247500D01*
X1162000D01*
Y288000D01*
X1105500D01*
G01X1075208Y270317D02*
X1075083Y270067D01*
X1075000Y269775D01*
Y269442D01*
X1075125Y269067D01*
X1075333Y268775D01*
X1075583Y268567D01*
X1076000Y268400D01*
X1076375Y268358D01*
X1076750Y268442D01*
X1077000Y268567D01*
X1077250Y268817D01*
X1077417Y269108D01*
X1077500Y269400D01*
Y269692D01*
X1077417Y269983D01*
X1077292Y270233D01*
X1077125Y270442D01*
G01X1075417Y271708D02*
X1075167Y271958D01*
X1075042Y272250D01*
X1075000Y272583D01*
X1075083Y273000D01*
X1075292Y273292D01*
X1075542Y273375D01*
X1075792Y273333D01*
X1076000Y273167D01*
X1076417Y272333D01*
X1076708Y271958D01*
X1077125Y271708D01*
X1077500Y271625D01*
Y273375D01*
G01X1076458Y274808D02*
X1076167Y275100D01*
X1076000Y275350D01*
X1075917Y275683D01*
X1076000Y275975D01*
X1076167Y276183D01*
X1076417Y276350D01*
X1076708Y276392D01*
X1076958Y276350D01*
X1077208Y276183D01*
X1077417Y275933D01*
X1077500Y275642D01*
X1077417Y275308D01*
X1077167Y275017D01*
X1076792Y274850D01*
X1076375Y274808D01*
X1075833Y274892D01*
X1075542Y275017D01*
X1075250Y275225D01*
X1075042Y275517D01*
X1075000Y275808D01*
X1075083Y276100D01*
X1075292Y276308D01*
G01X1071708Y270317D02*
X1071583Y270067D01*
X1071500Y269775D01*
Y269442D01*
X1071625Y269067D01*
X1071833Y268775D01*
X1072083Y268567D01*
X1072500Y268400D01*
X1072875Y268358D01*
X1073250Y268442D01*
X1073500Y268567D01*
X1073750Y268817D01*
X1073917Y269108D01*
X1074000Y269400D01*
Y269692D01*
X1073917Y269983D01*
X1073792Y270233D01*
X1073625Y270442D01*
G01X1071917Y271708D02*
X1071667Y271958D01*
X1071542Y272250D01*
X1071500Y272583D01*
X1071583Y273000D01*
X1071792Y273292D01*
X1072042Y273375D01*
X1072292Y273333D01*
X1072500Y273167D01*
X1072917Y272333D01*
X1073208Y271958D01*
X1073625Y271708D01*
X1074000Y271625D01*
Y273375D01*
G01X1073625Y274683D02*
X1073833Y274933D01*
X1073958Y275225D01*
X1074000Y275600D01*
X1073917Y275975D01*
X1073750Y276267D01*
X1073458Y276475D01*
X1073125Y276517D01*
X1072792Y276433D01*
X1072583Y276225D01*
X1072417Y275933D01*
X1072375Y275642D01*
X1072417Y275350D01*
X1072583Y274975D01*
X1071500Y275100D01*
Y276225D01*
G01X1062750Y325000D02*
X1062417Y325042D01*
X1062125Y325208D01*
X1061875Y325458D01*
X1061708Y325750D01*
X1061625Y326083D01*
Y326417D01*
X1061708Y326750D01*
X1061875Y327042D01*
X1062125Y327292D01*
X1062417Y327458D01*
X1062750Y327500D01*
X1063083Y327458D01*
X1063375Y327292D01*
X1063625Y327042D01*
X1063792Y326750D01*
X1063875Y326417D01*
Y326083D01*
X1063792Y325750D01*
X1063625Y325458D01*
X1063375Y325208D01*
X1063083Y325042D01*
X1062750Y325000D01*
G01X1065058D02*
Y327500D01*
X1066642D01*
G01X1066058Y326292D02*
X1065058D01*
G01X1068158Y325000D02*
Y327500D01*
X1069742D01*
G01X1069158Y326292D02*
X1068158D01*
G01X1062750Y340000D02*
X1062417Y340042D01*
X1062125Y340208D01*
X1061875Y340458D01*
X1061708Y340750D01*
X1061625Y341083D01*
Y341417D01*
X1061708Y341750D01*
X1061875Y342042D01*
X1062125Y342292D01*
X1062417Y342458D01*
X1062750Y342500D01*
X1063083Y342458D01*
X1063375Y342292D01*
X1063625Y342042D01*
X1063792Y341750D01*
X1063875Y341417D01*
Y341083D01*
X1063792Y340750D01*
X1063625Y340458D01*
X1063375Y340208D01*
X1063083Y340042D01*
X1062750Y340000D01*
G01X1065058D02*
Y342500D01*
X1066642D01*
G01X1066058Y341292D02*
X1065058D01*
G01X1068158Y340000D02*
Y342500D01*
X1069742D01*
G01X1069158Y341292D02*
X1068158D01*
G01X1062750Y335000D02*
X1062417Y335042D01*
X1062125Y335208D01*
X1061875Y335458D01*
X1061708Y335750D01*
X1061625Y336083D01*
Y336417D01*
X1061708Y336750D01*
X1061875Y337042D01*
X1062125Y337292D01*
X1062417Y337458D01*
X1062750Y337500D01*
X1063083Y337458D01*
X1063375Y337292D01*
X1063625Y337042D01*
X1063792Y336750D01*
X1063875Y336417D01*
Y336083D01*
X1063792Y335750D01*
X1063625Y335458D01*
X1063375Y335208D01*
X1063083Y335042D01*
X1062750Y335000D01*
G01X1065058D02*
Y337500D01*
X1066642D01*
G01X1066058Y336292D02*
X1065058D01*
G01X1068158Y335000D02*
Y337500D01*
X1069742D01*
G01X1069158Y336292D02*
X1068158D01*
G01X1062750Y330000D02*
X1062417Y330042D01*
X1062125Y330208D01*
X1061875Y330458D01*
X1061708Y330750D01*
X1061625Y331083D01*
Y331417D01*
X1061708Y331750D01*
X1061875Y332042D01*
X1062125Y332292D01*
X1062417Y332458D01*
X1062750Y332500D01*
X1063083Y332458D01*
X1063375Y332292D01*
X1063625Y332042D01*
X1063792Y331750D01*
X1063875Y331417D01*
Y331083D01*
X1063792Y330750D01*
X1063625Y330458D01*
X1063375Y330208D01*
X1063083Y330042D01*
X1062750Y330000D01*
G01X1064892D02*
Y332500D01*
X1066808Y330000D01*
Y332500D01*
G01X1058167Y357500D02*
X1057333D01*
Y354167D01*
X1058167D01*
G01X1060017Y357500D02*
Y355000D01*
X1061683D01*
G01X1064783D02*
X1063117D01*
Y357500D01*
X1064783D01*
G01X1064117Y356292D02*
X1063117D01*
G01X1066133Y355000D02*
Y357500D01*
X1066967D01*
X1067300Y357375D01*
X1067550Y357208D01*
X1067758Y356958D01*
X1067925Y356667D01*
X1067967Y356250D01*
X1067925Y355833D01*
X1067758Y355542D01*
X1067550Y355292D01*
X1067300Y355125D01*
X1066967Y355000D01*
X1066133D01*
G01X1069358Y357083D02*
X1069608Y357333D01*
X1069900Y357458D01*
X1070233Y357500D01*
X1070650Y357417D01*
X1070942Y357208D01*
X1071025Y356958D01*
X1070983Y356708D01*
X1070817Y356500D01*
X1069983Y356083D01*
X1069608Y355792D01*
X1069358Y355375D01*
X1069275Y355000D01*
X1071025D01*
G01X1072458Y357083D02*
X1072708Y357333D01*
X1073000Y357458D01*
X1073333Y357500D01*
X1073750Y357417D01*
X1074042Y357208D01*
X1074125Y356958D01*
X1074083Y356708D01*
X1073917Y356500D01*
X1073083Y356083D01*
X1072708Y355792D01*
X1072458Y355375D01*
X1072375Y355000D01*
X1074125D01*
G01X1075933Y354167D02*
X1076767D01*
Y357500D01*
X1075933D01*
G01X1062750Y350000D02*
X1062417Y350042D01*
X1062125Y350208D01*
X1061875Y350458D01*
X1061708Y350750D01*
X1061625Y351083D01*
Y351417D01*
X1061708Y351750D01*
X1061875Y352042D01*
X1062125Y352292D01*
X1062417Y352458D01*
X1062750Y352500D01*
X1063083Y352458D01*
X1063375Y352292D01*
X1063625Y352042D01*
X1063792Y351750D01*
X1063875Y351417D01*
Y351083D01*
X1063792Y350750D01*
X1063625Y350458D01*
X1063375Y350208D01*
X1063083Y350042D01*
X1062750Y350000D01*
G01X1065058D02*
Y352500D01*
X1066642D01*
G01X1066058Y351292D02*
X1065058D01*
G01X1068158Y350000D02*
Y352500D01*
X1069742D01*
G01X1069158Y351292D02*
X1068158D01*
G01X1062750Y345000D02*
X1062417Y345042D01*
X1062125Y345208D01*
X1061875Y345458D01*
X1061708Y345750D01*
X1061625Y346083D01*
Y346417D01*
X1061708Y346750D01*
X1061875Y347042D01*
X1062125Y347292D01*
X1062417Y347458D01*
X1062750Y347500D01*
X1063083Y347458D01*
X1063375Y347292D01*
X1063625Y347042D01*
X1063792Y346750D01*
X1063875Y346417D01*
Y346083D01*
X1063792Y345750D01*
X1063625Y345458D01*
X1063375Y345208D01*
X1063083Y345042D01*
X1062750Y345000D01*
G01X1065058D02*
Y347500D01*
X1066642D01*
G01X1066058Y346292D02*
X1065058D01*
G01X1068158Y345000D02*
Y347500D01*
X1069742D01*
G01X1069158Y346292D02*
X1068158D01*
G01X1044479Y816184D02*
X1044354Y815934D01*
X1044271Y815642D01*
Y815309D01*
X1044396Y814934D01*
X1044604Y814642D01*
X1044854Y814434D01*
X1045271Y814267D01*
X1045646Y814225D01*
X1046021Y814309D01*
X1046271Y814434D01*
X1046521Y814684D01*
X1046688Y814975D01*
X1046771Y815267D01*
Y815559D01*
X1046688Y815850D01*
X1046563Y816100D01*
X1046396Y816309D01*
G01X1046771Y818367D02*
X1044271D01*
X1044771Y817867D01*
G01X1046771D02*
Y818867D01*
G01X1044271Y821467D02*
X1044354Y821134D01*
X1044563Y820884D01*
X1044813Y820717D01*
X1045146Y820592D01*
X1045521Y820550D01*
X1045896Y820592D01*
X1046229Y820717D01*
X1046479Y820884D01*
X1046688Y821134D01*
X1046771Y821467D01*
X1046688Y821800D01*
X1046479Y822050D01*
X1046229Y822217D01*
X1045896Y822342D01*
X1045521Y822384D01*
X1045146Y822342D01*
X1044813Y822217D01*
X1044563Y822050D01*
X1044354Y821800D01*
X1044271Y821467D01*
G01X1045729Y823775D02*
X1045438Y824067D01*
X1045271Y824317D01*
X1045188Y824650D01*
X1045271Y824942D01*
X1045438Y825150D01*
X1045688Y825317D01*
X1045979Y825359D01*
X1046229Y825317D01*
X1046479Y825150D01*
X1046688Y824900D01*
X1046771Y824609D01*
X1046688Y824275D01*
X1046438Y823984D01*
X1046063Y823817D01*
X1045646Y823775D01*
X1045104Y823859D01*
X1044813Y823984D01*
X1044521Y824192D01*
X1044313Y824484D01*
X1044271Y824775D01*
X1044354Y825067D01*
X1044563Y825275D01*
G01X1053077Y816184D02*
X1052952Y815934D01*
X1052869Y815642D01*
Y815309D01*
X1052994Y814934D01*
X1053202Y814642D01*
X1053452Y814434D01*
X1053869Y814267D01*
X1054244Y814225D01*
X1054619Y814309D01*
X1054869Y814434D01*
X1055119Y814684D01*
X1055286Y814975D01*
X1055369Y815267D01*
Y815559D01*
X1055286Y815850D01*
X1055161Y816100D01*
X1054994Y816309D01*
G01X1055369Y818367D02*
X1052869D01*
X1053369Y817867D01*
G01X1055369D02*
Y818867D01*
G01X1052869Y821467D02*
X1052952Y821134D01*
X1053161Y820884D01*
X1053411Y820717D01*
X1053744Y820592D01*
X1054119Y820550D01*
X1054494Y820592D01*
X1054827Y820717D01*
X1055077Y820884D01*
X1055286Y821134D01*
X1055369Y821467D01*
X1055286Y821800D01*
X1055077Y822050D01*
X1054827Y822217D01*
X1054494Y822342D01*
X1054119Y822384D01*
X1053744Y822342D01*
X1053411Y822217D01*
X1053161Y822050D01*
X1052952Y821800D01*
X1052869Y821467D01*
G01X1054994Y823650D02*
X1055202Y823900D01*
X1055327Y824192D01*
X1055369Y824567D01*
X1055286Y824942D01*
X1055119Y825234D01*
X1054827Y825442D01*
X1054494Y825484D01*
X1054161Y825400D01*
X1053952Y825192D01*
X1053786Y824900D01*
X1053744Y824609D01*
X1053786Y824317D01*
X1053952Y823942D01*
X1052869Y824067D01*
Y825192D01*
G01X1057077Y816184D02*
X1056952Y815934D01*
X1056869Y815642D01*
Y815309D01*
X1056994Y814934D01*
X1057202Y814642D01*
X1057452Y814434D01*
X1057869Y814267D01*
X1058244Y814225D01*
X1058619Y814309D01*
X1058869Y814434D01*
X1059119Y814684D01*
X1059286Y814975D01*
X1059369Y815267D01*
Y815559D01*
X1059286Y815850D01*
X1059161Y816100D01*
X1058994Y816309D01*
G01X1059369Y818367D02*
X1056869D01*
X1057369Y817867D01*
G01X1059369D02*
Y818867D01*
G01X1056869Y821467D02*
X1056952Y821134D01*
X1057161Y820884D01*
X1057411Y820717D01*
X1057744Y820592D01*
X1058119Y820550D01*
X1058494Y820592D01*
X1058827Y820717D01*
X1059077Y820884D01*
X1059286Y821134D01*
X1059369Y821467D01*
X1059286Y821800D01*
X1059077Y822050D01*
X1058827Y822217D01*
X1058494Y822342D01*
X1058119Y822384D01*
X1057744Y822342D01*
X1057411Y822217D01*
X1057161Y822050D01*
X1056952Y821800D01*
X1056869Y821467D01*
G01X1059369Y825067D02*
X1056869D01*
X1058661Y823525D01*
Y825609D01*
G01X1065676Y816184D02*
X1065551Y815934D01*
X1065468Y815642D01*
Y815309D01*
X1065593Y814934D01*
X1065801Y814642D01*
X1066051Y814434D01*
X1066468Y814267D01*
X1066843Y814225D01*
X1067218Y814309D01*
X1067468Y814434D01*
X1067718Y814684D01*
X1067885Y814975D01*
X1067968Y815267D01*
Y815559D01*
X1067885Y815850D01*
X1067760Y816100D01*
X1067593Y816309D01*
G01X1067968Y818367D02*
X1065468D01*
X1065968Y817867D01*
G01X1067968D02*
Y818867D01*
G01X1065468Y821467D02*
X1065551Y821134D01*
X1065760Y820884D01*
X1066010Y820717D01*
X1066343Y820592D01*
X1066718Y820550D01*
X1067093Y820592D01*
X1067426Y820717D01*
X1067676Y820884D01*
X1067885Y821134D01*
X1067968Y821467D01*
X1067885Y821800D01*
X1067676Y822050D01*
X1067426Y822217D01*
X1067093Y822342D01*
X1066718Y822384D01*
X1066343Y822342D01*
X1066010Y822217D01*
X1065760Y822050D01*
X1065551Y821800D01*
X1065468Y821467D01*
G01X1067468Y823650D02*
X1067760Y823900D01*
X1067926Y824234D01*
X1067968Y824609D01*
X1067926Y824942D01*
X1067718Y825275D01*
X1067468Y825484D01*
X1067218Y825525D01*
X1066926Y825442D01*
X1066718Y825150D01*
X1066635Y824859D01*
Y824484D01*
G01Y824859D02*
X1066510Y825109D01*
X1066301Y825317D01*
X1066051Y825400D01*
X1065801Y825317D01*
X1065593Y825109D01*
X1065468Y824734D01*
X1065510Y824359D01*
X1065676Y823984D01*
G01X1069676Y816184D02*
X1069551Y815934D01*
X1069468Y815642D01*
Y815309D01*
X1069593Y814934D01*
X1069801Y814642D01*
X1070051Y814434D01*
X1070468Y814267D01*
X1070843Y814225D01*
X1071218Y814309D01*
X1071468Y814434D01*
X1071718Y814684D01*
X1071885Y814975D01*
X1071968Y815267D01*
Y815559D01*
X1071885Y815850D01*
X1071760Y816100D01*
X1071593Y816309D01*
G01X1071968Y818367D02*
X1069468D01*
X1069968Y817867D01*
G01X1071968D02*
Y818867D01*
G01X1069468Y821467D02*
X1069551Y821134D01*
X1069760Y820884D01*
X1070010Y820717D01*
X1070343Y820592D01*
X1070718Y820550D01*
X1071093Y820592D01*
X1071426Y820717D01*
X1071676Y820884D01*
X1071885Y821134D01*
X1071968Y821467D01*
X1071885Y821800D01*
X1071676Y822050D01*
X1071426Y822217D01*
X1071093Y822342D01*
X1070718Y822384D01*
X1070343Y822342D01*
X1070010Y822217D01*
X1069760Y822050D01*
X1069551Y821800D01*
X1069468Y821467D01*
G01X1069885Y823775D02*
X1069635Y824025D01*
X1069510Y824317D01*
X1069468Y824650D01*
X1069551Y825067D01*
X1069760Y825359D01*
X1070010Y825442D01*
X1070260Y825400D01*
X1070468Y825234D01*
X1070885Y824400D01*
X1071176Y824025D01*
X1071593Y823775D01*
X1071968Y823692D01*
Y825442D01*
G01X1085300Y2500D02*
Y-1500D01*
X1092700D01*
G01X1085300Y7000D02*
Y3000D01*
X1092700D01*
G01X1095000Y49800D02*
Y19000D01*
G01X1084920Y29440D02*
Y25440D01*
X1092320D01*
G01X1085304Y38383D02*
Y34383D01*
X1092704D01*
G01X1084920Y24940D02*
Y20940D01*
X1092320D01*
G01X1085304Y42883D02*
Y38883D01*
X1092704D01*
G01X1084525Y16177D02*
Y12177D01*
X1091925D01*
G01X1084727Y20525D02*
Y16525D01*
X1092127D01*
G01X1083163Y62229D02*
Y64729D01*
X1081621Y62937D01*
X1083705D01*
G01X1085138Y63896D02*
X1086388Y62229D01*
G01Y63896D02*
X1085138Y62229D01*
G01X1089363D02*
Y64729D01*
X1087821Y62937D01*
X1089905D01*
G01X1095156Y56587D02*
Y62870D01*
G01X1077894Y77497D02*
Y74997D01*
X1079560D01*
G01X1082660D02*
X1080994D01*
Y77497D01*
X1082660D01*
G01X1081994Y76289D02*
X1080994D01*
G01X1084010Y74997D02*
Y77497D01*
X1084844D01*
X1085177Y77372D01*
X1085427Y77205D01*
X1085635Y76955D01*
X1085802Y76664D01*
X1085844Y76247D01*
X1085802Y75830D01*
X1085635Y75539D01*
X1085427Y75289D01*
X1085177Y75122D01*
X1084844Y74997D01*
X1084010D01*
G01X1087235Y77080D02*
X1087485Y77330D01*
X1087777Y77455D01*
X1088110Y77497D01*
X1088527Y77414D01*
X1088819Y77205D01*
X1088902Y76955D01*
X1088860Y76705D01*
X1088694Y76497D01*
X1087860Y76080D01*
X1087485Y75789D01*
X1087235Y75372D01*
X1087152Y74997D01*
X1088902D01*
G01X1090210Y75497D02*
X1090460Y75205D01*
X1090794Y75039D01*
X1091169Y74997D01*
X1091502Y75039D01*
X1091835Y75247D01*
X1092044Y75497D01*
X1092085Y75747D01*
X1092002Y76039D01*
X1091710Y76247D01*
X1091419Y76330D01*
X1091044D01*
G01X1091419D02*
X1091669Y76455D01*
X1091877Y76664D01*
X1091960Y76914D01*
X1091877Y77164D01*
X1091669Y77372D01*
X1091294Y77497D01*
X1090919Y77455D01*
X1090544Y77289D01*
G01X1090439Y66298D02*
X1079639D01*
Y71498D01*
X1090439D01*
Y66298D01*
G01X1085542Y101817D02*
X1085417Y101567D01*
X1085334Y101275D01*
Y100942D01*
X1085459Y100567D01*
X1085667Y100275D01*
X1085917Y100067D01*
X1086334Y99900D01*
X1086709Y99858D01*
X1087084Y99942D01*
X1087334Y100067D01*
X1087584Y100317D01*
X1087751Y100608D01*
X1087834Y100900D01*
Y101192D01*
X1087751Y101483D01*
X1087626Y101733D01*
X1087459Y101942D01*
G01X1087834Y103042D02*
X1085334D01*
X1087834Y104958D01*
X1085334D01*
G01X1087542Y106392D02*
X1087751Y106683D01*
X1087834Y107017D01*
X1087751Y107350D01*
X1087501Y107642D01*
X1087126Y107850D01*
X1086751Y107933D01*
X1086292D01*
X1085917Y107850D01*
X1085584Y107642D01*
X1085417Y107392D01*
X1085334Y107100D01*
X1085417Y106767D01*
X1085584Y106517D01*
X1085834Y106350D01*
X1086167Y106267D01*
X1086459Y106350D01*
X1086751Y106558D01*
X1086917Y106808D01*
X1086959Y107100D01*
X1086876Y107433D01*
X1086667Y107683D01*
X1086292Y107933D01*
G01X1098380Y115970D02*
X1098130Y116095D01*
X1097838Y116178D01*
X1097505D01*
X1097130Y116053D01*
X1096838Y115845D01*
X1096630Y115595D01*
X1096463Y115178D01*
X1096421Y114803D01*
X1096505Y114428D01*
X1096630Y114178D01*
X1096880Y113928D01*
X1097171Y113761D01*
X1097463Y113678D01*
X1097755D01*
X1098046Y113761D01*
X1098296Y113886D01*
X1098505Y114053D01*
G01X1099605Y113678D02*
Y116178D01*
X1101521Y113678D01*
Y116178D01*
G01X1103663Y113678D02*
Y116178D01*
X1103163Y115678D01*
G01Y113678D02*
X1104163D01*
G01X1105971Y114720D02*
X1106263Y115011D01*
X1106513Y115178D01*
X1106846Y115261D01*
X1107138Y115178D01*
X1107346Y115011D01*
X1107513Y114761D01*
X1107555Y114470D01*
X1107513Y114220D01*
X1107346Y113970D01*
X1107096Y113761D01*
X1106805Y113678D01*
X1106471Y113761D01*
X1106180Y114011D01*
X1106013Y114386D01*
X1105971Y114803D01*
X1106055Y115345D01*
X1106180Y115636D01*
X1106388Y115928D01*
X1106680Y116136D01*
X1106971Y116178D01*
X1107263Y116095D01*
X1107471Y115886D01*
G01X1102017Y231727D02*
Y234227D01*
X1103058D01*
X1103392Y234102D01*
X1103600Y233935D01*
X1103683Y233602D01*
X1103600Y233269D01*
X1103350Y233060D01*
X1103058Y232935D01*
X1102017D01*
G01X1103058D02*
X1103683Y231727D01*
G01X1105158Y232769D02*
X1105450Y233060D01*
X1105700Y233227D01*
X1106033Y233310D01*
X1106325Y233227D01*
X1106533Y233060D01*
X1106700Y232810D01*
X1106742Y232519D01*
X1106700Y232269D01*
X1106533Y232019D01*
X1106283Y231810D01*
X1105992Y231727D01*
X1105658Y231810D01*
X1105367Y232060D01*
X1105200Y232435D01*
X1105158Y232852D01*
X1105242Y233394D01*
X1105367Y233685D01*
X1105575Y233977D01*
X1105867Y234185D01*
X1106158Y234227D01*
X1106450Y234144D01*
X1106658Y233935D01*
G01X1109550Y231727D02*
Y234227D01*
X1108008Y232435D01*
X1110092D01*
G01X1111233Y232227D02*
X1111483Y231935D01*
X1111817Y231769D01*
X1112192Y231727D01*
X1112525Y231769D01*
X1112858Y231977D01*
X1113067Y232227D01*
X1113108Y232477D01*
X1113025Y232769D01*
X1112733Y232977D01*
X1112442Y233060D01*
X1112067D01*
G01X1112442D02*
X1112692Y233185D01*
X1112900Y233394D01*
X1112983Y233644D01*
X1112900Y233894D01*
X1112692Y234102D01*
X1112317Y234227D01*
X1111942Y234185D01*
X1111567Y234019D01*
G01X1088064Y231989D02*
Y234489D01*
X1089105D01*
X1089439Y234364D01*
X1089647Y234197D01*
X1089730Y233864D01*
X1089647Y233531D01*
X1089397Y233322D01*
X1089105Y233197D01*
X1088064D01*
G01X1089105D02*
X1089730Y231989D01*
G01X1092497D02*
Y234489D01*
X1090955Y232697D01*
X1093039D01*
G01X1094305Y234072D02*
X1094555Y234322D01*
X1094847Y234447D01*
X1095180Y234489D01*
X1095597Y234406D01*
X1095889Y234197D01*
X1095972Y233947D01*
X1095930Y233697D01*
X1095764Y233489D01*
X1094930Y233072D01*
X1094555Y232781D01*
X1094305Y232364D01*
X1094222Y231989D01*
X1095972D01*
G01X1098697D02*
Y234489D01*
X1097155Y232697D01*
X1099239D01*
G01X1089897Y227489D02*
X1089564Y227531D01*
X1089272Y227697D01*
X1089022Y227947D01*
X1088855Y228239D01*
X1088772Y228572D01*
Y228906D01*
X1088855Y229239D01*
X1089022Y229531D01*
X1089272Y229781D01*
X1089564Y229947D01*
X1089897Y229989D01*
X1090230Y229947D01*
X1090522Y229781D01*
X1090772Y229531D01*
X1090939Y229239D01*
X1091022Y228906D01*
Y228572D01*
X1090939Y228239D01*
X1090772Y227947D01*
X1090522Y227697D01*
X1090230Y227531D01*
X1089897Y227489D01*
G01X1090230Y228156D02*
X1090730Y227489D01*
G01X1092080Y227989D02*
X1092330Y227697D01*
X1092664Y227531D01*
X1093039Y227489D01*
X1093372Y227531D01*
X1093705Y227739D01*
X1093914Y227989D01*
X1093955Y228239D01*
X1093872Y228531D01*
X1093580Y228739D01*
X1093289Y228822D01*
X1092914D01*
G01X1093289D02*
X1093539Y228947D01*
X1093747Y229156D01*
X1093830Y229406D01*
X1093747Y229656D01*
X1093539Y229864D01*
X1093164Y229989D01*
X1092789Y229947D01*
X1092414Y229781D01*
G01X1096097Y227489D02*
X1096389Y227531D01*
X1096722Y227656D01*
X1096930Y227864D01*
X1097014Y228156D01*
X1096930Y228447D01*
X1096680Y228697D01*
X1096305Y228822D01*
X1095889D01*
X1095639Y228906D01*
X1095430Y229114D01*
X1095347Y229406D01*
X1095472Y229697D01*
X1095764Y229906D01*
X1096097Y229989D01*
X1096430Y229906D01*
X1096722Y229697D01*
X1096847Y229406D01*
X1096764Y229114D01*
X1096555Y228906D01*
X1096305Y228822D01*
X1095889D01*
X1095514Y228697D01*
X1095264Y228447D01*
X1095180Y228156D01*
X1095264Y227864D01*
X1095472Y227656D01*
X1095805Y227531D01*
X1096097Y227489D01*
G01X1103900Y227561D02*
X1103567Y227603D01*
X1103275Y227769D01*
X1103025Y228019D01*
X1102858Y228311D01*
X1102775Y228644D01*
Y228978D01*
X1102858Y229311D01*
X1103025Y229603D01*
X1103275Y229853D01*
X1103567Y230019D01*
X1103900Y230061D01*
X1104233Y230019D01*
X1104525Y229853D01*
X1104775Y229603D01*
X1104942Y229311D01*
X1105025Y228978D01*
Y228644D01*
X1104942Y228311D01*
X1104775Y228019D01*
X1104525Y227769D01*
X1104233Y227603D01*
X1103900Y227561D01*
G01X1104233Y228228D02*
X1104733Y227561D01*
G01X1106083Y228061D02*
X1106333Y227769D01*
X1106667Y227603D01*
X1107042Y227561D01*
X1107375Y227603D01*
X1107708Y227811D01*
X1107917Y228061D01*
X1107958Y228311D01*
X1107875Y228603D01*
X1107583Y228811D01*
X1107292Y228894D01*
X1106917D01*
G01X1107292D02*
X1107542Y229019D01*
X1107750Y229228D01*
X1107833Y229478D01*
X1107750Y229728D01*
X1107542Y229936D01*
X1107167Y230061D01*
X1106792Y230019D01*
X1106417Y229853D01*
G01X1109392Y227853D02*
X1109683Y227644D01*
X1110017Y227561D01*
X1110350Y227644D01*
X1110642Y227894D01*
X1110850Y228269D01*
X1110933Y228644D01*
Y229103D01*
X1110850Y229478D01*
X1110642Y229811D01*
X1110392Y229978D01*
X1110100Y230061D01*
X1109767Y229978D01*
X1109517Y229811D01*
X1109350Y229561D01*
X1109267Y229228D01*
X1109350Y228936D01*
X1109558Y228644D01*
X1109808Y228478D01*
X1110100Y228436D01*
X1110433Y228519D01*
X1110683Y228728D01*
X1110933Y229103D01*
G01X1105317Y259900D02*
Y262400D01*
X1106358D01*
X1106692Y262275D01*
X1106900Y262108D01*
X1106983Y261775D01*
X1106900Y261442D01*
X1106650Y261233D01*
X1106358Y261108D01*
X1105317D01*
G01X1106358D02*
X1106983Y259900D01*
G01X1108458Y261983D02*
X1108708Y262233D01*
X1109000Y262358D01*
X1109333Y262400D01*
X1109750Y262317D01*
X1110042Y262108D01*
X1110125Y261858D01*
X1110083Y261608D01*
X1109917Y261400D01*
X1109083Y260983D01*
X1108708Y260692D01*
X1108458Y260275D01*
X1108375Y259900D01*
X1110125D01*
G01X1112350D02*
Y262400D01*
X1111850Y261900D01*
G01Y259900D02*
X1112850D01*
G01X1115450D02*
X1115742Y259942D01*
X1116075Y260067D01*
X1116283Y260275D01*
X1116367Y260567D01*
X1116283Y260858D01*
X1116033Y261108D01*
X1115658Y261233D01*
X1115242D01*
X1114992Y261317D01*
X1114783Y261525D01*
X1114700Y261817D01*
X1114825Y262108D01*
X1115117Y262317D01*
X1115450Y262400D01*
X1115783Y262317D01*
X1116075Y262108D01*
X1116200Y261817D01*
X1116117Y261525D01*
X1115908Y261317D01*
X1115658Y261233D01*
X1115242D01*
X1114867Y261108D01*
X1114617Y260858D01*
X1114533Y260567D01*
X1114617Y260275D01*
X1114825Y260067D01*
X1115158Y259942D01*
X1115450Y259900D01*
G01X1105817Y263700D02*
Y266200D01*
X1106858D01*
X1107192Y266075D01*
X1107400Y265908D01*
X1107483Y265575D01*
X1107400Y265242D01*
X1107150Y265033D01*
X1106858Y264908D01*
X1105817D01*
G01X1106858D02*
X1107483Y263700D01*
G01X1108958Y265783D02*
X1109208Y266033D01*
X1109500Y266158D01*
X1109833Y266200D01*
X1110250Y266117D01*
X1110542Y265908D01*
X1110625Y265658D01*
X1110583Y265408D01*
X1110417Y265200D01*
X1109583Y264783D01*
X1109208Y264492D01*
X1108958Y264075D01*
X1108875Y263700D01*
X1110625D01*
G01X1111933Y264075D02*
X1112183Y263867D01*
X1112475Y263742D01*
X1112850Y263700D01*
X1113225Y263783D01*
X1113517Y263950D01*
X1113725Y264242D01*
X1113767Y264575D01*
X1113683Y264908D01*
X1113475Y265117D01*
X1113183Y265283D01*
X1112892Y265325D01*
X1112600Y265283D01*
X1112225Y265117D01*
X1112350Y266200D01*
X1113475D01*
G01X1116450Y263700D02*
Y266200D01*
X1114908Y264408D01*
X1116992D01*
G01X1092752Y272832D02*
X1090252D01*
Y273873D01*
X1090377Y274207D01*
X1090544Y274415D01*
X1090877Y274498D01*
X1091210Y274415D01*
X1091419Y274165D01*
X1091544Y273873D01*
Y272832D01*
G01Y273873D02*
X1092752Y274498D01*
G01Y276682D02*
X1092210Y276765D01*
X1091752Y276890D01*
X1091335Y277057D01*
X1090877Y277265D01*
X1090252Y277598D01*
Y275932D01*
G01X1090669Y279073D02*
X1090419Y279323D01*
X1090294Y279615D01*
X1090252Y279948D01*
X1090335Y280365D01*
X1090544Y280657D01*
X1090794Y280740D01*
X1091044Y280698D01*
X1091252Y280532D01*
X1091669Y279698D01*
X1091960Y279323D01*
X1092377Y279073D01*
X1092752Y278990D01*
Y280740D01*
G01Y282965D02*
X1090252D01*
X1090752Y282465D01*
G01X1092752D02*
Y283465D01*
G01X1088748Y272832D02*
X1086248D01*
Y273873D01*
X1086373Y274207D01*
X1086540Y274415D01*
X1086873Y274498D01*
X1087206Y274415D01*
X1087415Y274165D01*
X1087540Y273873D01*
Y272832D01*
G01Y273873D02*
X1088748Y274498D01*
G01Y276682D02*
X1088206Y276765D01*
X1087748Y276890D01*
X1087331Y277057D01*
X1086873Y277265D01*
X1086248Y277598D01*
Y275932D01*
G01X1086665Y279073D02*
X1086415Y279323D01*
X1086290Y279615D01*
X1086248Y279948D01*
X1086331Y280365D01*
X1086540Y280657D01*
X1086790Y280740D01*
X1087040Y280698D01*
X1087248Y280532D01*
X1087665Y279698D01*
X1087956Y279323D01*
X1088373Y279073D01*
X1088748Y278990D01*
Y280740D01*
G01X1088456Y282257D02*
X1088665Y282548D01*
X1088748Y282882D01*
X1088665Y283215D01*
X1088415Y283507D01*
X1088040Y283715D01*
X1087665Y283798D01*
X1087206D01*
X1086831Y283715D01*
X1086498Y283507D01*
X1086331Y283257D01*
X1086248Y282965D01*
X1086331Y282632D01*
X1086498Y282382D01*
X1086748Y282215D01*
X1087081Y282132D01*
X1087373Y282215D01*
X1087665Y282423D01*
X1087831Y282673D01*
X1087873Y282965D01*
X1087790Y283298D01*
X1087581Y283548D01*
X1087206Y283798D01*
G01X1108708Y270317D02*
X1108583Y270067D01*
X1108500Y269775D01*
Y269442D01*
X1108625Y269067D01*
X1108833Y268775D01*
X1109083Y268567D01*
X1109500Y268400D01*
X1109875Y268358D01*
X1110250Y268442D01*
X1110500Y268567D01*
X1110750Y268817D01*
X1110917Y269108D01*
X1111000Y269400D01*
Y269692D01*
X1110917Y269983D01*
X1110792Y270233D01*
X1110625Y270442D01*
G01X1108917Y271708D02*
X1108667Y271958D01*
X1108542Y272250D01*
X1108500Y272583D01*
X1108583Y273000D01*
X1108792Y273292D01*
X1109042Y273375D01*
X1109292Y273333D01*
X1109500Y273167D01*
X1109917Y272333D01*
X1110208Y271958D01*
X1110625Y271708D01*
X1111000Y271625D01*
Y273375D01*
G01X1110500Y274683D02*
X1110792Y274933D01*
X1110958Y275267D01*
X1111000Y275642D01*
X1110958Y275975D01*
X1110750Y276308D01*
X1110500Y276517D01*
X1110250Y276558D01*
X1109958Y276475D01*
X1109750Y276183D01*
X1109667Y275892D01*
Y275517D01*
G01Y275892D02*
X1109542Y276142D01*
X1109333Y276350D01*
X1109083Y276433D01*
X1108833Y276350D01*
X1108625Y276142D01*
X1108500Y275767D01*
X1108542Y275392D01*
X1108708Y275017D01*
G01X1105017Y270429D02*
X1104892Y270179D01*
X1104809Y269887D01*
Y269554D01*
X1104934Y269179D01*
X1105142Y268887D01*
X1105392Y268679D01*
X1105809Y268512D01*
X1106184Y268470D01*
X1106559Y268554D01*
X1106809Y268679D01*
X1107059Y268929D01*
X1107226Y269220D01*
X1107309Y269512D01*
Y269804D01*
X1107226Y270095D01*
X1107101Y270345D01*
X1106934Y270554D01*
G01X1105226Y271820D02*
X1104976Y272070D01*
X1104851Y272362D01*
X1104809Y272695D01*
X1104892Y273112D01*
X1105101Y273404D01*
X1105351Y273487D01*
X1105601Y273445D01*
X1105809Y273279D01*
X1106226Y272445D01*
X1106517Y272070D01*
X1106934Y271820D01*
X1107309Y271737D01*
Y273487D01*
G01X1105226Y274920D02*
X1104976Y275170D01*
X1104851Y275462D01*
X1104809Y275795D01*
X1104892Y276212D01*
X1105101Y276504D01*
X1105351Y276587D01*
X1105601Y276545D01*
X1105809Y276379D01*
X1106226Y275545D01*
X1106517Y275170D01*
X1106934Y274920D01*
X1107309Y274837D01*
Y276587D01*
G01X1101517Y270429D02*
X1101392Y270179D01*
X1101309Y269887D01*
Y269554D01*
X1101434Y269179D01*
X1101642Y268887D01*
X1101892Y268679D01*
X1102309Y268512D01*
X1102684Y268470D01*
X1103059Y268554D01*
X1103309Y268679D01*
X1103559Y268929D01*
X1103726Y269220D01*
X1103809Y269512D01*
Y269804D01*
X1103726Y270095D01*
X1103601Y270345D01*
X1103434Y270554D01*
G01X1101726Y271820D02*
X1101476Y272070D01*
X1101351Y272362D01*
X1101309Y272695D01*
X1101392Y273112D01*
X1101601Y273404D01*
X1101851Y273487D01*
X1102101Y273445D01*
X1102309Y273279D01*
X1102726Y272445D01*
X1103017Y272070D01*
X1103434Y271820D01*
X1103809Y271737D01*
Y273487D01*
G01Y275712D02*
X1101309D01*
X1101809Y275212D01*
G01X1103809D02*
Y276212D01*
G01X1097656Y270426D02*
X1097531Y270176D01*
X1097448Y269884D01*
Y269551D01*
X1097573Y269176D01*
X1097781Y268884D01*
X1098031Y268676D01*
X1098448Y268509D01*
X1098823Y268467D01*
X1099198Y268551D01*
X1099448Y268676D01*
X1099698Y268926D01*
X1099865Y269217D01*
X1099948Y269509D01*
Y269801D01*
X1099865Y270092D01*
X1099740Y270342D01*
X1099573Y270551D01*
G01X1097865Y271817D02*
X1097615Y272067D01*
X1097490Y272359D01*
X1097448Y272692D01*
X1097531Y273109D01*
X1097740Y273401D01*
X1097990Y273484D01*
X1098240Y273442D01*
X1098448Y273276D01*
X1098865Y272442D01*
X1099156Y272067D01*
X1099573Y271817D01*
X1099948Y271734D01*
Y273484D01*
G01X1097448Y275709D02*
X1097531Y275376D01*
X1097740Y275126D01*
X1097990Y274959D01*
X1098323Y274834D01*
X1098698Y274792D01*
X1099073Y274834D01*
X1099406Y274959D01*
X1099656Y275126D01*
X1099865Y275376D01*
X1099948Y275709D01*
X1099865Y276042D01*
X1099656Y276292D01*
X1099406Y276459D01*
X1099073Y276584D01*
X1098698Y276626D01*
X1098323Y276584D01*
X1097990Y276459D01*
X1097740Y276292D01*
X1097531Y276042D01*
X1097448Y275709D01*
G01X1094156Y270426D02*
X1094031Y270176D01*
X1093948Y269884D01*
Y269551D01*
X1094073Y269176D01*
X1094281Y268884D01*
X1094531Y268676D01*
X1094948Y268509D01*
X1095323Y268467D01*
X1095698Y268551D01*
X1095948Y268676D01*
X1096198Y268926D01*
X1096365Y269217D01*
X1096448Y269509D01*
Y269801D01*
X1096365Y270092D01*
X1096240Y270342D01*
X1096073Y270551D01*
G01X1096448Y272609D02*
X1093948D01*
X1094448Y272109D01*
G01X1096448D02*
Y273109D01*
G01X1096156Y275001D02*
X1096365Y275292D01*
X1096448Y275626D01*
X1096365Y275959D01*
X1096115Y276251D01*
X1095740Y276459D01*
X1095365Y276542D01*
X1094906D01*
X1094531Y276459D01*
X1094198Y276251D01*
X1094031Y276001D01*
X1093948Y275709D01*
X1094031Y275376D01*
X1094198Y275126D01*
X1094448Y274959D01*
X1094781Y274876D01*
X1095073Y274959D01*
X1095365Y275167D01*
X1095531Y275417D01*
X1095573Y275709D01*
X1095490Y276042D01*
X1095281Y276292D01*
X1094906Y276542D01*
G01X1082657Y270247D02*
X1082532Y269997D01*
X1082449Y269705D01*
Y269372D01*
X1082574Y268997D01*
X1082782Y268705D01*
X1083032Y268497D01*
X1083449Y268330D01*
X1083824Y268288D01*
X1084199Y268372D01*
X1084449Y268497D01*
X1084699Y268747D01*
X1084866Y269038D01*
X1084949Y269330D01*
Y269622D01*
X1084866Y269913D01*
X1084741Y270163D01*
X1084574Y270372D01*
G01X1084949Y272430D02*
X1082449D01*
X1082949Y271930D01*
G01X1084949D02*
Y272930D01*
G01Y275530D02*
X1084907Y275822D01*
X1084782Y276155D01*
X1084574Y276363D01*
X1084282Y276447D01*
X1083991Y276363D01*
X1083741Y276113D01*
X1083616Y275738D01*
Y275322D01*
X1083532Y275072D01*
X1083324Y274863D01*
X1083032Y274780D01*
X1082741Y274905D01*
X1082532Y275197D01*
X1082449Y275530D01*
X1082532Y275863D01*
X1082741Y276155D01*
X1083032Y276280D01*
X1083324Y276197D01*
X1083532Y275988D01*
X1083616Y275738D01*
Y275322D01*
X1083741Y274947D01*
X1083991Y274697D01*
X1084282Y274613D01*
X1084574Y274697D01*
X1084782Y274905D01*
X1084907Y275238D01*
X1084949Y275530D01*
G01X1079157Y270247D02*
X1079032Y269997D01*
X1078949Y269705D01*
Y269372D01*
X1079074Y268997D01*
X1079282Y268705D01*
X1079532Y268497D01*
X1079949Y268330D01*
X1080324Y268288D01*
X1080699Y268372D01*
X1080949Y268497D01*
X1081199Y268747D01*
X1081366Y269038D01*
X1081449Y269330D01*
Y269622D01*
X1081366Y269913D01*
X1081241Y270163D01*
X1081074Y270372D01*
G01X1081449Y272430D02*
X1078949D01*
X1079449Y271930D01*
G01X1081449D02*
Y272930D01*
G01Y275447D02*
X1080907Y275530D01*
X1080449Y275655D01*
X1080032Y275822D01*
X1079574Y276030D01*
X1078949Y276363D01*
Y274697D01*
G01X1087750Y325000D02*
X1087417Y325042D01*
X1087125Y325208D01*
X1086875Y325458D01*
X1086708Y325750D01*
X1086625Y326083D01*
Y326417D01*
X1086708Y326750D01*
X1086875Y327042D01*
X1087125Y327292D01*
X1087417Y327458D01*
X1087750Y327500D01*
X1088083Y327458D01*
X1088375Y327292D01*
X1088625Y327042D01*
X1088792Y326750D01*
X1088875Y326417D01*
Y326083D01*
X1088792Y325750D01*
X1088625Y325458D01*
X1088375Y325208D01*
X1088083Y325042D01*
X1087750Y325000D01*
G01X1089892D02*
Y327500D01*
X1091808Y325000D01*
Y327500D01*
G01X1087750Y335000D02*
X1087417Y335042D01*
X1087125Y335208D01*
X1086875Y335458D01*
X1086708Y335750D01*
X1086625Y336083D01*
Y336417D01*
X1086708Y336750D01*
X1086875Y337042D01*
X1087125Y337292D01*
X1087417Y337458D01*
X1087750Y337500D01*
X1088083Y337458D01*
X1088375Y337292D01*
X1088625Y337042D01*
X1088792Y336750D01*
X1088875Y336417D01*
Y336083D01*
X1088792Y335750D01*
X1088625Y335458D01*
X1088375Y335208D01*
X1088083Y335042D01*
X1087750Y335000D01*
G01X1090058D02*
Y337500D01*
X1091642D01*
G01X1091058Y336292D02*
X1090058D01*
G01X1093158Y335000D02*
Y337500D01*
X1094742D01*
G01X1094158Y336292D02*
X1093158D01*
G01X1087750Y340000D02*
X1087417Y340042D01*
X1087125Y340208D01*
X1086875Y340458D01*
X1086708Y340750D01*
X1086625Y341083D01*
Y341417D01*
X1086708Y341750D01*
X1086875Y342042D01*
X1087125Y342292D01*
X1087417Y342458D01*
X1087750Y342500D01*
X1088083Y342458D01*
X1088375Y342292D01*
X1088625Y342042D01*
X1088792Y341750D01*
X1088875Y341417D01*
Y341083D01*
X1088792Y340750D01*
X1088625Y340458D01*
X1088375Y340208D01*
X1088083Y340042D01*
X1087750Y340000D01*
G01X1090058D02*
Y342500D01*
X1091642D01*
G01X1091058Y341292D02*
X1090058D01*
G01X1093158Y340000D02*
Y342500D01*
X1094742D01*
G01X1094158Y341292D02*
X1093158D01*
G01X1087750Y330000D02*
X1087417Y330042D01*
X1087125Y330208D01*
X1086875Y330458D01*
X1086708Y330750D01*
X1086625Y331083D01*
Y331417D01*
X1086708Y331750D01*
X1086875Y332042D01*
X1087125Y332292D01*
X1087417Y332458D01*
X1087750Y332500D01*
X1088083Y332458D01*
X1088375Y332292D01*
X1088625Y332042D01*
X1088792Y331750D01*
X1088875Y331417D01*
Y331083D01*
X1088792Y330750D01*
X1088625Y330458D01*
X1088375Y330208D01*
X1088083Y330042D01*
X1087750Y330000D01*
G01X1090058D02*
Y332500D01*
X1091642D01*
G01X1091058Y331292D02*
X1090058D01*
G01X1093158Y330000D02*
Y332500D01*
X1094742D01*
G01X1094158Y331292D02*
X1093158D01*
G01X1087750Y345000D02*
X1087417Y345042D01*
X1087125Y345208D01*
X1086875Y345458D01*
X1086708Y345750D01*
X1086625Y346083D01*
Y346417D01*
X1086708Y346750D01*
X1086875Y347042D01*
X1087125Y347292D01*
X1087417Y347458D01*
X1087750Y347500D01*
X1088083Y347458D01*
X1088375Y347292D01*
X1088625Y347042D01*
X1088792Y346750D01*
X1088875Y346417D01*
Y346083D01*
X1088792Y345750D01*
X1088625Y345458D01*
X1088375Y345208D01*
X1088083Y345042D01*
X1087750Y345000D01*
G01X1090058D02*
Y347500D01*
X1091642D01*
G01X1091058Y346292D02*
X1090058D01*
G01X1093158Y345000D02*
Y347500D01*
X1094742D01*
G01X1094158Y346292D02*
X1093158D01*
G01X1087750Y350000D02*
X1087417Y350042D01*
X1087125Y350208D01*
X1086875Y350458D01*
X1086708Y350750D01*
X1086625Y351083D01*
Y351417D01*
X1086708Y351750D01*
X1086875Y352042D01*
X1087125Y352292D01*
X1087417Y352458D01*
X1087750Y352500D01*
X1088083Y352458D01*
X1088375Y352292D01*
X1088625Y352042D01*
X1088792Y351750D01*
X1088875Y351417D01*
Y351083D01*
X1088792Y350750D01*
X1088625Y350458D01*
X1088375Y350208D01*
X1088083Y350042D01*
X1087750Y350000D01*
G01X1090058D02*
Y352500D01*
X1091642D01*
G01X1091058Y351292D02*
X1090058D01*
G01X1093158Y350000D02*
Y352500D01*
X1094742D01*
G01X1094158Y351292D02*
X1093158D01*
G01X1083167Y357500D02*
X1082333D01*
Y354167D01*
X1083167D01*
G01X1085017Y357500D02*
Y355000D01*
X1086683D01*
G01X1089783D02*
X1088117D01*
Y357500D01*
X1089783D01*
G01X1089117Y356292D02*
X1088117D01*
G01X1091133Y355000D02*
Y357500D01*
X1091967D01*
X1092300Y357375D01*
X1092550Y357208D01*
X1092758Y356958D01*
X1092925Y356667D01*
X1092967Y356250D01*
X1092925Y355833D01*
X1092758Y355542D01*
X1092550Y355292D01*
X1092300Y355125D01*
X1091967Y355000D01*
X1091133D01*
G01X1094358Y357083D02*
X1094608Y357333D01*
X1094900Y357458D01*
X1095233Y357500D01*
X1095650Y357417D01*
X1095942Y357208D01*
X1096025Y356958D01*
X1095983Y356708D01*
X1095817Y356500D01*
X1094983Y356083D01*
X1094608Y355792D01*
X1094358Y355375D01*
X1094275Y355000D01*
X1096025D01*
G01X1097333Y355500D02*
X1097583Y355208D01*
X1097917Y355042D01*
X1098292Y355000D01*
X1098625Y355042D01*
X1098958Y355250D01*
X1099167Y355500D01*
X1099208Y355750D01*
X1099125Y356042D01*
X1098833Y356250D01*
X1098542Y356333D01*
X1098167D01*
G01X1098542D02*
X1098792Y356458D01*
X1099000Y356667D01*
X1099083Y356917D01*
X1099000Y357167D01*
X1098792Y357375D01*
X1098417Y357500D01*
X1098042Y357458D01*
X1097667Y357292D01*
G01X1100933Y354167D02*
X1101767D01*
Y357500D01*
X1100933D01*
G01X1090872Y817734D02*
X1090747Y817484D01*
X1090664Y817192D01*
Y816859D01*
X1090789Y816484D01*
X1090997Y816192D01*
X1091247Y815984D01*
X1091664Y815817D01*
X1092039Y815775D01*
X1092414Y815859D01*
X1092664Y815984D01*
X1092914Y816234D01*
X1093081Y816525D01*
X1093164Y816817D01*
Y817109D01*
X1093081Y817400D01*
X1092956Y817650D01*
X1092789Y817859D01*
G01X1092872Y819209D02*
X1093081Y819500D01*
X1093164Y819834D01*
X1093081Y820167D01*
X1092831Y820459D01*
X1092456Y820667D01*
X1092081Y820750D01*
X1091622D01*
X1091247Y820667D01*
X1090914Y820459D01*
X1090747Y820209D01*
X1090664Y819917D01*
X1090747Y819584D01*
X1090914Y819334D01*
X1091164Y819167D01*
X1091497Y819084D01*
X1091789Y819167D01*
X1092081Y819375D01*
X1092247Y819625D01*
X1092289Y819917D01*
X1092206Y820250D01*
X1091997Y820500D01*
X1091622Y820750D01*
G01X1092872Y822309D02*
X1093081Y822600D01*
X1093164Y822934D01*
X1093081Y823267D01*
X1092831Y823559D01*
X1092456Y823767D01*
X1092081Y823850D01*
X1091622D01*
X1091247Y823767D01*
X1090914Y823559D01*
X1090747Y823309D01*
X1090664Y823017D01*
X1090747Y822684D01*
X1090914Y822434D01*
X1091164Y822267D01*
X1091497Y822184D01*
X1091789Y822267D01*
X1092081Y822475D01*
X1092247Y822725D01*
X1092289Y823017D01*
X1092206Y823350D01*
X1091997Y823600D01*
X1091622Y823850D01*
G01X1094872Y817734D02*
X1094747Y817484D01*
X1094664Y817192D01*
Y816859D01*
X1094789Y816484D01*
X1094997Y816192D01*
X1095247Y815984D01*
X1095664Y815817D01*
X1096039Y815775D01*
X1096414Y815859D01*
X1096664Y815984D01*
X1096914Y816234D01*
X1097081Y816525D01*
X1097164Y816817D01*
Y817109D01*
X1097081Y817400D01*
X1096956Y817650D01*
X1096789Y817859D01*
G01X1096872Y819209D02*
X1097081Y819500D01*
X1097164Y819834D01*
X1097081Y820167D01*
X1096831Y820459D01*
X1096456Y820667D01*
X1096081Y820750D01*
X1095622D01*
X1095247Y820667D01*
X1094914Y820459D01*
X1094747Y820209D01*
X1094664Y819917D01*
X1094747Y819584D01*
X1094914Y819334D01*
X1095164Y819167D01*
X1095497Y819084D01*
X1095789Y819167D01*
X1096081Y819375D01*
X1096247Y819625D01*
X1096289Y819917D01*
X1096206Y820250D01*
X1095997Y820500D01*
X1095622Y820750D01*
G01X1097164Y823017D02*
X1097122Y823309D01*
X1096997Y823642D01*
X1096789Y823850D01*
X1096497Y823934D01*
X1096206Y823850D01*
X1095956Y823600D01*
X1095831Y823225D01*
Y822809D01*
X1095747Y822559D01*
X1095539Y822350D01*
X1095247Y822267D01*
X1094956Y822392D01*
X1094747Y822684D01*
X1094664Y823017D01*
X1094747Y823350D01*
X1094956Y823642D01*
X1095247Y823767D01*
X1095539Y823684D01*
X1095747Y823475D01*
X1095831Y823225D01*
Y822809D01*
X1095956Y822434D01*
X1096206Y822184D01*
X1096497Y822100D01*
X1096789Y822184D01*
X1096997Y822392D01*
X1097122Y822725D01*
X1097164Y823017D01*
G01X1103471Y817734D02*
X1103346Y817484D01*
X1103263Y817192D01*
Y816859D01*
X1103388Y816484D01*
X1103596Y816192D01*
X1103846Y815984D01*
X1104263Y815817D01*
X1104638Y815775D01*
X1105013Y815859D01*
X1105263Y815984D01*
X1105513Y816234D01*
X1105680Y816525D01*
X1105763Y816817D01*
Y817109D01*
X1105680Y817400D01*
X1105555Y817650D01*
X1105388Y817859D01*
G01X1105471Y819209D02*
X1105680Y819500D01*
X1105763Y819834D01*
X1105680Y820167D01*
X1105430Y820459D01*
X1105055Y820667D01*
X1104680Y820750D01*
X1104221D01*
X1103846Y820667D01*
X1103513Y820459D01*
X1103346Y820209D01*
X1103263Y819917D01*
X1103346Y819584D01*
X1103513Y819334D01*
X1103763Y819167D01*
X1104096Y819084D01*
X1104388Y819167D01*
X1104680Y819375D01*
X1104846Y819625D01*
X1104888Y819917D01*
X1104805Y820250D01*
X1104596Y820500D01*
X1104221Y820750D01*
G01X1105763Y822934D02*
X1105221Y823017D01*
X1104763Y823142D01*
X1104346Y823309D01*
X1103888Y823517D01*
X1103263Y823850D01*
Y822184D01*
G01X1107471Y817734D02*
X1107346Y817484D01*
X1107263Y817192D01*
Y816859D01*
X1107388Y816484D01*
X1107596Y816192D01*
X1107846Y815984D01*
X1108263Y815817D01*
X1108638Y815775D01*
X1109013Y815859D01*
X1109263Y815984D01*
X1109513Y816234D01*
X1109680Y816525D01*
X1109763Y816817D01*
Y817109D01*
X1109680Y817400D01*
X1109555Y817650D01*
X1109388Y817859D01*
G01X1109471Y819209D02*
X1109680Y819500D01*
X1109763Y819834D01*
X1109680Y820167D01*
X1109430Y820459D01*
X1109055Y820667D01*
X1108680Y820750D01*
X1108221D01*
X1107846Y820667D01*
X1107513Y820459D01*
X1107346Y820209D01*
X1107263Y819917D01*
X1107346Y819584D01*
X1107513Y819334D01*
X1107763Y819167D01*
X1108096Y819084D01*
X1108388Y819167D01*
X1108680Y819375D01*
X1108846Y819625D01*
X1108888Y819917D01*
X1108805Y820250D01*
X1108596Y820500D01*
X1108221Y820750D01*
G01X1108721Y822225D02*
X1108430Y822517D01*
X1108263Y822767D01*
X1108180Y823100D01*
X1108263Y823392D01*
X1108430Y823600D01*
X1108680Y823767D01*
X1108971Y823809D01*
X1109221Y823767D01*
X1109471Y823600D01*
X1109680Y823350D01*
X1109763Y823059D01*
X1109680Y822725D01*
X1109430Y822434D01*
X1109055Y822267D01*
X1108638Y822225D01*
X1108096Y822309D01*
X1107805Y822434D01*
X1107513Y822642D01*
X1107305Y822934D01*
X1107263Y823225D01*
X1107346Y823517D01*
X1107555Y823725D01*
G01X1078274Y816184D02*
X1078149Y815934D01*
X1078066Y815642D01*
Y815309D01*
X1078191Y814934D01*
X1078399Y814642D01*
X1078649Y814434D01*
X1079066Y814267D01*
X1079441Y814225D01*
X1079816Y814309D01*
X1080066Y814434D01*
X1080316Y814684D01*
X1080483Y814975D01*
X1080566Y815267D01*
Y815559D01*
X1080483Y815850D01*
X1080358Y816100D01*
X1080191Y816309D01*
G01X1080566Y818367D02*
X1078066D01*
X1078566Y817867D01*
G01X1080566D02*
Y818867D01*
G01X1078066Y821467D02*
X1078149Y821134D01*
X1078358Y820884D01*
X1078608Y820717D01*
X1078941Y820592D01*
X1079316Y820550D01*
X1079691Y820592D01*
X1080024Y820717D01*
X1080274Y820884D01*
X1080483Y821134D01*
X1080566Y821467D01*
X1080483Y821800D01*
X1080274Y822050D01*
X1080024Y822217D01*
X1079691Y822342D01*
X1079316Y822384D01*
X1078941Y822342D01*
X1078608Y822217D01*
X1078358Y822050D01*
X1078149Y821800D01*
X1078066Y821467D01*
G01X1080566Y824567D02*
X1078066D01*
X1078566Y824067D01*
G01X1080566D02*
Y825067D01*
G01X1082274Y816184D02*
X1082149Y815934D01*
X1082066Y815642D01*
Y815309D01*
X1082191Y814934D01*
X1082399Y814642D01*
X1082649Y814434D01*
X1083066Y814267D01*
X1083441Y814225D01*
X1083816Y814309D01*
X1084066Y814434D01*
X1084316Y814684D01*
X1084483Y814975D01*
X1084566Y815267D01*
Y815559D01*
X1084483Y815850D01*
X1084358Y816100D01*
X1084191Y816309D01*
G01X1084566Y818367D02*
X1082066D01*
X1082566Y817867D01*
G01X1084566D02*
Y818867D01*
G01X1082066Y821467D02*
X1082149Y821134D01*
X1082358Y820884D01*
X1082608Y820717D01*
X1082941Y820592D01*
X1083316Y820550D01*
X1083691Y820592D01*
X1084024Y820717D01*
X1084274Y820884D01*
X1084483Y821134D01*
X1084566Y821467D01*
X1084483Y821800D01*
X1084274Y822050D01*
X1084024Y822217D01*
X1083691Y822342D01*
X1083316Y822384D01*
X1082941Y822342D01*
X1082608Y822217D01*
X1082358Y822050D01*
X1082149Y821800D01*
X1082066Y821467D01*
G01Y824567D02*
X1082149Y824234D01*
X1082358Y823984D01*
X1082608Y823817D01*
X1082941Y823692D01*
X1083316Y823650D01*
X1083691Y823692D01*
X1084024Y823817D01*
X1084274Y823984D01*
X1084483Y824234D01*
X1084566Y824567D01*
X1084483Y824900D01*
X1084274Y825150D01*
X1084024Y825317D01*
X1083691Y825442D01*
X1083316Y825484D01*
X1082941Y825442D01*
X1082608Y825317D01*
X1082358Y825150D01*
X1082149Y824900D01*
X1082066Y824567D01*
G01X1112035Y-43680D02*
Y109220D01*
X1294535D01*
Y-43680D01*
X1112035D01*
G01X1294535Y-19527D02*
X1112035D01*
G01X1140800Y111700D02*
X1143300Y116700D01*
X1145800Y111700D01*
G01X1144900Y113450D02*
X1141700D01*
G01X1112935Y131139D02*
X1112685Y131264D01*
X1112393Y131347D01*
X1112060D01*
X1111685Y131222D01*
X1111393Y131014D01*
X1111185Y130764D01*
X1111018Y130347D01*
X1110976Y129972D01*
X1111060Y129597D01*
X1111185Y129347D01*
X1111435Y129097D01*
X1111726Y128930D01*
X1112018Y128847D01*
X1112310D01*
X1112601Y128930D01*
X1112851Y129055D01*
X1113060Y129222D01*
G01X1114410Y129139D02*
X1114701Y128930D01*
X1115035Y128847D01*
X1115368Y128930D01*
X1115660Y129180D01*
X1115868Y129555D01*
X1115951Y129930D01*
Y130389D01*
X1115868Y130764D01*
X1115660Y131097D01*
X1115410Y131264D01*
X1115118Y131347D01*
X1114785Y131264D01*
X1114535Y131097D01*
X1114368Y130847D01*
X1114285Y130514D01*
X1114368Y130222D01*
X1114576Y129930D01*
X1114826Y129764D01*
X1115118Y129722D01*
X1115451Y129805D01*
X1115701Y130014D01*
X1115951Y130389D01*
G01X1112935Y134639D02*
X1112685Y134764D01*
X1112393Y134847D01*
X1112060D01*
X1111685Y134722D01*
X1111393Y134514D01*
X1111185Y134264D01*
X1111018Y133847D01*
X1110976Y133472D01*
X1111060Y133097D01*
X1111185Y132847D01*
X1111435Y132597D01*
X1111726Y132430D01*
X1112018Y132347D01*
X1112310D01*
X1112601Y132430D01*
X1112851Y132555D01*
X1113060Y132722D01*
G01X1115118Y132347D02*
X1115410Y132389D01*
X1115743Y132514D01*
X1115951Y132722D01*
X1116035Y133014D01*
X1115951Y133305D01*
X1115701Y133555D01*
X1115326Y133680D01*
X1114910D01*
X1114660Y133764D01*
X1114451Y133972D01*
X1114368Y134264D01*
X1114493Y134555D01*
X1114785Y134764D01*
X1115118Y134847D01*
X1115451Y134764D01*
X1115743Y134555D01*
X1115868Y134264D01*
X1115785Y133972D01*
X1115576Y133764D01*
X1115326Y133680D01*
X1114910D01*
X1114535Y133555D01*
X1114285Y133305D01*
X1114201Y133014D01*
X1114285Y132722D01*
X1114493Y132514D01*
X1114826Y132389D01*
X1115118Y132347D01*
G01X1128525Y118809D02*
X1128400Y118559D01*
X1128317Y118267D01*
Y117934D01*
X1128442Y117559D01*
X1128650Y117267D01*
X1128900Y117059D01*
X1129317Y116892D01*
X1129692Y116850D01*
X1130067Y116934D01*
X1130317Y117059D01*
X1130567Y117309D01*
X1130734Y117600D01*
X1130817Y117892D01*
Y118184D01*
X1130734Y118475D01*
X1130609Y118725D01*
X1130442Y118934D01*
G01X1130817Y120992D02*
X1128317D01*
X1128817Y120492D01*
G01X1130817D02*
Y121492D01*
G01Y124092D02*
X1128317D01*
X1128817Y123592D01*
G01X1130817D02*
Y124592D01*
G01X1125025Y118809D02*
X1124900Y118559D01*
X1124817Y118267D01*
Y117934D01*
X1124942Y117559D01*
X1125150Y117267D01*
X1125400Y117059D01*
X1125817Y116892D01*
X1126192Y116850D01*
X1126567Y116934D01*
X1126817Y117059D01*
X1127067Y117309D01*
X1127234Y117600D01*
X1127317Y117892D01*
Y118184D01*
X1127234Y118475D01*
X1127109Y118725D01*
X1126942Y118934D01*
G01X1127317Y120992D02*
X1124817D01*
X1125317Y120492D01*
G01X1127317D02*
Y121492D01*
G01X1124817Y124092D02*
X1124900Y123759D01*
X1125109Y123509D01*
X1125359Y123342D01*
X1125692Y123217D01*
X1126067Y123175D01*
X1126442Y123217D01*
X1126775Y123342D01*
X1127025Y123509D01*
X1127234Y123759D01*
X1127317Y124092D01*
X1127234Y124425D01*
X1127025Y124675D01*
X1126775Y124842D01*
X1126442Y124967D01*
X1126067Y125009D01*
X1125692Y124967D01*
X1125359Y124842D01*
X1125109Y124675D01*
X1124900Y124425D01*
X1124817Y124092D01*
G01X1125700Y233000D02*
Y237000D01*
X1118300D01*
G01X1139700Y232500D02*
Y236500D01*
X1132300D01*
G01X1128000Y218000D02*
Y232000D01*
G01X1115000Y218000D02*
X1128000D01*
G01X1115000Y232000D02*
Y218000D01*
G01X1128000Y232000D02*
X1115000D01*
G01X1142500Y218000D02*
Y232000D01*
G01X1129500Y218000D02*
X1142500D01*
G01X1129500Y232000D02*
Y218000D01*
G01X1142500Y232000D02*
X1129500D01*
G01X1118179Y268112D02*
X1115679D01*
Y269153D01*
X1115804Y269487D01*
X1115971Y269695D01*
X1116304Y269778D01*
X1116637Y269695D01*
X1116846Y269445D01*
X1116971Y269153D01*
Y268112D01*
G01Y269153D02*
X1118179Y269778D01*
G01X1117679Y271128D02*
X1117971Y271378D01*
X1118137Y271712D01*
X1118179Y272087D01*
X1118137Y272420D01*
X1117929Y272753D01*
X1117679Y272962D01*
X1117429Y273003D01*
X1117137Y272920D01*
X1116929Y272628D01*
X1116846Y272337D01*
Y271962D01*
G01Y272337D02*
X1116721Y272587D01*
X1116512Y272795D01*
X1116262Y272878D01*
X1116012Y272795D01*
X1115804Y272587D01*
X1115679Y272212D01*
X1115721Y271837D01*
X1115887Y271462D01*
G01X1118179Y275062D02*
X1117637Y275145D01*
X1117179Y275270D01*
X1116762Y275437D01*
X1116304Y275645D01*
X1115679Y275978D01*
Y274312D01*
G01X1118179Y278162D02*
X1117637Y278245D01*
X1117179Y278370D01*
X1116762Y278537D01*
X1116304Y278745D01*
X1115679Y279078D01*
Y277412D01*
G01X1122219Y268112D02*
X1119719D01*
Y269153D01*
X1119844Y269487D01*
X1120011Y269695D01*
X1120344Y269778D01*
X1120677Y269695D01*
X1120886Y269445D01*
X1121011Y269153D01*
Y268112D01*
G01Y269153D02*
X1122219Y269778D01*
G01Y272545D02*
X1119719D01*
X1121511Y271003D01*
Y273087D01*
G01X1122219Y275145D02*
X1119719D01*
X1120219Y274645D01*
G01X1122219D02*
Y275645D01*
G01X1121719Y277328D02*
X1122011Y277578D01*
X1122177Y277912D01*
X1122219Y278287D01*
X1122177Y278620D01*
X1121969Y278953D01*
X1121719Y279162D01*
X1121469Y279203D01*
X1121177Y279120D01*
X1120969Y278828D01*
X1120886Y278537D01*
Y278162D01*
G01Y278537D02*
X1120761Y278787D01*
X1120552Y278995D01*
X1120302Y279078D01*
X1120052Y278995D01*
X1119844Y278787D01*
X1119719Y278412D01*
X1119761Y278037D01*
X1119927Y277662D01*
G01X1138505Y268438D02*
X1136005D01*
Y269479D01*
X1136130Y269813D01*
X1136297Y270021D01*
X1136630Y270104D01*
X1136963Y270021D01*
X1137172Y269771D01*
X1137297Y269479D01*
Y268438D01*
G01Y269479D02*
X1138505Y270104D01*
G01Y272288D02*
X1137963Y272371D01*
X1137505Y272496D01*
X1137088Y272663D01*
X1136630Y272871D01*
X1136005Y273204D01*
Y271538D01*
G01X1138505Y275471D02*
X1136005D01*
X1136505Y274971D01*
G01X1138505D02*
Y275971D01*
G01Y278571D02*
X1138463Y278863D01*
X1138338Y279196D01*
X1138130Y279404D01*
X1137838Y279488D01*
X1137547Y279404D01*
X1137297Y279154D01*
X1137172Y278779D01*
Y278363D01*
X1137088Y278113D01*
X1136880Y277904D01*
X1136588Y277821D01*
X1136297Y277946D01*
X1136088Y278238D01*
X1136005Y278571D01*
X1136088Y278904D01*
X1136297Y279196D01*
X1136588Y279321D01*
X1136880Y279238D01*
X1137088Y279029D01*
X1137172Y278779D01*
Y278363D01*
X1137297Y277988D01*
X1137547Y277738D01*
X1137838Y277654D01*
X1138130Y277738D01*
X1138338Y277946D01*
X1138463Y278279D01*
X1138505Y278571D01*
G01X1134497Y268439D02*
X1131997D01*
Y269480D01*
X1132122Y269814D01*
X1132289Y270022D01*
X1132622Y270105D01*
X1132955Y270022D01*
X1133164Y269772D01*
X1133289Y269480D01*
Y268439D01*
G01Y269480D02*
X1134497Y270105D01*
G01Y272289D02*
X1133955Y272372D01*
X1133497Y272497D01*
X1133080Y272664D01*
X1132622Y272872D01*
X1131997Y273205D01*
Y271539D01*
G01X1132414Y274680D02*
X1132164Y274930D01*
X1132039Y275222D01*
X1131997Y275555D01*
X1132080Y275972D01*
X1132289Y276264D01*
X1132539Y276347D01*
X1132789Y276305D01*
X1132997Y276139D01*
X1133414Y275305D01*
X1133705Y274930D01*
X1134122Y274680D01*
X1134497Y274597D01*
Y276347D01*
G01X1133455Y277780D02*
X1133164Y278072D01*
X1132997Y278322D01*
X1132914Y278655D01*
X1132997Y278947D01*
X1133164Y279155D01*
X1133414Y279322D01*
X1133705Y279364D01*
X1133955Y279322D01*
X1134205Y279155D01*
X1134414Y278905D01*
X1134497Y278614D01*
X1134414Y278280D01*
X1134164Y277989D01*
X1133789Y277822D01*
X1133372Y277780D01*
X1132830Y277864D01*
X1132539Y277989D01*
X1132247Y278197D01*
X1132039Y278489D01*
X1131997Y278780D01*
X1132080Y279072D01*
X1132289Y279280D01*
G01X1143573Y270639D02*
X1143448Y270389D01*
X1143365Y270097D01*
Y269764D01*
X1143490Y269389D01*
X1143698Y269097D01*
X1143948Y268889D01*
X1144365Y268722D01*
X1144740Y268680D01*
X1145115Y268764D01*
X1145365Y268889D01*
X1145615Y269139D01*
X1145782Y269430D01*
X1145865Y269722D01*
Y270014D01*
X1145782Y270305D01*
X1145657Y270555D01*
X1145490Y270764D01*
G01X1145865Y273322D02*
X1143365D01*
X1145157Y271780D01*
Y273864D01*
G01X1145573Y275214D02*
X1145782Y275505D01*
X1145865Y275839D01*
X1145782Y276172D01*
X1145532Y276464D01*
X1145157Y276672D01*
X1144782Y276755D01*
X1144323D01*
X1143948Y276672D01*
X1143615Y276464D01*
X1143448Y276214D01*
X1143365Y275922D01*
X1143448Y275589D01*
X1143615Y275339D01*
X1143865Y275172D01*
X1144198Y275089D01*
X1144490Y275172D01*
X1144782Y275380D01*
X1144948Y275630D01*
X1144990Y275922D01*
X1144907Y276255D01*
X1144698Y276505D01*
X1144323Y276755D01*
G01X1140073Y270639D02*
X1139948Y270389D01*
X1139865Y270097D01*
Y269764D01*
X1139990Y269389D01*
X1140198Y269097D01*
X1140448Y268889D01*
X1140865Y268722D01*
X1141240Y268680D01*
X1141615Y268764D01*
X1141865Y268889D01*
X1142115Y269139D01*
X1142282Y269430D01*
X1142365Y269722D01*
Y270014D01*
X1142282Y270305D01*
X1142157Y270555D01*
X1141990Y270764D01*
G01X1142365Y273322D02*
X1139865D01*
X1141657Y271780D01*
Y273864D01*
G01X1142365Y275922D02*
X1142323Y276214D01*
X1142198Y276547D01*
X1141990Y276755D01*
X1141698Y276839D01*
X1141407Y276755D01*
X1141157Y276505D01*
X1141032Y276130D01*
Y275714D01*
X1140948Y275464D01*
X1140740Y275255D01*
X1140448Y275172D01*
X1140157Y275297D01*
X1139948Y275589D01*
X1139865Y275922D01*
X1139948Y276255D01*
X1140157Y276547D01*
X1140448Y276672D01*
X1140740Y276589D01*
X1140948Y276380D01*
X1141032Y276130D01*
Y275714D01*
X1141157Y275339D01*
X1141407Y275089D01*
X1141698Y275005D01*
X1141990Y275089D01*
X1142198Y275297D01*
X1142323Y275630D01*
X1142365Y275922D01*
G01X1124252Y270236D02*
X1124127Y269986D01*
X1124044Y269694D01*
Y269361D01*
X1124169Y268986D01*
X1124377Y268694D01*
X1124627Y268486D01*
X1125044Y268319D01*
X1125419Y268277D01*
X1125794Y268361D01*
X1126044Y268486D01*
X1126294Y268736D01*
X1126461Y269027D01*
X1126544Y269319D01*
Y269611D01*
X1126461Y269902D01*
X1126336Y270152D01*
X1126169Y270361D01*
G01X1126544Y272919D02*
X1124044D01*
X1125836Y271377D01*
Y273461D01*
G01X1126544Y275436D02*
X1126002Y275519D01*
X1125544Y275644D01*
X1125127Y275811D01*
X1124669Y276019D01*
X1124044Y276352D01*
Y274686D01*
G01X1127752Y270236D02*
X1127627Y269986D01*
X1127544Y269694D01*
Y269361D01*
X1127669Y268986D01*
X1127877Y268694D01*
X1128127Y268486D01*
X1128544Y268319D01*
X1128919Y268277D01*
X1129294Y268361D01*
X1129544Y268486D01*
X1129794Y268736D01*
X1129961Y269027D01*
X1130044Y269319D01*
Y269611D01*
X1129961Y269902D01*
X1129836Y270152D01*
X1129669Y270361D01*
G01X1130044Y272919D02*
X1127544D01*
X1129336Y271377D01*
Y273461D01*
G01X1129002Y274727D02*
X1128711Y275019D01*
X1128544Y275269D01*
X1128461Y275602D01*
X1128544Y275894D01*
X1128711Y276102D01*
X1128961Y276269D01*
X1129252Y276311D01*
X1129502Y276269D01*
X1129752Y276102D01*
X1129961Y275852D01*
X1130044Y275561D01*
X1129961Y275227D01*
X1129711Y274936D01*
X1129336Y274769D01*
X1128919Y274727D01*
X1128377Y274811D01*
X1128086Y274936D01*
X1127794Y275144D01*
X1127586Y275436D01*
X1127544Y275727D01*
X1127627Y276019D01*
X1127836Y276227D01*
G01X1112208Y270317D02*
X1112083Y270067D01*
X1112000Y269775D01*
Y269442D01*
X1112125Y269067D01*
X1112333Y268775D01*
X1112583Y268567D01*
X1113000Y268400D01*
X1113375Y268358D01*
X1113750Y268442D01*
X1114000Y268567D01*
X1114250Y268817D01*
X1114417Y269108D01*
X1114500Y269400D01*
Y269692D01*
X1114417Y269983D01*
X1114292Y270233D01*
X1114125Y270442D01*
G01X1114500Y273000D02*
X1112000D01*
X1113792Y271458D01*
Y273542D01*
G01X1114125Y274683D02*
X1114333Y274933D01*
X1114458Y275225D01*
X1114500Y275600D01*
X1114417Y275975D01*
X1114250Y276267D01*
X1113958Y276475D01*
X1113625Y276517D01*
X1113292Y276433D01*
X1113083Y276225D01*
X1112917Y275933D01*
X1112875Y275642D01*
X1112917Y275350D01*
X1113083Y274975D01*
X1112000Y275100D01*
Y276225D01*
G01X1138033Y365100D02*
X1138500Y365500D01*
X1138850Y366166D01*
X1139083Y367100D01*
X1138850Y367900D01*
X1138383Y368433D01*
X1137567Y368833D01*
X1134417D01*
Y360833D01*
X1138267D01*
X1139083Y361366D01*
X1139550Y362166D01*
X1139783Y363100D01*
X1139550Y364033D01*
X1138850Y364833D01*
X1138033Y365100D01*
X1134417D01*
G01X1150700Y431900D02*
X1229700D01*
Y356900D01*
X1124200D01*
Y431900D01*
X1150700D01*
G01X1132378Y376160D02*
Y378660D01*
X1133419D01*
X1133753Y378535D01*
X1133961Y378368D01*
X1134044Y378035D01*
X1133961Y377702D01*
X1133711Y377493D01*
X1133419Y377368D01*
X1132378D01*
G01X1133419D02*
X1134044Y376160D01*
G01X1135394Y376660D02*
X1135644Y376368D01*
X1135978Y376202D01*
X1136353Y376160D01*
X1136686Y376202D01*
X1137019Y376410D01*
X1137228Y376660D01*
X1137269Y376910D01*
X1137186Y377202D01*
X1136894Y377410D01*
X1136603Y377493D01*
X1136228D01*
G01X1136603D02*
X1136853Y377618D01*
X1137061Y377827D01*
X1137144Y378077D01*
X1137061Y378327D01*
X1136853Y378535D01*
X1136478Y378660D01*
X1136103Y378618D01*
X1135728Y378452D01*
G01X1138619Y377202D02*
X1138911Y377493D01*
X1139161Y377660D01*
X1139494Y377743D01*
X1139786Y377660D01*
X1139994Y377493D01*
X1140161Y377243D01*
X1140203Y376952D01*
X1140161Y376702D01*
X1139994Y376452D01*
X1139744Y376243D01*
X1139453Y376160D01*
X1139119Y376243D01*
X1138828Y376493D01*
X1138661Y376868D01*
X1138619Y377285D01*
X1138703Y377827D01*
X1138828Y378118D01*
X1139036Y378410D01*
X1139328Y378618D01*
X1139619Y378660D01*
X1139911Y378577D01*
X1140119Y378368D01*
G01X1142511Y378660D02*
X1142178Y378577D01*
X1141928Y378368D01*
X1141761Y378118D01*
X1141636Y377785D01*
X1141594Y377410D01*
X1141636Y377035D01*
X1141761Y376702D01*
X1141928Y376452D01*
X1142178Y376243D01*
X1142511Y376160D01*
X1142844Y376243D01*
X1143094Y376452D01*
X1143261Y376702D01*
X1143386Y377035D01*
X1143428Y377410D01*
X1143386Y377785D01*
X1143261Y378118D01*
X1143094Y378368D01*
X1142844Y378577D01*
X1142511Y378660D01*
G01X1145611Y376160D02*
Y378660D01*
X1145111Y378160D01*
G01Y376160D02*
X1146111D01*
G01X1142767Y360766D02*
Y363266D01*
X1143808D01*
X1144142Y363141D01*
X1144350Y362974D01*
X1144433Y362641D01*
X1144350Y362308D01*
X1144100Y362099D01*
X1143808Y361974D01*
X1142767D01*
G01X1143808D02*
X1144433Y360766D01*
G01X1146617D02*
X1146700Y361308D01*
X1146825Y361766D01*
X1146992Y362183D01*
X1147200Y362641D01*
X1147533Y363266D01*
X1145867D01*
G01X1149092Y361058D02*
X1149383Y360849D01*
X1149717Y360766D01*
X1150050Y360849D01*
X1150342Y361099D01*
X1150550Y361474D01*
X1150633Y361849D01*
Y362308D01*
X1150550Y362683D01*
X1150342Y363016D01*
X1150092Y363183D01*
X1149800Y363266D01*
X1149467Y363183D01*
X1149217Y363016D01*
X1149050Y362766D01*
X1148967Y362433D01*
X1149050Y362141D01*
X1149258Y361849D01*
X1149508Y361683D01*
X1149800Y361641D01*
X1150133Y361724D01*
X1150383Y361933D01*
X1150633Y362308D01*
G01X1152900Y360766D02*
X1153192Y360808D01*
X1153525Y360933D01*
X1153733Y361141D01*
X1153817Y361433D01*
X1153733Y361724D01*
X1153483Y361974D01*
X1153108Y362099D01*
X1152692D01*
X1152442Y362183D01*
X1152233Y362391D01*
X1152150Y362683D01*
X1152275Y362974D01*
X1152567Y363183D01*
X1152900Y363266D01*
X1153233Y363183D01*
X1153525Y362974D01*
X1153650Y362683D01*
X1153567Y362391D01*
X1153358Y362183D01*
X1153108Y362099D01*
X1152692D01*
X1152317Y361974D01*
X1152067Y361724D01*
X1151983Y361433D01*
X1152067Y361141D01*
X1152275Y360933D01*
X1152608Y360808D01*
X1152900Y360766D01*
G01X1155208Y362849D02*
X1155458Y363099D01*
X1155750Y363224D01*
X1156083Y363266D01*
X1156500Y363183D01*
X1156792Y362974D01*
X1156875Y362724D01*
X1156833Y362474D01*
X1156667Y362266D01*
X1155833Y361849D01*
X1155458Y361558D01*
X1155208Y361141D01*
X1155125Y360766D01*
X1156875D01*
G01X1132900Y382966D02*
Y380466D01*
G01X1131942Y382966D02*
X1133858D01*
G01X1135167Y380466D02*
Y382966D01*
X1136167D01*
X1136500Y382841D01*
X1136750Y382549D01*
X1136833Y382216D01*
X1136750Y381883D01*
X1136542Y381633D01*
X1136167Y381508D01*
X1135167D01*
G01X1138308Y382549D02*
X1138558Y382799D01*
X1138850Y382924D01*
X1139183Y382966D01*
X1139600Y382883D01*
X1139892Y382674D01*
X1139975Y382424D01*
X1139933Y382174D01*
X1139767Y381966D01*
X1138933Y381549D01*
X1138558Y381258D01*
X1138308Y380841D01*
X1138225Y380466D01*
X1139975D01*
G01X1141283Y380966D02*
X1141533Y380674D01*
X1141867Y380508D01*
X1142242Y380466D01*
X1142575Y380508D01*
X1142908Y380716D01*
X1143117Y380966D01*
X1143158Y381216D01*
X1143075Y381508D01*
X1142783Y381716D01*
X1142492Y381799D01*
X1142117D01*
G01X1142492D02*
X1142742Y381924D01*
X1142950Y382133D01*
X1143033Y382383D01*
X1142950Y382633D01*
X1142742Y382841D01*
X1142367Y382966D01*
X1141992Y382924D01*
X1141617Y382758D01*
G01X1145800Y380466D02*
Y382966D01*
X1144258Y381174D01*
X1146342D01*
G01X1128084Y386487D02*
Y388987D01*
X1129125D01*
X1129459Y388862D01*
X1129667Y388695D01*
X1129750Y388362D01*
X1129667Y388029D01*
X1129417Y387820D01*
X1129125Y387695D01*
X1128084D01*
G01X1129125D02*
X1129750Y386487D01*
G01X1131100Y386987D02*
X1131350Y386695D01*
X1131684Y386529D01*
X1132059Y386487D01*
X1132392Y386529D01*
X1132725Y386737D01*
X1132934Y386987D01*
X1132975Y387237D01*
X1132892Y387529D01*
X1132600Y387737D01*
X1132309Y387820D01*
X1131934D01*
G01X1132309D02*
X1132559Y387945D01*
X1132767Y388154D01*
X1132850Y388404D01*
X1132767Y388654D01*
X1132559Y388862D01*
X1132184Y388987D01*
X1131809Y388945D01*
X1131434Y388779D01*
G01X1134325Y387529D02*
X1134617Y387820D01*
X1134867Y387987D01*
X1135200Y388070D01*
X1135492Y387987D01*
X1135700Y387820D01*
X1135867Y387570D01*
X1135909Y387279D01*
X1135867Y387029D01*
X1135700Y386779D01*
X1135450Y386570D01*
X1135159Y386487D01*
X1134825Y386570D01*
X1134534Y386820D01*
X1134367Y387195D01*
X1134325Y387612D01*
X1134409Y388154D01*
X1134534Y388445D01*
X1134742Y388737D01*
X1135034Y388945D01*
X1135325Y388987D01*
X1135617Y388904D01*
X1135825Y388695D01*
G01X1138217Y388987D02*
X1137884Y388904D01*
X1137634Y388695D01*
X1137467Y388445D01*
X1137342Y388112D01*
X1137300Y387737D01*
X1137342Y387362D01*
X1137467Y387029D01*
X1137634Y386779D01*
X1137884Y386570D01*
X1138217Y386487D01*
X1138550Y386570D01*
X1138800Y386779D01*
X1138967Y387029D01*
X1139092Y387362D01*
X1139134Y387737D01*
X1139092Y388112D01*
X1138967Y388445D01*
X1138800Y388695D01*
X1138550Y388904D01*
X1138217Y388987D01*
G01X1140400Y386987D02*
X1140650Y386695D01*
X1140984Y386529D01*
X1141359Y386487D01*
X1141692Y386529D01*
X1142025Y386737D01*
X1142234Y386987D01*
X1142275Y387237D01*
X1142192Y387529D01*
X1141900Y387737D01*
X1141609Y387820D01*
X1141234D01*
G01X1141609D02*
X1141859Y387945D01*
X1142067Y388154D01*
X1142150Y388404D01*
X1142067Y388654D01*
X1141859Y388862D01*
X1141484Y388987D01*
X1141109Y388945D01*
X1140734Y388779D01*
G01X1143930Y402611D02*
X1141430D01*
Y403652D01*
X1141555Y403986D01*
X1141722Y404194D01*
X1142055Y404277D01*
X1142388Y404194D01*
X1142597Y403944D01*
X1142722Y403652D01*
Y402611D01*
G01Y403652D02*
X1143930Y404277D01*
G01X1143430Y405627D02*
X1143722Y405877D01*
X1143888Y406211D01*
X1143930Y406586D01*
X1143888Y406919D01*
X1143680Y407252D01*
X1143430Y407461D01*
X1143180Y407502D01*
X1142888Y407419D01*
X1142680Y407127D01*
X1142597Y406836D01*
Y406461D01*
G01Y406836D02*
X1142472Y407086D01*
X1142263Y407294D01*
X1142013Y407377D01*
X1141763Y407294D01*
X1141555Y407086D01*
X1141430Y406711D01*
X1141472Y406336D01*
X1141638Y405961D01*
G01X1142888Y408852D02*
X1142597Y409144D01*
X1142430Y409394D01*
X1142347Y409727D01*
X1142430Y410019D01*
X1142597Y410227D01*
X1142847Y410394D01*
X1143138Y410436D01*
X1143388Y410394D01*
X1143638Y410227D01*
X1143847Y409977D01*
X1143930Y409686D01*
X1143847Y409352D01*
X1143597Y409061D01*
X1143222Y408894D01*
X1142805Y408852D01*
X1142263Y408936D01*
X1141972Y409061D01*
X1141680Y409269D01*
X1141472Y409561D01*
X1141430Y409852D01*
X1141513Y410144D01*
X1141722Y410352D01*
G01X1141430Y412744D02*
X1141513Y412411D01*
X1141722Y412161D01*
X1141972Y411994D01*
X1142305Y411869D01*
X1142680Y411827D01*
X1143055Y411869D01*
X1143388Y411994D01*
X1143638Y412161D01*
X1143847Y412411D01*
X1143930Y412744D01*
X1143847Y413077D01*
X1143638Y413327D01*
X1143388Y413494D01*
X1143055Y413619D01*
X1142680Y413661D01*
X1142305Y413619D01*
X1141972Y413494D01*
X1141722Y413327D01*
X1141513Y413077D01*
X1141430Y412744D01*
G01X1141847Y415052D02*
X1141597Y415302D01*
X1141472Y415594D01*
X1141430Y415927D01*
X1141513Y416344D01*
X1141722Y416636D01*
X1141972Y416719D01*
X1142222Y416677D01*
X1142430Y416511D01*
X1142847Y415677D01*
X1143138Y415302D01*
X1143555Y415052D01*
X1143930Y414969D01*
Y416719D01*
G01X1134086Y395148D02*
Y397648D01*
X1135127D01*
X1135461Y397523D01*
X1135669Y397356D01*
X1135752Y397023D01*
X1135669Y396690D01*
X1135419Y396481D01*
X1135127Y396356D01*
X1134086D01*
G01X1135127D02*
X1135752Y395148D01*
G01X1137227Y397231D02*
X1137477Y397481D01*
X1137769Y397606D01*
X1138102Y397648D01*
X1138519Y397565D01*
X1138811Y397356D01*
X1138894Y397106D01*
X1138852Y396856D01*
X1138686Y396648D01*
X1137852Y396231D01*
X1137477Y395940D01*
X1137227Y395523D01*
X1137144Y395148D01*
X1138894D01*
G01X1141036D02*
X1141119Y395690D01*
X1141244Y396148D01*
X1141411Y396565D01*
X1141619Y397023D01*
X1141952Y397648D01*
X1140286D01*
G01X1144219D02*
X1143886Y397565D01*
X1143636Y397356D01*
X1143469Y397106D01*
X1143344Y396773D01*
X1143302Y396398D01*
X1143344Y396023D01*
X1143469Y395690D01*
X1143636Y395440D01*
X1143886Y395231D01*
X1144219Y395148D01*
X1144552Y395231D01*
X1144802Y395440D01*
X1144969Y395690D01*
X1145094Y396023D01*
X1145136Y396398D01*
X1145094Y396773D01*
X1144969Y397106D01*
X1144802Y397356D01*
X1144552Y397565D01*
X1144219Y397648D01*
G01X1134086Y391021D02*
Y393521D01*
X1135127D01*
X1135461Y393396D01*
X1135669Y393229D01*
X1135752Y392896D01*
X1135669Y392563D01*
X1135419Y392354D01*
X1135127Y392229D01*
X1134086D01*
G01X1135127D02*
X1135752Y391021D01*
G01X1137227Y393104D02*
X1137477Y393354D01*
X1137769Y393479D01*
X1138102Y393521D01*
X1138519Y393438D01*
X1138811Y393229D01*
X1138894Y392979D01*
X1138852Y392729D01*
X1138686Y392521D01*
X1137852Y392104D01*
X1137477Y391813D01*
X1137227Y391396D01*
X1137144Y391021D01*
X1138894D01*
G01X1140327Y392063D02*
X1140619Y392354D01*
X1140869Y392521D01*
X1141202Y392604D01*
X1141494Y392521D01*
X1141702Y392354D01*
X1141869Y392104D01*
X1141911Y391813D01*
X1141869Y391563D01*
X1141702Y391313D01*
X1141452Y391104D01*
X1141161Y391021D01*
X1140827Y391104D01*
X1140536Y391354D01*
X1140369Y391729D01*
X1140327Y392146D01*
X1140411Y392688D01*
X1140536Y392979D01*
X1140744Y393271D01*
X1141036Y393479D01*
X1141327Y393521D01*
X1141619Y393438D01*
X1141827Y393229D01*
G01X1143511Y391313D02*
X1143802Y391104D01*
X1144136Y391021D01*
X1144469Y391104D01*
X1144761Y391354D01*
X1144969Y391729D01*
X1145052Y392104D01*
Y392563D01*
X1144969Y392938D01*
X1144761Y393271D01*
X1144511Y393438D01*
X1144219Y393521D01*
X1143886Y393438D01*
X1143636Y393271D01*
X1143469Y393021D01*
X1143386Y392688D01*
X1143469Y392396D01*
X1143677Y392104D01*
X1143927Y391938D01*
X1144219Y391896D01*
X1144552Y391979D01*
X1144802Y392188D01*
X1145052Y392563D01*
G01X1120069Y817734D02*
X1119944Y817484D01*
X1119861Y817192D01*
Y816859D01*
X1119986Y816484D01*
X1120194Y816192D01*
X1120444Y815984D01*
X1120861Y815817D01*
X1121236Y815775D01*
X1121611Y815859D01*
X1121861Y815984D01*
X1122111Y816234D01*
X1122278Y816525D01*
X1122361Y816817D01*
Y817109D01*
X1122278Y817400D01*
X1122153Y817650D01*
X1121986Y817859D01*
G01X1122069Y819209D02*
X1122278Y819500D01*
X1122361Y819834D01*
X1122278Y820167D01*
X1122028Y820459D01*
X1121653Y820667D01*
X1121278Y820750D01*
X1120819D01*
X1120444Y820667D01*
X1120111Y820459D01*
X1119944Y820209D01*
X1119861Y819917D01*
X1119944Y819584D01*
X1120111Y819334D01*
X1120361Y819167D01*
X1120694Y819084D01*
X1120986Y819167D01*
X1121278Y819375D01*
X1121444Y819625D01*
X1121486Y819917D01*
X1121403Y820250D01*
X1121194Y820500D01*
X1120819Y820750D01*
G01X1121986Y822100D02*
X1122194Y822350D01*
X1122319Y822642D01*
X1122361Y823017D01*
X1122278Y823392D01*
X1122111Y823684D01*
X1121819Y823892D01*
X1121486Y823934D01*
X1121153Y823850D01*
X1120944Y823642D01*
X1120778Y823350D01*
X1120736Y823059D01*
X1120778Y822767D01*
X1120944Y822392D01*
X1119861Y822517D01*
Y823642D01*
G01X1116069Y817734D02*
X1115944Y817484D01*
X1115861Y817192D01*
Y816859D01*
X1115986Y816484D01*
X1116194Y816192D01*
X1116444Y815984D01*
X1116861Y815817D01*
X1117236Y815775D01*
X1117611Y815859D01*
X1117861Y815984D01*
X1118111Y816234D01*
X1118278Y816525D01*
X1118361Y816817D01*
Y817109D01*
X1118278Y817400D01*
X1118153Y817650D01*
X1117986Y817859D01*
G01X1118069Y819209D02*
X1118278Y819500D01*
X1118361Y819834D01*
X1118278Y820167D01*
X1118028Y820459D01*
X1117653Y820667D01*
X1117278Y820750D01*
X1116819D01*
X1116444Y820667D01*
X1116111Y820459D01*
X1115944Y820209D01*
X1115861Y819917D01*
X1115944Y819584D01*
X1116111Y819334D01*
X1116361Y819167D01*
X1116694Y819084D01*
X1116986Y819167D01*
X1117278Y819375D01*
X1117444Y819625D01*
X1117486Y819917D01*
X1117403Y820250D01*
X1117194Y820500D01*
X1116819Y820750D01*
G01X1118361Y823517D02*
X1115861D01*
X1117653Y821975D01*
Y824059D01*
G01X1128668Y817734D02*
X1128543Y817484D01*
X1128460Y817192D01*
Y816859D01*
X1128585Y816484D01*
X1128793Y816192D01*
X1129043Y815984D01*
X1129460Y815817D01*
X1129835Y815775D01*
X1130210Y815859D01*
X1130460Y815984D01*
X1130710Y816234D01*
X1130877Y816525D01*
X1130960Y816817D01*
Y817109D01*
X1130877Y817400D01*
X1130752Y817650D01*
X1130585Y817859D01*
G01X1130668Y819209D02*
X1130877Y819500D01*
X1130960Y819834D01*
X1130877Y820167D01*
X1130627Y820459D01*
X1130252Y820667D01*
X1129877Y820750D01*
X1129418D01*
X1129043Y820667D01*
X1128710Y820459D01*
X1128543Y820209D01*
X1128460Y819917D01*
X1128543Y819584D01*
X1128710Y819334D01*
X1128960Y819167D01*
X1129293Y819084D01*
X1129585Y819167D01*
X1129877Y819375D01*
X1130043Y819625D01*
X1130085Y819917D01*
X1130002Y820250D01*
X1129793Y820500D01*
X1129418Y820750D01*
G01X1130460Y822100D02*
X1130752Y822350D01*
X1130918Y822684D01*
X1130960Y823059D01*
X1130918Y823392D01*
X1130710Y823725D01*
X1130460Y823934D01*
X1130210Y823975D01*
X1129918Y823892D01*
X1129710Y823600D01*
X1129627Y823309D01*
Y822934D01*
G01Y823309D02*
X1129502Y823559D01*
X1129293Y823767D01*
X1129043Y823850D01*
X1128793Y823767D01*
X1128585Y823559D01*
X1128460Y823184D01*
X1128502Y822809D01*
X1128668Y822434D01*
G01X1132668Y817734D02*
X1132543Y817484D01*
X1132460Y817192D01*
Y816859D01*
X1132585Y816484D01*
X1132793Y816192D01*
X1133043Y815984D01*
X1133460Y815817D01*
X1133835Y815775D01*
X1134210Y815859D01*
X1134460Y815984D01*
X1134710Y816234D01*
X1134877Y816525D01*
X1134960Y816817D01*
Y817109D01*
X1134877Y817400D01*
X1134752Y817650D01*
X1134585Y817859D01*
G01X1134668Y819209D02*
X1134877Y819500D01*
X1134960Y819834D01*
X1134877Y820167D01*
X1134627Y820459D01*
X1134252Y820667D01*
X1133877Y820750D01*
X1133418D01*
X1133043Y820667D01*
X1132710Y820459D01*
X1132543Y820209D01*
X1132460Y819917D01*
X1132543Y819584D01*
X1132710Y819334D01*
X1132960Y819167D01*
X1133293Y819084D01*
X1133585Y819167D01*
X1133877Y819375D01*
X1134043Y819625D01*
X1134085Y819917D01*
X1134002Y820250D01*
X1133793Y820500D01*
X1133418Y820750D01*
G01X1132877Y822225D02*
X1132627Y822475D01*
X1132502Y822767D01*
X1132460Y823100D01*
X1132543Y823517D01*
X1132752Y823809D01*
X1133002Y823892D01*
X1133252Y823850D01*
X1133460Y823684D01*
X1133877Y822850D01*
X1134168Y822475D01*
X1134585Y822225D01*
X1134960Y822142D01*
Y823892D01*
G01X1141266Y817734D02*
X1141141Y817484D01*
X1141058Y817192D01*
Y816859D01*
X1141183Y816484D01*
X1141391Y816192D01*
X1141641Y815984D01*
X1142058Y815817D01*
X1142433Y815775D01*
X1142808Y815859D01*
X1143058Y815984D01*
X1143308Y816234D01*
X1143475Y816525D01*
X1143558Y816817D01*
Y817109D01*
X1143475Y817400D01*
X1143350Y817650D01*
X1143183Y817859D01*
G01X1143558Y819917D02*
X1143516Y820209D01*
X1143391Y820542D01*
X1143183Y820750D01*
X1142891Y820834D01*
X1142600Y820750D01*
X1142350Y820500D01*
X1142225Y820125D01*
Y819709D01*
X1142141Y819459D01*
X1141933Y819250D01*
X1141641Y819167D01*
X1141350Y819292D01*
X1141141Y819584D01*
X1141058Y819917D01*
X1141141Y820250D01*
X1141350Y820542D01*
X1141641Y820667D01*
X1141933Y820584D01*
X1142141Y820375D01*
X1142225Y820125D01*
Y819709D01*
X1142350Y819334D01*
X1142600Y819084D01*
X1142891Y819000D01*
X1143183Y819084D01*
X1143391Y819292D01*
X1143516Y819625D01*
X1143558Y819917D01*
G01X1141058Y823017D02*
X1141141Y822684D01*
X1141350Y822434D01*
X1141600Y822267D01*
X1141933Y822142D01*
X1142308Y822100D01*
X1142683Y822142D01*
X1143016Y822267D01*
X1143266Y822434D01*
X1143475Y822684D01*
X1143558Y823017D01*
X1143475Y823350D01*
X1143266Y823600D01*
X1143016Y823767D01*
X1142683Y823892D01*
X1142308Y823934D01*
X1141933Y823892D01*
X1141600Y823767D01*
X1141350Y823600D01*
X1141141Y823350D01*
X1141058Y823017D01*
G01X1158073Y113770D02*
X1155573D01*
Y114811D01*
X1155698Y115145D01*
X1155865Y115353D01*
X1156198Y115436D01*
X1156531Y115353D01*
X1156740Y115103D01*
X1156865Y114811D01*
Y113770D01*
G01Y114811D02*
X1158073Y115436D01*
G01Y117620D02*
X1157531Y117703D01*
X1157073Y117828D01*
X1156656Y117995D01*
X1156198Y118203D01*
X1155573Y118536D01*
Y116870D01*
G01X1155990Y120011D02*
X1155740Y120261D01*
X1155615Y120553D01*
X1155573Y120886D01*
X1155656Y121303D01*
X1155865Y121595D01*
X1156115Y121678D01*
X1156365Y121636D01*
X1156573Y121470D01*
X1156990Y120636D01*
X1157281Y120261D01*
X1157698Y120011D01*
X1158073Y119928D01*
Y121678D01*
G01X1155573Y123903D02*
X1155656Y123570D01*
X1155865Y123320D01*
X1156115Y123153D01*
X1156448Y123028D01*
X1156823Y122986D01*
X1157198Y123028D01*
X1157531Y123153D01*
X1157781Y123320D01*
X1157990Y123570D01*
X1158073Y123903D01*
X1157990Y124236D01*
X1157781Y124486D01*
X1157531Y124653D01*
X1157198Y124778D01*
X1156823Y124820D01*
X1156448Y124778D01*
X1156115Y124653D01*
X1155865Y124486D01*
X1155656Y124236D01*
X1155573Y123903D01*
G01X1171479Y128171D02*
X1175479D01*
Y135571D01*
G01X1154061Y113775D02*
X1151561D01*
Y114816D01*
X1151686Y115150D01*
X1151853Y115358D01*
X1152186Y115441D01*
X1152519Y115358D01*
X1152728Y115108D01*
X1152853Y114816D01*
Y113775D01*
G01Y114816D02*
X1154061Y115441D01*
G01Y117625D02*
X1153519Y117708D01*
X1153061Y117833D01*
X1152644Y118000D01*
X1152186Y118208D01*
X1151561Y118541D01*
Y116875D01*
G01X1151978Y120016D02*
X1151728Y120266D01*
X1151603Y120558D01*
X1151561Y120891D01*
X1151644Y121308D01*
X1151853Y121600D01*
X1152103Y121683D01*
X1152353Y121641D01*
X1152561Y121475D01*
X1152978Y120641D01*
X1153269Y120266D01*
X1153686Y120016D01*
X1154061Y119933D01*
Y121683D01*
G01Y123825D02*
X1153519Y123908D01*
X1153061Y124033D01*
X1152644Y124200D01*
X1152186Y124408D01*
X1151561Y124741D01*
Y123075D01*
G01X1167467Y128176D02*
X1171467D01*
Y135576D01*
G01X1150130Y128441D02*
X1150005Y128191D01*
X1149922Y127899D01*
Y127566D01*
X1150047Y127191D01*
X1150255Y126899D01*
X1150505Y126691D01*
X1150922Y126524D01*
X1151297Y126482D01*
X1151672Y126566D01*
X1151922Y126691D01*
X1152172Y126941D01*
X1152339Y127232D01*
X1152422Y127524D01*
Y127816D01*
X1152339Y128107D01*
X1152214Y128357D01*
X1152047Y128566D01*
G01X1152422Y130624D02*
X1149922D01*
X1150422Y130124D01*
G01X1152422D02*
Y131124D01*
G01X1151922Y132807D02*
X1152214Y133057D01*
X1152380Y133391D01*
X1152422Y133766D01*
X1152380Y134099D01*
X1152172Y134432D01*
X1151922Y134641D01*
X1151672Y134682D01*
X1151380Y134599D01*
X1151172Y134307D01*
X1151089Y134016D01*
Y133641D01*
G01Y134016D02*
X1150964Y134266D01*
X1150755Y134474D01*
X1150505Y134557D01*
X1150255Y134474D01*
X1150047Y134266D01*
X1149922Y133891D01*
X1149964Y133516D01*
X1150130Y133141D01*
G01X1146630Y128441D02*
X1146505Y128191D01*
X1146422Y127899D01*
Y127566D01*
X1146547Y127191D01*
X1146755Y126899D01*
X1147005Y126691D01*
X1147422Y126524D01*
X1147797Y126482D01*
X1148172Y126566D01*
X1148422Y126691D01*
X1148672Y126941D01*
X1148839Y127232D01*
X1148922Y127524D01*
Y127816D01*
X1148839Y128107D01*
X1148714Y128357D01*
X1148547Y128566D01*
G01X1148922Y130624D02*
X1146422D01*
X1146922Y130124D01*
G01X1148922D02*
Y131124D01*
G01X1146839Y132932D02*
X1146589Y133182D01*
X1146464Y133474D01*
X1146422Y133807D01*
X1146505Y134224D01*
X1146714Y134516D01*
X1146964Y134599D01*
X1147214Y134557D01*
X1147422Y134391D01*
X1147839Y133557D01*
X1148130Y133182D01*
X1148547Y132932D01*
X1148922Y132849D01*
Y134599D01*
G01X1173708Y204067D02*
X1173583Y203817D01*
X1173500Y203525D01*
Y203192D01*
X1173625Y202817D01*
X1173833Y202525D01*
X1174083Y202317D01*
X1174500Y202150D01*
X1174875Y202108D01*
X1175250Y202192D01*
X1175500Y202317D01*
X1175750Y202567D01*
X1175917Y202858D01*
X1176000Y203150D01*
Y203442D01*
X1175917Y203733D01*
X1175792Y203983D01*
X1175625Y204192D01*
G01X1176000Y206750D02*
X1173500D01*
X1175292Y205208D01*
Y207292D01*
G01X1173917Y208558D02*
X1173667Y208808D01*
X1173542Y209100D01*
X1173500Y209433D01*
X1173583Y209850D01*
X1173792Y210142D01*
X1174042Y210225D01*
X1174292Y210183D01*
X1174500Y210017D01*
X1174917Y209183D01*
X1175208Y208808D01*
X1175625Y208558D01*
X1176000Y208475D01*
Y210225D01*
G01X1175625Y211533D02*
X1175833Y211783D01*
X1175958Y212075D01*
X1176000Y212450D01*
X1175917Y212825D01*
X1175750Y213117D01*
X1175458Y213325D01*
X1175125Y213367D01*
X1174792Y213283D01*
X1174583Y213075D01*
X1174417Y212783D01*
X1174375Y212492D01*
X1174417Y212200D01*
X1174583Y211825D01*
X1173500Y211950D01*
Y213075D01*
G01X1163771Y203831D02*
X1163646Y203581D01*
X1163563Y203289D01*
Y202956D01*
X1163688Y202581D01*
X1163896Y202289D01*
X1164146Y202081D01*
X1164563Y201914D01*
X1164938Y201872D01*
X1165313Y201956D01*
X1165563Y202081D01*
X1165813Y202331D01*
X1165980Y202622D01*
X1166063Y202914D01*
Y203206D01*
X1165980Y203497D01*
X1165855Y203747D01*
X1165688Y203956D01*
G01X1166063Y206514D02*
X1163563D01*
X1165355Y204972D01*
Y207056D01*
G01X1163980Y208322D02*
X1163730Y208572D01*
X1163605Y208864D01*
X1163563Y209197D01*
X1163646Y209614D01*
X1163855Y209906D01*
X1164105Y209989D01*
X1164355Y209947D01*
X1164563Y209781D01*
X1164980Y208947D01*
X1165271Y208572D01*
X1165688Y208322D01*
X1166063Y208239D01*
Y209989D01*
G01Y212714D02*
X1163563D01*
X1165355Y211172D01*
Y213256D01*
G01X1154200Y232500D02*
Y236500D01*
X1146800D01*
G01X1157000Y218000D02*
Y232000D01*
G01X1144000Y218000D02*
X1157000D01*
G01X1144000Y232000D02*
Y218000D01*
G01X1157000Y232000D02*
X1144000D01*
G01X1148083Y253000D02*
X1151000Y261000D01*
X1153917Y253000D01*
G01X1152867Y255800D02*
X1149133D01*
G01X1158325Y270944D02*
X1158200Y270694D01*
X1158117Y270402D01*
Y270069D01*
X1158242Y269694D01*
X1158450Y269402D01*
X1158700Y269194D01*
X1159117Y269027D01*
X1159492Y268985D01*
X1159867Y269069D01*
X1160117Y269194D01*
X1160367Y269444D01*
X1160534Y269735D01*
X1160617Y270027D01*
Y270319D01*
X1160534Y270610D01*
X1160409Y270860D01*
X1160242Y271069D01*
G01Y272210D02*
X1160450Y272460D01*
X1160575Y272752D01*
X1160617Y273127D01*
X1160534Y273502D01*
X1160367Y273794D01*
X1160075Y274002D01*
X1159742Y274044D01*
X1159409Y273960D01*
X1159200Y273752D01*
X1159034Y273460D01*
X1158992Y273169D01*
X1159034Y272877D01*
X1159200Y272502D01*
X1158117Y272627D01*
Y273752D01*
G01X1160117Y275310D02*
X1160409Y275560D01*
X1160575Y275894D01*
X1160617Y276269D01*
X1160575Y276602D01*
X1160367Y276935D01*
X1160117Y277144D01*
X1159867Y277185D01*
X1159575Y277102D01*
X1159367Y276810D01*
X1159284Y276519D01*
Y276144D01*
G01Y276519D02*
X1159159Y276769D01*
X1158950Y276977D01*
X1158700Y277060D01*
X1158450Y276977D01*
X1158242Y276769D01*
X1158117Y276394D01*
X1158159Y276019D01*
X1158325Y275644D01*
G01X1154825Y270944D02*
X1154700Y270694D01*
X1154617Y270402D01*
Y270069D01*
X1154742Y269694D01*
X1154950Y269402D01*
X1155200Y269194D01*
X1155617Y269027D01*
X1155992Y268985D01*
X1156367Y269069D01*
X1156617Y269194D01*
X1156867Y269444D01*
X1157034Y269735D01*
X1157117Y270027D01*
Y270319D01*
X1157034Y270610D01*
X1156909Y270860D01*
X1156742Y271069D01*
G01Y272210D02*
X1156950Y272460D01*
X1157075Y272752D01*
X1157117Y273127D01*
X1157034Y273502D01*
X1156867Y273794D01*
X1156575Y274002D01*
X1156242Y274044D01*
X1155909Y273960D01*
X1155700Y273752D01*
X1155534Y273460D01*
X1155492Y273169D01*
X1155534Y272877D01*
X1155700Y272502D01*
X1154617Y272627D01*
Y273752D01*
G01X1155034Y275435D02*
X1154784Y275685D01*
X1154659Y275977D01*
X1154617Y276310D01*
X1154700Y276727D01*
X1154909Y277019D01*
X1155159Y277102D01*
X1155409Y277060D01*
X1155617Y276894D01*
X1156034Y276060D01*
X1156325Y275685D01*
X1156742Y275435D01*
X1157117Y275352D01*
Y277102D01*
G01X1150851Y271047D02*
X1150726Y270797D01*
X1150643Y270505D01*
Y270172D01*
X1150768Y269797D01*
X1150976Y269505D01*
X1151226Y269297D01*
X1151643Y269130D01*
X1152018Y269088D01*
X1152393Y269172D01*
X1152643Y269297D01*
X1152893Y269547D01*
X1153060Y269838D01*
X1153143Y270130D01*
Y270422D01*
X1153060Y270713D01*
X1152935Y270963D01*
X1152768Y271172D01*
G01Y272313D02*
X1152976Y272563D01*
X1153101Y272855D01*
X1153143Y273230D01*
X1153060Y273605D01*
X1152893Y273897D01*
X1152601Y274105D01*
X1152268Y274147D01*
X1151935Y274063D01*
X1151726Y273855D01*
X1151560Y273563D01*
X1151518Y273272D01*
X1151560Y272980D01*
X1151726Y272605D01*
X1150643Y272730D01*
Y273855D01*
G01X1153143Y276330D02*
X1150643D01*
X1151143Y275830D01*
G01X1153143D02*
Y276830D01*
G01X1147351Y271047D02*
X1147226Y270797D01*
X1147143Y270505D01*
Y270172D01*
X1147268Y269797D01*
X1147476Y269505D01*
X1147726Y269297D01*
X1148143Y269130D01*
X1148518Y269088D01*
X1148893Y269172D01*
X1149143Y269297D01*
X1149393Y269547D01*
X1149560Y269838D01*
X1149643Y270130D01*
Y270422D01*
X1149560Y270713D01*
X1149435Y270963D01*
X1149268Y271172D01*
G01Y272313D02*
X1149476Y272563D01*
X1149601Y272855D01*
X1149643Y273230D01*
X1149560Y273605D01*
X1149393Y273897D01*
X1149101Y274105D01*
X1148768Y274147D01*
X1148435Y274063D01*
X1148226Y273855D01*
X1148060Y273563D01*
X1148018Y273272D01*
X1148060Y272980D01*
X1148226Y272605D01*
X1147143Y272730D01*
Y273855D01*
G01Y276330D02*
X1147226Y275997D01*
X1147435Y275747D01*
X1147685Y275580D01*
X1148018Y275455D01*
X1148393Y275413D01*
X1148768Y275455D01*
X1149101Y275580D01*
X1149351Y275747D01*
X1149560Y275997D01*
X1149643Y276330D01*
X1149560Y276663D01*
X1149351Y276913D01*
X1149101Y277080D01*
X1148768Y277205D01*
X1148393Y277247D01*
X1148018Y277205D01*
X1147685Y277080D01*
X1147435Y276913D01*
X1147226Y276663D01*
X1147143Y276330D01*
G01X1174868Y284020D02*
X1174743Y283770D01*
X1174660Y283478D01*
Y283145D01*
X1174785Y282770D01*
X1174993Y282478D01*
X1175243Y282270D01*
X1175660Y282103D01*
X1176035Y282061D01*
X1176410Y282145D01*
X1176660Y282270D01*
X1176910Y282520D01*
X1177077Y282811D01*
X1177160Y283103D01*
Y283395D01*
X1177077Y283686D01*
X1176952Y283936D01*
X1176785Y284145D01*
G01X1177160Y286703D02*
X1174660D01*
X1176452Y285161D01*
Y287245D01*
G01X1176785Y288386D02*
X1176993Y288636D01*
X1177118Y288928D01*
X1177160Y289303D01*
X1177077Y289678D01*
X1176910Y289970D01*
X1176618Y290178D01*
X1176285Y290220D01*
X1175952Y290136D01*
X1175743Y289928D01*
X1175577Y289636D01*
X1175535Y289345D01*
X1175577Y289053D01*
X1175743Y288678D01*
X1174660Y288803D01*
Y289928D01*
G01X1176785Y291486D02*
X1176993Y291736D01*
X1177118Y292028D01*
X1177160Y292403D01*
X1177077Y292778D01*
X1176910Y293070D01*
X1176618Y293278D01*
X1176285Y293320D01*
X1175952Y293236D01*
X1175743Y293028D01*
X1175577Y292736D01*
X1175535Y292445D01*
X1175577Y292153D01*
X1175743Y291778D01*
X1174660Y291903D01*
Y293028D01*
G01X1169807Y284458D02*
X1169682Y284208D01*
X1169599Y283916D01*
Y283583D01*
X1169724Y283208D01*
X1169932Y282916D01*
X1170182Y282708D01*
X1170599Y282541D01*
X1170974Y282499D01*
X1171349Y282583D01*
X1171599Y282708D01*
X1171849Y282958D01*
X1172016Y283249D01*
X1172099Y283541D01*
Y283833D01*
X1172016Y284124D01*
X1171891Y284374D01*
X1171724Y284583D01*
G01X1172099Y287141D02*
X1169599D01*
X1171391Y285599D01*
Y287683D01*
G01X1171724Y288824D02*
X1171932Y289074D01*
X1172057Y289366D01*
X1172099Y289741D01*
X1172016Y290116D01*
X1171849Y290408D01*
X1171557Y290616D01*
X1171224Y290658D01*
X1170891Y290574D01*
X1170682Y290366D01*
X1170516Y290074D01*
X1170474Y289783D01*
X1170516Y289491D01*
X1170682Y289116D01*
X1169599Y289241D01*
Y290366D01*
G01X1172099Y293341D02*
X1169599D01*
X1171391Y291799D01*
Y293883D01*
G01X1163217Y360566D02*
Y363066D01*
X1164258D01*
X1164592Y362941D01*
X1164800Y362774D01*
X1164883Y362441D01*
X1164800Y362108D01*
X1164550Y361899D01*
X1164258Y361774D01*
X1163217D01*
G01X1164258D02*
X1164883Y360566D01*
G01X1166358Y361608D02*
X1166650Y361899D01*
X1166900Y362066D01*
X1167233Y362149D01*
X1167525Y362066D01*
X1167733Y361899D01*
X1167900Y361649D01*
X1167942Y361358D01*
X1167900Y361108D01*
X1167733Y360858D01*
X1167483Y360649D01*
X1167192Y360566D01*
X1166858Y360649D01*
X1166567Y360899D01*
X1166400Y361274D01*
X1166358Y361691D01*
X1166442Y362233D01*
X1166567Y362524D01*
X1166775Y362816D01*
X1167067Y363024D01*
X1167358Y363066D01*
X1167650Y362983D01*
X1167858Y362774D01*
G01X1170167Y360566D02*
X1170250Y361108D01*
X1170375Y361566D01*
X1170542Y361983D01*
X1170750Y362441D01*
X1171083Y363066D01*
X1169417D01*
G01X1172433Y361066D02*
X1172683Y360774D01*
X1173017Y360608D01*
X1173392Y360566D01*
X1173725Y360608D01*
X1174058Y360816D01*
X1174267Y361066D01*
X1174308Y361316D01*
X1174225Y361608D01*
X1173933Y361816D01*
X1173642Y361899D01*
X1173267D01*
G01X1173642D02*
X1173892Y362024D01*
X1174100Y362233D01*
X1174183Y362483D01*
X1174100Y362733D01*
X1173892Y362941D01*
X1173517Y363066D01*
X1173142Y363024D01*
X1172767Y362858D01*
G01X1176317Y360467D02*
Y362967D01*
X1177358D01*
X1177692Y362842D01*
X1177900Y362675D01*
X1177983Y362342D01*
X1177900Y362009D01*
X1177650Y361800D01*
X1177358Y361675D01*
X1176317D01*
G01X1177358D02*
X1177983Y360467D01*
G01X1179458Y361509D02*
X1179750Y361800D01*
X1180000Y361967D01*
X1180333Y362050D01*
X1180625Y361967D01*
X1180833Y361800D01*
X1181000Y361550D01*
X1181042Y361259D01*
X1181000Y361009D01*
X1180833Y360759D01*
X1180583Y360550D01*
X1180292Y360467D01*
X1179958Y360550D01*
X1179667Y360800D01*
X1179500Y361175D01*
X1179458Y361592D01*
X1179542Y362134D01*
X1179667Y362425D01*
X1179875Y362717D01*
X1180167Y362925D01*
X1180458Y362967D01*
X1180750Y362884D01*
X1180958Y362675D01*
G01X1183850Y360467D02*
Y362967D01*
X1182308Y361175D01*
X1184392D01*
G01X1186450Y360467D02*
Y362967D01*
X1185950Y362467D01*
G01Y360467D02*
X1186950D01*
G01X1168167Y364566D02*
Y367066D01*
X1169208D01*
X1169542Y366941D01*
X1169750Y366774D01*
X1169833Y366441D01*
X1169750Y366108D01*
X1169500Y365899D01*
X1169208Y365774D01*
X1168167D01*
G01X1169208D02*
X1169833Y364566D01*
G01X1172017D02*
X1172100Y365108D01*
X1172225Y365566D01*
X1172392Y365983D01*
X1172600Y366441D01*
X1172933Y367066D01*
X1171267D01*
G01X1174492Y364858D02*
X1174783Y364649D01*
X1175117Y364566D01*
X1175450Y364649D01*
X1175742Y364899D01*
X1175950Y365274D01*
X1176033Y365649D01*
Y366108D01*
X1175950Y366483D01*
X1175742Y366816D01*
X1175492Y366983D01*
X1175200Y367066D01*
X1174867Y366983D01*
X1174617Y366816D01*
X1174450Y366566D01*
X1174367Y366233D01*
X1174450Y365941D01*
X1174658Y365649D01*
X1174908Y365483D01*
X1175200Y365441D01*
X1175533Y365524D01*
X1175783Y365733D01*
X1176033Y366108D01*
G01X1178300Y364566D02*
Y367066D01*
X1177800Y366566D01*
G01Y364566D02*
X1178800D01*
G01X1181317D02*
X1181400Y365108D01*
X1181525Y365566D01*
X1181692Y365983D01*
X1181900Y366441D01*
X1182233Y367066D01*
X1180567D01*
G01X1170057Y371308D02*
X1169807Y371433D01*
X1169515Y371516D01*
X1169182D01*
X1168807Y371391D01*
X1168515Y371183D01*
X1168307Y370933D01*
X1168140Y370516D01*
X1168098Y370141D01*
X1168182Y369766D01*
X1168307Y369516D01*
X1168557Y369266D01*
X1168848Y369099D01*
X1169140Y369016D01*
X1169432D01*
X1169723Y369099D01*
X1169973Y369224D01*
X1170182Y369391D01*
G01X1171448Y371099D02*
X1171698Y371349D01*
X1171990Y371474D01*
X1172323Y371516D01*
X1172740Y371433D01*
X1173032Y371224D01*
X1173115Y370974D01*
X1173073Y370724D01*
X1172907Y370516D01*
X1172073Y370099D01*
X1171698Y369808D01*
X1171448Y369391D01*
X1171365Y369016D01*
X1173115D01*
G01X1174548Y370058D02*
X1174840Y370349D01*
X1175090Y370516D01*
X1175423Y370599D01*
X1175715Y370516D01*
X1175923Y370349D01*
X1176090Y370099D01*
X1176132Y369808D01*
X1176090Y369558D01*
X1175923Y369308D01*
X1175673Y369099D01*
X1175382Y369016D01*
X1175048Y369099D01*
X1174757Y369349D01*
X1174590Y369724D01*
X1174548Y370141D01*
X1174632Y370683D01*
X1174757Y370974D01*
X1174965Y371266D01*
X1175257Y371474D01*
X1175548Y371516D01*
X1175840Y371433D01*
X1176048Y371224D01*
G01X1177648Y370058D02*
X1177940Y370349D01*
X1178190Y370516D01*
X1178523Y370599D01*
X1178815Y370516D01*
X1179023Y370349D01*
X1179190Y370099D01*
X1179232Y369808D01*
X1179190Y369558D01*
X1179023Y369308D01*
X1178773Y369099D01*
X1178482Y369016D01*
X1178148Y369099D01*
X1177857Y369349D01*
X1177690Y369724D01*
X1177648Y370141D01*
X1177732Y370683D01*
X1177857Y370974D01*
X1178065Y371266D01*
X1178357Y371474D01*
X1178648Y371516D01*
X1178940Y371433D01*
X1179148Y371224D01*
G01X1155534Y384917D02*
X1153034D01*
Y385917D01*
X1153159Y386250D01*
X1153451Y386500D01*
X1153784Y386583D01*
X1154117Y386500D01*
X1154367Y386292D01*
X1154492Y385917D01*
Y384917D01*
G01X1155534Y388850D02*
X1155492Y388517D01*
X1155326Y388225D01*
X1155076Y387975D01*
X1154784Y387808D01*
X1154451Y387725D01*
X1154117D01*
X1153784Y387808D01*
X1153492Y387975D01*
X1153242Y388225D01*
X1153076Y388517D01*
X1153034Y388850D01*
X1153076Y389183D01*
X1153242Y389475D01*
X1153492Y389725D01*
X1153784Y389892D01*
X1154117Y389975D01*
X1154451D01*
X1154784Y389892D01*
X1155076Y389725D01*
X1155326Y389475D01*
X1155492Y389183D01*
X1155534Y388850D01*
G01X1154867Y389183D02*
X1155534Y389683D01*
G01X1153451Y391158D02*
X1153201Y391408D01*
X1153076Y391700D01*
X1153034Y392033D01*
X1153117Y392450D01*
X1153326Y392742D01*
X1153576Y392825D01*
X1153826Y392783D01*
X1154034Y392617D01*
X1154451Y391783D01*
X1154742Y391408D01*
X1155159Y391158D01*
X1155534Y391075D01*
Y392825D01*
G01Y395050D02*
X1153034D01*
X1153534Y394550D01*
G01X1155534D02*
Y395550D01*
G01X1147534Y386933D02*
X1149326D01*
X1149701Y387100D01*
X1149951Y387433D01*
X1150034Y387850D01*
X1149951Y388267D01*
X1149701Y388600D01*
X1149326Y388767D01*
X1147534D01*
G01X1150034Y391450D02*
X1147534D01*
X1149326Y389908D01*
Y391992D01*
G01X1157783Y390963D02*
Y393463D01*
X1158824D01*
X1159158Y393338D01*
X1159366Y393171D01*
X1159449Y392838D01*
X1159366Y392505D01*
X1159116Y392296D01*
X1158824Y392171D01*
X1157783D01*
G01X1158824D02*
X1159449Y390963D01*
G01X1161633D02*
X1161716Y391505D01*
X1161841Y391963D01*
X1162008Y392380D01*
X1162216Y392838D01*
X1162549Y393463D01*
X1160883D01*
G01X1164108Y391255D02*
X1164399Y391046D01*
X1164733Y390963D01*
X1165066Y391046D01*
X1165358Y391296D01*
X1165566Y391671D01*
X1165649Y392046D01*
Y392505D01*
X1165566Y392880D01*
X1165358Y393213D01*
X1165108Y393380D01*
X1164816Y393463D01*
X1164483Y393380D01*
X1164233Y393213D01*
X1164066Y392963D01*
X1163983Y392630D01*
X1164066Y392338D01*
X1164274Y392046D01*
X1164524Y391880D01*
X1164816Y391838D01*
X1165149Y391921D01*
X1165399Y392130D01*
X1165649Y392505D01*
G01X1167916Y393463D02*
X1167583Y393380D01*
X1167333Y393171D01*
X1167166Y392921D01*
X1167041Y392588D01*
X1166999Y392213D01*
X1167041Y391838D01*
X1167166Y391505D01*
X1167333Y391255D01*
X1167583Y391046D01*
X1167916Y390963D01*
X1168249Y391046D01*
X1168499Y391255D01*
X1168666Y391505D01*
X1168791Y391838D01*
X1168833Y392213D01*
X1168791Y392588D01*
X1168666Y392921D01*
X1168499Y393171D01*
X1168249Y393380D01*
X1167916Y393463D01*
G01X1170099Y391338D02*
X1170349Y391130D01*
X1170641Y391005D01*
X1171016Y390963D01*
X1171391Y391046D01*
X1171683Y391213D01*
X1171891Y391505D01*
X1171933Y391838D01*
X1171849Y392171D01*
X1171641Y392380D01*
X1171349Y392546D01*
X1171058Y392588D01*
X1170766Y392546D01*
X1170391Y392380D01*
X1170516Y393463D01*
X1171641D01*
G01X1157717Y386566D02*
Y389066D01*
X1158758D01*
X1159092Y388941D01*
X1159300Y388774D01*
X1159383Y388441D01*
X1159300Y388108D01*
X1159050Y387899D01*
X1158758Y387774D01*
X1157717D01*
G01X1158758D02*
X1159383Y386566D01*
G01X1160858Y387608D02*
X1161150Y387899D01*
X1161400Y388066D01*
X1161733Y388149D01*
X1162025Y388066D01*
X1162233Y387899D01*
X1162400Y387649D01*
X1162442Y387358D01*
X1162400Y387108D01*
X1162233Y386858D01*
X1161983Y386649D01*
X1161692Y386566D01*
X1161358Y386649D01*
X1161067Y386899D01*
X1160900Y387274D01*
X1160858Y387691D01*
X1160942Y388233D01*
X1161067Y388524D01*
X1161275Y388816D01*
X1161567Y389024D01*
X1161858Y389066D01*
X1162150Y388983D01*
X1162358Y388774D01*
G01X1164042Y386858D02*
X1164333Y386649D01*
X1164667Y386566D01*
X1165000Y386649D01*
X1165292Y386899D01*
X1165500Y387274D01*
X1165583Y387649D01*
Y388108D01*
X1165500Y388483D01*
X1165292Y388816D01*
X1165042Y388983D01*
X1164750Y389066D01*
X1164417Y388983D01*
X1164167Y388816D01*
X1164000Y388566D01*
X1163917Y388233D01*
X1164000Y387941D01*
X1164208Y387649D01*
X1164458Y387483D01*
X1164750Y387441D01*
X1165083Y387524D01*
X1165333Y387733D01*
X1165583Y388108D01*
G01X1167767Y386566D02*
X1167850Y387108D01*
X1167975Y387566D01*
X1168142Y387983D01*
X1168350Y388441D01*
X1168683Y389066D01*
X1167017D01*
G01X1172167Y379600D02*
Y382100D01*
X1173208D01*
X1173542Y381975D01*
X1173750Y381808D01*
X1173833Y381475D01*
X1173750Y381142D01*
X1173500Y380933D01*
X1173208Y380808D01*
X1172167D01*
G01X1173208D02*
X1173833Y379600D01*
G01X1176017D02*
X1176100Y380142D01*
X1176225Y380600D01*
X1176392Y381017D01*
X1176600Y381475D01*
X1176933Y382100D01*
X1175267D01*
G01X1178492Y379892D02*
X1178783Y379683D01*
X1179117Y379600D01*
X1179450Y379683D01*
X1179742Y379933D01*
X1179950Y380308D01*
X1180033Y380683D01*
Y381142D01*
X1179950Y381517D01*
X1179742Y381850D01*
X1179492Y382017D01*
X1179200Y382100D01*
X1178867Y382017D01*
X1178617Y381850D01*
X1178450Y381600D01*
X1178367Y381267D01*
X1178450Y380975D01*
X1178658Y380683D01*
X1178908Y380517D01*
X1179200Y380475D01*
X1179533Y380558D01*
X1179783Y380767D01*
X1180033Y381142D01*
G01X1182300Y382100D02*
X1181967Y382017D01*
X1181717Y381808D01*
X1181550Y381558D01*
X1181425Y381225D01*
X1181383Y380850D01*
X1181425Y380475D01*
X1181550Y380142D01*
X1181717Y379892D01*
X1181967Y379683D01*
X1182300Y379600D01*
X1182633Y379683D01*
X1182883Y379892D01*
X1183050Y380142D01*
X1183175Y380475D01*
X1183217Y380850D01*
X1183175Y381225D01*
X1183050Y381558D01*
X1182883Y381808D01*
X1182633Y382017D01*
X1182300Y382100D01*
G01X1184483Y380100D02*
X1184733Y379808D01*
X1185067Y379642D01*
X1185442Y379600D01*
X1185775Y379642D01*
X1186108Y379850D01*
X1186317Y380100D01*
X1186358Y380350D01*
X1186275Y380642D01*
X1185983Y380850D01*
X1185692Y380933D01*
X1185317D01*
G01X1185692D02*
X1185942Y381058D01*
X1186150Y381267D01*
X1186233Y381517D01*
X1186150Y381767D01*
X1185942Y381975D01*
X1185567Y382100D01*
X1185192Y382058D01*
X1184817Y381892D01*
G01X1168167Y407566D02*
Y410066D01*
X1169208D01*
X1169542Y409941D01*
X1169750Y409774D01*
X1169833Y409441D01*
X1169750Y409108D01*
X1169500Y408899D01*
X1169208Y408774D01*
X1168167D01*
G01X1169208D02*
X1169833Y407566D01*
G01X1172017D02*
X1172100Y408108D01*
X1172225Y408566D01*
X1172392Y408983D01*
X1172600Y409441D01*
X1172933Y410066D01*
X1171267D01*
G01X1174492Y407858D02*
X1174783Y407649D01*
X1175117Y407566D01*
X1175450Y407649D01*
X1175742Y407899D01*
X1175950Y408274D01*
X1176033Y408649D01*
Y409108D01*
X1175950Y409483D01*
X1175742Y409816D01*
X1175492Y409983D01*
X1175200Y410066D01*
X1174867Y409983D01*
X1174617Y409816D01*
X1174450Y409566D01*
X1174367Y409233D01*
X1174450Y408941D01*
X1174658Y408649D01*
X1174908Y408483D01*
X1175200Y408441D01*
X1175533Y408524D01*
X1175783Y408733D01*
X1176033Y409108D01*
G01X1178300Y410066D02*
X1177967Y409983D01*
X1177717Y409774D01*
X1177550Y409524D01*
X1177425Y409191D01*
X1177383Y408816D01*
X1177425Y408441D01*
X1177550Y408108D01*
X1177717Y407858D01*
X1177967Y407649D01*
X1178300Y407566D01*
X1178633Y407649D01*
X1178883Y407858D01*
X1179050Y408108D01*
X1179175Y408441D01*
X1179217Y408816D01*
X1179175Y409191D01*
X1179050Y409524D01*
X1178883Y409774D01*
X1178633Y409983D01*
X1178300Y410066D01*
G01X1181900Y407566D02*
Y410066D01*
X1180358Y408274D01*
X1182442D01*
G01X1158376Y405779D02*
X1155876D01*
Y406820D01*
X1156001Y407154D01*
X1156168Y407362D01*
X1156501Y407445D01*
X1156834Y407362D01*
X1157043Y407112D01*
X1157168Y406820D01*
Y405779D01*
G01Y406820D02*
X1158376Y407445D01*
G01Y410212D02*
X1155876D01*
X1157668Y408670D01*
Y410754D01*
G01X1152876Y404229D02*
X1150376D01*
Y405270D01*
X1150501Y405604D01*
X1150668Y405812D01*
X1151001Y405895D01*
X1151334Y405812D01*
X1151543Y405562D01*
X1151668Y405270D01*
Y404229D01*
G01Y405270D02*
X1152876Y405895D01*
G01X1152376Y407245D02*
X1152668Y407495D01*
X1152834Y407829D01*
X1152876Y408204D01*
X1152834Y408537D01*
X1152626Y408870D01*
X1152376Y409079D01*
X1152126Y409120D01*
X1151834Y409037D01*
X1151626Y408745D01*
X1151543Y408454D01*
Y408079D01*
G01Y408454D02*
X1151418Y408704D01*
X1151209Y408912D01*
X1150959Y408995D01*
X1150709Y408912D01*
X1150501Y408704D01*
X1150376Y408329D01*
X1150418Y407954D01*
X1150584Y407579D01*
G01X1152876Y411262D02*
X1150376D01*
X1150876Y410762D01*
G01X1152876D02*
Y411762D01*
G01X1148383Y408417D02*
X1145883D01*
Y409458D01*
X1146008Y409792D01*
X1146175Y410000D01*
X1146508Y410083D01*
X1146841Y410000D01*
X1147050Y409750D01*
X1147175Y409458D01*
Y408417D01*
G01Y409458D02*
X1148383Y410083D01*
G01Y412350D02*
X1145883D01*
X1146383Y411850D01*
G01X1148383D02*
Y412850D01*
G01X1146300Y414658D02*
X1146050Y414908D01*
X1145925Y415200D01*
X1145883Y415533D01*
X1145966Y415950D01*
X1146175Y416242D01*
X1146425Y416325D01*
X1146675Y416283D01*
X1146883Y416117D01*
X1147300Y415283D01*
X1147591Y414908D01*
X1148008Y414658D01*
X1148383Y414575D01*
Y416325D01*
G01X1173742Y386167D02*
X1173617Y385917D01*
X1173534Y385625D01*
Y385292D01*
X1173659Y384917D01*
X1173867Y384625D01*
X1174117Y384417D01*
X1174534Y384250D01*
X1174909Y384208D01*
X1175284Y384292D01*
X1175534Y384417D01*
X1175784Y384667D01*
X1175951Y384958D01*
X1176034Y385250D01*
Y385542D01*
X1175951Y385833D01*
X1175826Y386083D01*
X1175659Y386292D01*
G01X1175534Y387433D02*
X1175826Y387683D01*
X1175992Y388017D01*
X1176034Y388392D01*
X1175992Y388725D01*
X1175784Y389058D01*
X1175534Y389267D01*
X1175284Y389308D01*
X1174992Y389225D01*
X1174784Y388933D01*
X1174701Y388642D01*
Y388267D01*
G01Y388642D02*
X1174576Y388892D01*
X1174367Y389100D01*
X1174117Y389183D01*
X1173867Y389100D01*
X1173659Y388892D01*
X1173534Y388517D01*
X1173576Y388142D01*
X1173742Y387767D01*
G01X1176034Y391367D02*
X1175492Y391450D01*
X1175034Y391575D01*
X1174617Y391742D01*
X1174159Y391950D01*
X1173534Y392283D01*
Y390617D01*
G01X1175659Y393633D02*
X1175867Y393883D01*
X1175992Y394175D01*
X1176034Y394550D01*
X1175951Y394925D01*
X1175784Y395217D01*
X1175492Y395425D01*
X1175159Y395467D01*
X1174826Y395383D01*
X1174617Y395175D01*
X1174451Y394883D01*
X1174409Y394592D01*
X1174451Y394300D01*
X1174617Y393925D01*
X1173534Y394050D01*
Y395175D01*
G01X1177867Y405092D02*
X1177617Y405217D01*
X1177325Y405300D01*
X1176992D01*
X1176617Y405175D01*
X1176325Y404967D01*
X1176117Y404717D01*
X1175950Y404300D01*
X1175908Y403925D01*
X1175992Y403550D01*
X1176117Y403300D01*
X1176367Y403050D01*
X1176658Y402883D01*
X1176950Y402800D01*
X1177242D01*
X1177533Y402883D01*
X1177783Y403008D01*
X1177992Y403175D01*
G01X1179258Y404883D02*
X1179508Y405133D01*
X1179800Y405258D01*
X1180133Y405300D01*
X1180550Y405217D01*
X1180842Y405008D01*
X1180925Y404758D01*
X1180883Y404508D01*
X1180717Y404300D01*
X1179883Y403883D01*
X1179508Y403592D01*
X1179258Y403175D01*
X1179175Y402800D01*
X1180925D01*
G01X1183650D02*
Y405300D01*
X1182108Y403508D01*
X1184192D01*
G01X1186250Y402800D02*
Y405300D01*
X1185750Y404800D01*
G01Y402800D02*
X1186750D01*
G01X1150575Y379399D02*
X1150908Y379191D01*
X1151283Y379066D01*
X1151617D01*
X1151950Y379191D01*
X1152200Y379399D01*
X1152325Y379691D01*
X1152242Y379983D01*
X1152033Y380233D01*
X1151658Y380399D01*
X1151158Y380483D01*
X1150867Y380649D01*
X1150742Y380941D01*
X1150825Y381233D01*
X1151033Y381441D01*
X1151325Y381566D01*
X1151617D01*
X1151908Y381483D01*
X1152158Y381274D01*
G01X1155467Y381358D02*
X1155217Y381483D01*
X1154925Y381566D01*
X1154592D01*
X1154217Y381441D01*
X1153925Y381233D01*
X1153717Y380983D01*
X1153550Y380566D01*
X1153508Y380191D01*
X1153592Y379816D01*
X1153717Y379566D01*
X1153967Y379316D01*
X1154258Y379149D01*
X1154550Y379066D01*
X1154842D01*
X1155133Y379149D01*
X1155383Y379274D01*
X1155592Y379441D01*
G01X1157650Y379066D02*
Y381566D01*
X1157150Y381066D01*
G01Y379066D02*
X1158150D01*
G01X1159833Y379566D02*
X1160083Y379274D01*
X1160417Y379108D01*
X1160792Y379066D01*
X1161125Y379108D01*
X1161458Y379316D01*
X1161667Y379566D01*
X1161708Y379816D01*
X1161625Y380108D01*
X1161333Y380316D01*
X1161042Y380399D01*
X1160667D01*
G01X1161042D02*
X1161292Y380524D01*
X1161500Y380733D01*
X1161583Y380983D01*
X1161500Y381233D01*
X1161292Y381441D01*
X1160917Y381566D01*
X1160542Y381524D01*
X1160167Y381358D01*
G01X1163850Y381566D02*
X1163517Y381483D01*
X1163267Y381274D01*
X1163100Y381024D01*
X1162975Y380691D01*
X1162933Y380316D01*
X1162975Y379941D01*
X1163100Y379608D01*
X1163267Y379358D01*
X1163517Y379149D01*
X1163850Y379066D01*
X1164183Y379149D01*
X1164433Y379358D01*
X1164600Y379608D01*
X1164725Y379941D01*
X1164767Y380316D01*
X1164725Y380691D01*
X1164600Y381024D01*
X1164433Y381274D01*
X1164183Y381483D01*
X1163850Y381566D01*
G01X1166158Y381149D02*
X1166408Y381399D01*
X1166700Y381524D01*
X1167033Y381566D01*
X1167450Y381483D01*
X1167742Y381274D01*
X1167825Y381024D01*
X1167783Y380774D01*
X1167617Y380566D01*
X1166783Y380149D01*
X1166408Y379858D01*
X1166158Y379441D01*
X1166075Y379066D01*
X1167825D01*
G01X1159859Y406023D02*
X1159734Y405773D01*
X1159651Y405481D01*
Y405148D01*
X1159776Y404773D01*
X1159984Y404481D01*
X1160234Y404273D01*
X1160651Y404106D01*
X1161026Y404064D01*
X1161401Y404148D01*
X1161651Y404273D01*
X1161901Y404523D01*
X1162068Y404814D01*
X1162151Y405106D01*
Y405398D01*
X1162068Y405689D01*
X1161943Y405939D01*
X1161776Y406148D01*
G01X1162151Y408706D02*
X1159651D01*
X1161443Y407164D01*
Y409248D01*
G01X1160068Y410514D02*
X1159818Y410764D01*
X1159693Y411056D01*
X1159651Y411389D01*
X1159734Y411806D01*
X1159943Y412098D01*
X1160193Y412181D01*
X1160443Y412139D01*
X1160651Y411973D01*
X1161068Y411139D01*
X1161359Y410764D01*
X1161776Y410514D01*
X1162151Y410431D01*
Y412181D01*
G01X1153267Y415066D02*
Y417566D01*
X1154308D01*
X1154642Y417441D01*
X1154850Y417274D01*
X1154933Y416941D01*
X1154850Y416608D01*
X1154600Y416399D01*
X1154308Y416274D01*
X1153267D01*
G01X1154308D02*
X1154933Y415066D01*
G01X1156283Y415566D02*
X1156533Y415274D01*
X1156867Y415108D01*
X1157242Y415066D01*
X1157575Y415108D01*
X1157908Y415316D01*
X1158117Y415566D01*
X1158158Y415816D01*
X1158075Y416108D01*
X1157783Y416316D01*
X1157492Y416399D01*
X1157117D01*
G01X1157492D02*
X1157742Y416524D01*
X1157950Y416733D01*
X1158033Y416983D01*
X1157950Y417233D01*
X1157742Y417441D01*
X1157367Y417566D01*
X1156992Y417524D01*
X1156617Y417358D01*
G01X1160300Y417566D02*
X1159967Y417483D01*
X1159717Y417274D01*
X1159550Y417024D01*
X1159425Y416691D01*
X1159383Y416316D01*
X1159425Y415941D01*
X1159550Y415608D01*
X1159717Y415358D01*
X1159967Y415149D01*
X1160300Y415066D01*
X1160633Y415149D01*
X1160883Y415358D01*
X1161050Y415608D01*
X1161175Y415941D01*
X1161217Y416316D01*
X1161175Y416691D01*
X1161050Y417024D01*
X1160883Y417274D01*
X1160633Y417483D01*
X1160300Y417566D01*
G01X1170696Y810271D02*
X1170446Y810396D01*
X1170154Y810479D01*
X1169821D01*
X1169446Y810354D01*
X1169154Y810146D01*
X1168946Y809896D01*
X1168779Y809479D01*
X1168737Y809104D01*
X1168821Y808729D01*
X1168946Y808479D01*
X1169196Y808229D01*
X1169487Y808062D01*
X1169779Y807979D01*
X1170071D01*
X1170362Y808062D01*
X1170612Y808187D01*
X1170821Y808354D01*
G01X1173379Y807979D02*
Y810479D01*
X1171837Y808687D01*
X1173921D01*
G01X1175979Y807979D02*
Y810479D01*
X1175479Y809979D01*
G01Y807979D02*
X1176479D01*
G01X1178162Y808479D02*
X1178412Y808187D01*
X1178746Y808021D01*
X1179121Y807979D01*
X1179454Y808021D01*
X1179787Y808229D01*
X1179996Y808479D01*
X1180037Y808729D01*
X1179954Y809021D01*
X1179662Y809229D01*
X1179371Y809312D01*
X1178996D01*
G01X1179371D02*
X1179621Y809437D01*
X1179829Y809646D01*
X1179912Y809896D01*
X1179829Y810146D01*
X1179621Y810354D01*
X1179246Y810479D01*
X1178871Y810437D01*
X1178496Y810271D01*
G01X1181387Y810062D02*
X1181637Y810312D01*
X1181929Y810437D01*
X1182262Y810479D01*
X1182679Y810396D01*
X1182971Y810187D01*
X1183054Y809937D01*
X1183012Y809687D01*
X1182846Y809479D01*
X1182012Y809062D01*
X1181637Y808771D01*
X1181387Y808354D01*
X1181304Y807979D01*
X1183054D01*
G01X1145266Y817734D02*
X1145141Y817484D01*
X1145058Y817192D01*
Y816859D01*
X1145183Y816484D01*
X1145391Y816192D01*
X1145641Y815984D01*
X1146058Y815817D01*
X1146433Y815775D01*
X1146808Y815859D01*
X1147058Y815984D01*
X1147308Y816234D01*
X1147475Y816525D01*
X1147558Y816817D01*
Y817109D01*
X1147475Y817400D01*
X1147350Y817650D01*
X1147183Y817859D01*
G01X1147266Y819209D02*
X1147475Y819500D01*
X1147558Y819834D01*
X1147475Y820167D01*
X1147225Y820459D01*
X1146850Y820667D01*
X1146475Y820750D01*
X1146016D01*
X1145641Y820667D01*
X1145308Y820459D01*
X1145141Y820209D01*
X1145058Y819917D01*
X1145141Y819584D01*
X1145308Y819334D01*
X1145558Y819167D01*
X1145891Y819084D01*
X1146183Y819167D01*
X1146475Y819375D01*
X1146641Y819625D01*
X1146683Y819917D01*
X1146600Y820250D01*
X1146391Y820500D01*
X1146016Y820750D01*
G01X1147558Y823017D02*
X1145058D01*
X1145558Y822517D01*
G01X1147558D02*
Y823517D01*
G01X1153864Y817734D02*
X1153739Y817484D01*
X1153656Y817192D01*
Y816859D01*
X1153781Y816484D01*
X1153989Y816192D01*
X1154239Y815984D01*
X1154656Y815817D01*
X1155031Y815775D01*
X1155406Y815859D01*
X1155656Y815984D01*
X1155906Y816234D01*
X1156073Y816525D01*
X1156156Y816817D01*
Y817109D01*
X1156073Y817400D01*
X1155948Y817650D01*
X1155781Y817859D01*
G01X1156156Y819834D02*
X1155614Y819917D01*
X1155156Y820042D01*
X1154739Y820209D01*
X1154281Y820417D01*
X1153656Y820750D01*
Y819084D01*
G01X1155864Y822309D02*
X1156073Y822600D01*
X1156156Y822934D01*
X1156073Y823267D01*
X1155823Y823559D01*
X1155448Y823767D01*
X1155073Y823850D01*
X1154614D01*
X1154239Y823767D01*
X1153906Y823559D01*
X1153739Y823309D01*
X1153656Y823017D01*
X1153739Y822684D01*
X1153906Y822434D01*
X1154156Y822267D01*
X1154489Y822184D01*
X1154781Y822267D01*
X1155073Y822475D01*
X1155239Y822725D01*
X1155281Y823017D01*
X1155198Y823350D01*
X1154989Y823600D01*
X1154614Y823850D01*
G01X1157864Y817734D02*
X1157739Y817484D01*
X1157656Y817192D01*
Y816859D01*
X1157781Y816484D01*
X1157989Y816192D01*
X1158239Y815984D01*
X1158656Y815817D01*
X1159031Y815775D01*
X1159406Y815859D01*
X1159656Y815984D01*
X1159906Y816234D01*
X1160073Y816525D01*
X1160156Y816817D01*
Y817109D01*
X1160073Y817400D01*
X1159948Y817650D01*
X1159781Y817859D01*
G01X1160156Y819834D02*
X1159614Y819917D01*
X1159156Y820042D01*
X1158739Y820209D01*
X1158281Y820417D01*
X1157656Y820750D01*
Y819084D01*
G01X1160156Y823017D02*
X1160114Y823309D01*
X1159989Y823642D01*
X1159781Y823850D01*
X1159489Y823934D01*
X1159198Y823850D01*
X1158948Y823600D01*
X1158823Y823225D01*
Y822809D01*
X1158739Y822559D01*
X1158531Y822350D01*
X1158239Y822267D01*
X1157948Y822392D01*
X1157739Y822684D01*
X1157656Y823017D01*
X1157739Y823350D01*
X1157948Y823642D01*
X1158239Y823767D01*
X1158531Y823684D01*
X1158739Y823475D01*
X1158823Y823225D01*
Y822809D01*
X1158948Y822434D01*
X1159198Y822184D01*
X1159489Y822100D01*
X1159781Y822184D01*
X1159989Y822392D01*
X1160114Y822725D01*
X1160156Y823017D01*
G01X1176905Y818968D02*
X1176780Y818718D01*
X1176697Y818426D01*
Y818093D01*
X1176822Y817718D01*
X1177030Y817426D01*
X1177280Y817218D01*
X1177697Y817051D01*
X1178072Y817009D01*
X1178447Y817093D01*
X1178697Y817218D01*
X1178947Y817468D01*
X1179114Y817759D01*
X1179197Y818051D01*
Y818343D01*
X1179114Y818634D01*
X1178989Y818884D01*
X1178822Y819093D01*
G01X1179197Y821068D02*
X1178655Y821151D01*
X1178197Y821276D01*
X1177780Y821443D01*
X1177322Y821651D01*
X1176697Y821984D01*
Y820318D01*
G01X1178155Y823459D02*
X1177864Y823751D01*
X1177697Y824001D01*
X1177614Y824334D01*
X1177697Y824626D01*
X1177864Y824834D01*
X1178114Y825001D01*
X1178405Y825043D01*
X1178655Y825001D01*
X1178905Y824834D01*
X1179114Y824584D01*
X1179197Y824293D01*
X1179114Y823959D01*
X1178864Y823668D01*
X1178489Y823501D01*
X1178072Y823459D01*
X1177530Y823543D01*
X1177239Y823668D01*
X1176947Y823876D01*
X1176739Y824168D01*
X1176697Y824459D01*
X1176780Y824751D01*
X1176989Y824959D01*
G01X1183752Y-13114D02*
Y-9114D01*
X1185352D01*
X1185885Y-9314D01*
X1186285Y-9781D01*
X1186418Y-10314D01*
X1186285Y-10847D01*
X1185952Y-11247D01*
X1185352Y-11447D01*
X1183752D01*
G01X1188752Y-13114D02*
Y-10447D01*
G01Y-10981D02*
X1189085Y-10714D01*
X1189418Y-10514D01*
X1189885Y-10447D01*
X1190218Y-10514D01*
X1190618Y-10714D01*
G01X1193285Y-11314D02*
X1195418D01*
X1195218Y-10847D01*
X1194885Y-10581D01*
X1194418Y-10447D01*
X1193952Y-10514D01*
X1193552Y-10714D01*
X1193285Y-11181D01*
X1193152Y-11581D01*
Y-11981D01*
X1193285Y-12381D01*
X1193618Y-12781D01*
X1194018Y-13047D01*
X1194485Y-13114D01*
X1194952Y-12981D01*
X1195418Y-12581D01*
G01X1197885Y-12647D02*
X1198218Y-12914D01*
X1198685Y-13114D01*
X1199085D01*
X1199485Y-12981D01*
X1199752Y-12781D01*
X1199885Y-12514D01*
X1199818Y-12114D01*
X1199552Y-11914D01*
X1198352Y-11514D01*
X1198085Y-11047D01*
X1198218Y-10714D01*
X1198485Y-10514D01*
X1198885Y-10447D01*
X1199285Y-10514D01*
X1199685Y-10714D01*
G01X1202485Y-12647D02*
X1202818Y-12914D01*
X1203285Y-13114D01*
X1203685D01*
X1204085Y-12981D01*
X1204352Y-12781D01*
X1204485Y-12514D01*
X1204418Y-12114D01*
X1204152Y-11914D01*
X1202952Y-11514D01*
X1202685Y-11047D01*
X1202818Y-10714D01*
X1203085Y-10514D01*
X1203485Y-10447D01*
X1203885Y-10514D01*
X1204285Y-10714D01*
G01X1211418Y-13114D02*
Y-9114D01*
X1213952D01*
G01X1213018Y-11047D02*
X1211418D01*
G01X1217285Y-10447D02*
Y-13114D01*
G01Y-9381D02*
X1217152Y-9314D01*
Y-9181D01*
X1217285Y-9114D01*
X1217418Y-9181D01*
Y-9314D01*
X1217285Y-9381D01*
G01X1221885Y-9114D02*
Y-13114D01*
G01X1220952Y-10447D02*
X1222818D01*
G01X1185981Y113987D02*
X1186381Y114237D01*
X1186681Y114653D01*
X1186881Y115237D01*
X1186681Y115737D01*
X1186281Y116070D01*
X1185581Y116320D01*
X1182881D01*
Y111320D01*
X1186181D01*
X1186881Y111653D01*
X1187281Y112153D01*
X1187481Y112737D01*
X1187281Y113320D01*
X1186681Y113820D01*
X1185981Y113987D01*
X1182881D01*
G01X1207500Y120000D02*
X1213500D01*
G01X1199500Y125000D02*
X1204500D01*
Y120000D01*
G01X1193500Y127500D02*
Y143500D01*
X1195000D01*
G01X1210748Y128115D02*
X1214748D01*
Y135515D01*
G01X1194008Y119917D02*
X1193883Y119667D01*
X1193800Y119375D01*
Y119042D01*
X1193925Y118667D01*
X1194133Y118375D01*
X1194383Y118167D01*
X1194800Y118000D01*
X1195175Y117958D01*
X1195550Y118042D01*
X1195800Y118167D01*
X1196050Y118417D01*
X1196217Y118708D01*
X1196300Y119000D01*
Y119292D01*
X1196217Y119583D01*
X1196092Y119833D01*
X1195925Y120042D01*
G01X1194217Y121308D02*
X1193967Y121558D01*
X1193842Y121850D01*
X1193800Y122183D01*
X1193883Y122600D01*
X1194092Y122892D01*
X1194342Y122975D01*
X1194592Y122933D01*
X1194800Y122767D01*
X1195217Y121933D01*
X1195508Y121558D01*
X1195925Y121308D01*
X1196300Y121225D01*
Y122975D01*
G01Y125700D02*
X1193800D01*
X1195592Y124158D01*
Y126242D01*
G01X1190694Y119935D02*
X1190569Y119685D01*
X1190486Y119393D01*
Y119060D01*
X1190611Y118685D01*
X1190819Y118393D01*
X1191069Y118185D01*
X1191486Y118018D01*
X1191861Y117976D01*
X1192236Y118060D01*
X1192486Y118185D01*
X1192736Y118435D01*
X1192903Y118726D01*
X1192986Y119018D01*
Y119310D01*
X1192903Y119601D01*
X1192778Y119851D01*
X1192611Y120060D01*
G01X1192986Y122118D02*
X1190486D01*
X1190986Y121618D01*
G01X1192986D02*
Y122618D01*
G01X1191944Y124426D02*
X1191653Y124718D01*
X1191486Y124968D01*
X1191403Y125301D01*
X1191486Y125593D01*
X1191653Y125801D01*
X1191903Y125968D01*
X1192194Y126010D01*
X1192444Y125968D01*
X1192694Y125801D01*
X1192903Y125551D01*
X1192986Y125260D01*
X1192903Y124926D01*
X1192653Y124635D01*
X1192278Y124468D01*
X1191861Y124426D01*
X1191319Y124510D01*
X1191028Y124635D01*
X1190736Y124843D01*
X1190528Y125135D01*
X1190486Y125426D01*
X1190569Y125718D01*
X1190778Y125926D01*
G01X1181904Y120525D02*
X1181779Y120275D01*
X1181696Y119983D01*
Y119650D01*
X1181821Y119275D01*
X1182029Y118983D01*
X1182279Y118775D01*
X1182696Y118608D01*
X1183071Y118566D01*
X1183446Y118650D01*
X1183696Y118775D01*
X1183946Y119025D01*
X1184113Y119316D01*
X1184196Y119608D01*
Y119900D01*
X1184113Y120191D01*
X1183988Y120441D01*
X1183821Y120650D01*
G01X1184196Y122708D02*
X1181696D01*
X1182196Y122208D01*
G01X1184196D02*
Y123208D01*
G01X1183821Y124891D02*
X1184029Y125141D01*
X1184154Y125433D01*
X1184196Y125808D01*
X1184113Y126183D01*
X1183946Y126475D01*
X1183654Y126683D01*
X1183321Y126725D01*
X1182988Y126641D01*
X1182779Y126433D01*
X1182613Y126141D01*
X1182571Y125850D01*
X1182613Y125558D01*
X1182779Y125183D01*
X1181696Y125308D01*
Y126433D01*
G01X1185404Y120525D02*
X1185279Y120275D01*
X1185196Y119983D01*
Y119650D01*
X1185321Y119275D01*
X1185529Y118983D01*
X1185779Y118775D01*
X1186196Y118608D01*
X1186571Y118566D01*
X1186946Y118650D01*
X1187196Y118775D01*
X1187446Y119025D01*
X1187613Y119316D01*
X1187696Y119608D01*
Y119900D01*
X1187613Y120191D01*
X1187488Y120441D01*
X1187321Y120650D01*
G01X1187696Y122708D02*
X1185196D01*
X1185696Y122208D01*
G01X1187696D02*
Y123208D01*
G01Y126308D02*
X1185196D01*
X1186988Y124766D01*
Y126850D01*
G01X1209650Y155400D02*
X1209317Y155442D01*
X1209025Y155608D01*
X1208775Y155858D01*
X1208608Y156150D01*
X1208525Y156483D01*
Y156817D01*
X1208608Y157150D01*
X1208775Y157442D01*
X1209025Y157692D01*
X1209317Y157858D01*
X1209650Y157900D01*
X1209983Y157858D01*
X1210275Y157692D01*
X1210525Y157442D01*
X1210692Y157150D01*
X1210775Y156817D01*
Y156483D01*
X1210692Y156150D01*
X1210525Y155858D01*
X1210275Y155608D01*
X1209983Y155442D01*
X1209650Y155400D01*
G01X1211792D02*
Y157900D01*
X1213708Y155400D01*
Y157900D01*
G01X1209650Y150400D02*
X1209317Y150442D01*
X1209025Y150608D01*
X1208775Y150858D01*
X1208608Y151150D01*
X1208525Y151483D01*
Y151817D01*
X1208608Y152150D01*
X1208775Y152442D01*
X1209025Y152692D01*
X1209317Y152858D01*
X1209650Y152900D01*
X1209983Y152858D01*
X1210275Y152692D01*
X1210525Y152442D01*
X1210692Y152150D01*
X1210775Y151817D01*
Y151483D01*
X1210692Y151150D01*
X1210525Y150858D01*
X1210275Y150608D01*
X1209983Y150442D01*
X1209650Y150400D01*
G01X1211792D02*
Y152900D01*
X1213708Y150400D01*
Y152900D01*
G01X1199067Y162800D02*
X1198233D01*
Y159467D01*
X1199067D01*
G01X1200917Y162800D02*
Y160300D01*
X1202583D01*
G01X1205683D02*
X1204017D01*
Y162800D01*
X1205683D01*
G01X1205017Y161592D02*
X1204017D01*
G01X1207033Y160300D02*
Y162800D01*
X1207867D01*
X1208200Y162675D01*
X1208450Y162508D01*
X1208658Y162258D01*
X1208825Y161967D01*
X1208867Y161550D01*
X1208825Y161133D01*
X1208658Y160842D01*
X1208450Y160592D01*
X1208200Y160425D01*
X1207867Y160300D01*
X1207033D01*
G01X1211050D02*
Y162800D01*
X1210550Y162300D01*
G01Y160300D02*
X1211550D01*
G01X1213358Y162383D02*
X1213608Y162633D01*
X1213900Y162758D01*
X1214233Y162800D01*
X1214650Y162717D01*
X1214942Y162508D01*
X1215025Y162258D01*
X1214983Y162008D01*
X1214817Y161800D01*
X1213983Y161383D01*
X1213608Y161092D01*
X1213358Y160675D01*
X1213275Y160300D01*
X1215025D01*
G01X1216833Y159467D02*
X1217667D01*
Y162800D01*
X1216833D01*
G01X1209650Y145400D02*
X1209317Y145442D01*
X1209025Y145608D01*
X1208775Y145858D01*
X1208608Y146150D01*
X1208525Y146483D01*
Y146817D01*
X1208608Y147150D01*
X1208775Y147442D01*
X1209025Y147692D01*
X1209317Y147858D01*
X1209650Y147900D01*
X1209983Y147858D01*
X1210275Y147692D01*
X1210525Y147442D01*
X1210692Y147150D01*
X1210775Y146817D01*
Y146483D01*
X1210692Y146150D01*
X1210525Y145858D01*
X1210275Y145608D01*
X1209983Y145442D01*
X1209650Y145400D01*
G01X1211792D02*
Y147900D01*
X1213708Y145400D01*
Y147900D01*
G01X1183975Y155100D02*
X1185725Y157600D01*
G01X1183975D02*
X1185725Y155100D01*
G01X1187950D02*
Y157600D01*
X1187450Y157100D01*
G01Y155100D02*
X1188450D01*
G01X1190258Y156142D02*
X1190550Y156433D01*
X1190800Y156600D01*
X1191133Y156683D01*
X1191425Y156600D01*
X1191633Y156433D01*
X1191800Y156183D01*
X1191842Y155892D01*
X1191800Y155642D01*
X1191633Y155392D01*
X1191383Y155183D01*
X1191092Y155100D01*
X1190758Y155183D01*
X1190467Y155433D01*
X1190300Y155808D01*
X1190258Y156225D01*
X1190342Y156767D01*
X1190467Y157058D01*
X1190675Y157350D01*
X1190967Y157558D01*
X1191258Y157600D01*
X1191550Y157517D01*
X1191758Y157308D01*
G01X1183975Y150100D02*
X1185725Y152600D01*
G01X1183975D02*
X1185725Y150100D01*
G01X1187950D02*
X1188242Y150142D01*
X1188575Y150267D01*
X1188783Y150475D01*
X1188867Y150767D01*
X1188783Y151058D01*
X1188533Y151308D01*
X1188158Y151433D01*
X1187742D01*
X1187492Y151517D01*
X1187283Y151725D01*
X1187200Y152017D01*
X1187325Y152308D01*
X1187617Y152517D01*
X1187950Y152600D01*
X1188283Y152517D01*
X1188575Y152308D01*
X1188700Y152017D01*
X1188617Y151725D01*
X1188408Y151517D01*
X1188158Y151433D01*
X1187742D01*
X1187367Y151308D01*
X1187117Y151058D01*
X1187033Y150767D01*
X1187117Y150475D01*
X1187325Y150267D01*
X1187658Y150142D01*
X1187950Y150100D01*
G01X1183733Y167700D02*
Y165908D01*
X1183900Y165533D01*
X1184233Y165283D01*
X1184650Y165200D01*
X1185067Y165283D01*
X1185400Y165533D01*
X1185567Y165908D01*
Y167700D01*
G01X1187000Y164367D02*
Y166867D01*
G01Y166492D02*
X1187208Y166700D01*
X1187417Y166825D01*
X1187750Y166867D01*
X1188042Y166825D01*
X1188333Y166617D01*
X1188458Y166325D01*
X1188500Y166033D01*
X1188458Y165742D01*
X1188333Y165450D01*
X1188083Y165283D01*
X1187750Y165200D01*
X1187458Y165242D01*
X1187167Y165367D01*
X1187000Y165533D01*
G01X1190850Y165200D02*
Y167700D01*
G01X1193950Y166867D02*
Y165200D01*
G01Y167533D02*
X1193867Y167575D01*
Y167658D01*
X1193950Y167700D01*
X1194033Y167658D01*
Y167575D01*
X1193950Y167533D01*
G01X1196342Y165200D02*
Y166867D01*
G01Y166450D02*
X1196508Y166658D01*
X1196758Y166825D01*
X1197092Y166867D01*
X1197383Y166825D01*
X1197633Y166658D01*
X1197758Y166367D01*
Y165200D01*
G01X1199442D02*
Y167700D01*
G01X1200775Y166867D02*
X1199442Y165908D01*
G01X1199983Y166283D02*
X1200858Y165200D01*
G01X1205850Y167700D02*
X1206850D01*
G01X1206350D02*
Y165200D01*
G01X1205850D02*
X1206850D01*
G01X1208742D02*
Y166867D01*
G01Y166450D02*
X1208908Y166658D01*
X1209158Y166825D01*
X1209492Y166867D01*
X1209783Y166825D01*
X1210033Y166658D01*
X1210158Y166367D01*
Y165200D01*
G01X1213300Y167700D02*
Y165200D01*
G01Y165575D02*
X1213133Y165367D01*
X1212883Y165242D01*
X1212592Y165200D01*
X1212258Y165283D01*
X1212008Y165492D01*
X1211842Y165742D01*
X1211800Y166033D01*
X1211842Y166325D01*
X1212008Y166575D01*
X1212258Y166783D01*
X1212592Y166867D01*
X1212883Y166825D01*
X1213092Y166742D01*
X1213300Y166575D01*
G01X1215650Y166867D02*
Y165200D01*
G01Y167533D02*
X1215567Y167575D01*
Y167658D01*
X1215650Y167700D01*
X1215733Y167658D01*
Y167575D01*
X1215650Y167533D01*
G01X1219417Y166658D02*
X1219125Y166825D01*
X1218875Y166867D01*
X1218542Y166783D01*
X1218292Y166617D01*
X1218125Y166325D01*
X1218083Y166033D01*
X1218125Y165742D01*
X1218292Y165492D01*
X1218542Y165283D01*
X1218875Y165200D01*
X1219167Y165283D01*
X1219417Y165450D01*
G01X1222600Y165200D02*
Y166867D01*
G01Y166575D02*
X1222433Y166742D01*
X1222183Y166825D01*
X1221892Y166867D01*
X1221600Y166783D01*
X1221350Y166617D01*
X1221183Y166367D01*
X1221100Y166033D01*
X1221183Y165700D01*
X1221350Y165450D01*
X1221600Y165283D01*
X1221892Y165200D01*
X1222183Y165242D01*
X1222433Y165367D01*
X1222600Y165533D01*
G01X1224950Y167700D02*
Y165200D01*
G01X1224367Y166867D02*
X1225533D01*
G01X1228050D02*
Y165200D01*
G01Y167533D02*
X1227967Y167575D01*
Y167658D01*
X1228050Y167700D01*
X1228133Y167658D01*
Y167575D01*
X1228050Y167533D01*
G01X1231150Y165200D02*
X1230900Y165242D01*
X1230650Y165408D01*
X1230483Y165700D01*
X1230400Y166033D01*
X1230483Y166367D01*
X1230650Y166658D01*
X1230900Y166825D01*
X1231150Y166867D01*
X1231400Y166825D01*
X1231650Y166658D01*
X1231817Y166367D01*
X1231858Y166033D01*
X1231817Y165700D01*
X1231650Y165408D01*
X1231400Y165242D01*
X1231150Y165200D01*
G01X1233542D02*
Y166867D01*
G01Y166450D02*
X1233708Y166658D01*
X1233958Y166825D01*
X1234292Y166867D01*
X1234583Y166825D01*
X1234833Y166658D01*
X1234958Y166367D01*
Y165200D01*
G01X1237350Y165117D02*
X1237267Y165158D01*
Y165242D01*
X1237350Y165283D01*
X1237433Y165242D01*
Y165158D01*
X1237350Y165117D01*
G01Y166242D02*
X1237267Y166283D01*
Y166367D01*
X1237350Y166408D01*
X1237433Y166367D01*
Y166283D01*
X1237350Y166242D01*
G01X1183767Y160100D02*
Y162600D01*
X1184850Y160517D01*
X1185933Y162600D01*
Y160100D01*
G01X1187950D02*
X1187617Y160142D01*
X1187325Y160308D01*
X1187075Y160558D01*
X1186908Y160850D01*
X1186825Y161183D01*
Y161517D01*
X1186908Y161850D01*
X1187075Y162142D01*
X1187325Y162392D01*
X1187617Y162558D01*
X1187950Y162600D01*
X1188283Y162558D01*
X1188575Y162392D01*
X1188825Y162142D01*
X1188992Y161850D01*
X1189075Y161517D01*
Y161183D01*
X1188992Y160850D01*
X1188825Y160558D01*
X1188575Y160308D01*
X1188283Y160142D01*
X1187950Y160100D01*
G01X1190133D02*
Y162600D01*
X1190967D01*
X1191300Y162475D01*
X1191550Y162308D01*
X1191758Y162058D01*
X1191925Y161767D01*
X1191967Y161350D01*
X1191925Y160933D01*
X1191758Y160642D01*
X1191550Y160392D01*
X1191300Y160225D01*
X1190967Y160100D01*
X1190133D01*
G01X1194983D02*
X1193317D01*
Y162600D01*
X1194983D01*
G01X1194317Y161392D02*
X1193317D01*
G01X1183975Y145100D02*
X1185725Y147600D01*
G01X1183975D02*
X1185725Y145100D01*
G01X1188450D02*
Y147600D01*
X1186908Y145808D01*
X1188992D01*
G01X1201000Y143500D02*
X1204000D01*
G01X1207000D02*
X1229500D01*
G01X1211049Y203482D02*
X1210924Y203232D01*
X1210841Y202940D01*
Y202607D01*
X1210966Y202232D01*
X1211174Y201940D01*
X1211424Y201732D01*
X1211841Y201565D01*
X1212216Y201523D01*
X1212591Y201607D01*
X1212841Y201732D01*
X1213091Y201982D01*
X1213258Y202273D01*
X1213341Y202565D01*
Y202857D01*
X1213258Y203148D01*
X1213133Y203398D01*
X1212966Y203607D01*
G01X1213341Y206165D02*
X1210841D01*
X1212633Y204623D01*
Y206707D01*
G01X1212841Y207848D02*
X1213133Y208098D01*
X1213299Y208432D01*
X1213341Y208807D01*
X1213299Y209140D01*
X1213091Y209473D01*
X1212841Y209682D01*
X1212591Y209723D01*
X1212299Y209640D01*
X1212091Y209348D01*
X1212008Y209057D01*
Y208682D01*
G01Y209057D02*
X1211883Y209307D01*
X1211674Y209515D01*
X1211424Y209598D01*
X1211174Y209515D01*
X1210966Y209307D01*
X1210841Y208932D01*
X1210883Y208557D01*
X1211049Y208182D01*
G01X1213049Y211157D02*
X1213258Y211448D01*
X1213341Y211782D01*
X1213258Y212115D01*
X1213008Y212407D01*
X1212633Y212615D01*
X1212258Y212698D01*
X1211799D01*
X1211424Y212615D01*
X1211091Y212407D01*
X1210924Y212157D01*
X1210841Y211865D01*
X1210924Y211532D01*
X1211091Y211282D01*
X1211341Y211115D01*
X1211674Y211032D01*
X1211966Y211115D01*
X1212258Y211323D01*
X1212424Y211573D01*
X1212466Y211865D01*
X1212383Y212198D01*
X1212174Y212448D01*
X1211799Y212698D01*
G01X1201447Y203790D02*
X1201322Y203540D01*
X1201239Y203248D01*
Y202915D01*
X1201364Y202540D01*
X1201572Y202248D01*
X1201822Y202040D01*
X1202239Y201873D01*
X1202614Y201831D01*
X1202989Y201915D01*
X1203239Y202040D01*
X1203489Y202290D01*
X1203656Y202581D01*
X1203739Y202873D01*
Y203165D01*
X1203656Y203456D01*
X1203531Y203706D01*
X1203364Y203915D01*
G01X1203739Y206473D02*
X1201239D01*
X1203031Y204931D01*
Y207015D01*
G01X1203239Y208156D02*
X1203531Y208406D01*
X1203697Y208740D01*
X1203739Y209115D01*
X1203697Y209448D01*
X1203489Y209781D01*
X1203239Y209990D01*
X1202989Y210031D01*
X1202697Y209948D01*
X1202489Y209656D01*
X1202406Y209365D01*
Y208990D01*
G01Y209365D02*
X1202281Y209615D01*
X1202072Y209823D01*
X1201822Y209906D01*
X1201572Y209823D01*
X1201364Y209615D01*
X1201239Y209240D01*
X1201281Y208865D01*
X1201447Y208490D01*
G01X1203739Y212173D02*
X1201239D01*
X1201739Y211673D01*
G01X1203739D02*
Y212673D01*
G01X1192536Y204097D02*
X1192411Y203847D01*
X1192328Y203555D01*
Y203222D01*
X1192453Y202847D01*
X1192661Y202555D01*
X1192911Y202347D01*
X1193328Y202180D01*
X1193703Y202138D01*
X1194078Y202222D01*
X1194328Y202347D01*
X1194578Y202597D01*
X1194745Y202888D01*
X1194828Y203180D01*
Y203472D01*
X1194745Y203763D01*
X1194620Y204013D01*
X1194453Y204222D01*
G01X1194828Y206780D02*
X1192328D01*
X1194120Y205238D01*
Y207322D01*
G01X1192745Y208588D02*
X1192495Y208838D01*
X1192370Y209130D01*
X1192328Y209463D01*
X1192411Y209880D01*
X1192620Y210172D01*
X1192870Y210255D01*
X1193120Y210213D01*
X1193328Y210047D01*
X1193745Y209213D01*
X1194036Y208838D01*
X1194453Y208588D01*
X1194828Y208505D01*
Y210255D01*
G01Y212397D02*
X1194286Y212480D01*
X1193828Y212605D01*
X1193411Y212772D01*
X1192953Y212980D01*
X1192328Y213313D01*
Y211647D01*
G01X1184358Y203600D02*
X1184233Y203350D01*
X1184150Y203058D01*
Y202725D01*
X1184275Y202350D01*
X1184483Y202058D01*
X1184733Y201850D01*
X1185150Y201683D01*
X1185525Y201641D01*
X1185900Y201725D01*
X1186150Y201850D01*
X1186400Y202100D01*
X1186567Y202391D01*
X1186650Y202683D01*
Y202975D01*
X1186567Y203266D01*
X1186442Y203516D01*
X1186275Y203725D01*
G01X1186650Y206283D02*
X1184150D01*
X1185942Y204741D01*
Y206825D01*
G01X1184567Y208091D02*
X1184317Y208341D01*
X1184192Y208633D01*
X1184150Y208966D01*
X1184233Y209383D01*
X1184442Y209675D01*
X1184692Y209758D01*
X1184942Y209716D01*
X1185150Y209550D01*
X1185567Y208716D01*
X1185858Y208341D01*
X1186275Y208091D01*
X1186650Y208008D01*
Y209758D01*
G01X1185608Y211191D02*
X1185317Y211483D01*
X1185150Y211733D01*
X1185067Y212066D01*
X1185150Y212358D01*
X1185317Y212566D01*
X1185567Y212733D01*
X1185858Y212775D01*
X1186108Y212733D01*
X1186358Y212566D01*
X1186567Y212316D01*
X1186650Y212025D01*
X1186567Y211691D01*
X1186317Y211400D01*
X1185942Y211233D01*
X1185525Y211191D01*
X1184983Y211275D01*
X1184692Y211400D01*
X1184400Y211608D01*
X1184192Y211900D01*
X1184150Y212191D01*
X1184233Y212483D01*
X1184442Y212691D01*
G01X1206942Y283829D02*
X1206817Y283579D01*
X1206734Y283287D01*
Y282954D01*
X1206859Y282579D01*
X1207067Y282287D01*
X1207317Y282079D01*
X1207734Y281912D01*
X1208109Y281870D01*
X1208484Y281954D01*
X1208734Y282079D01*
X1208984Y282329D01*
X1209151Y282620D01*
X1209234Y282912D01*
Y283204D01*
X1209151Y283495D01*
X1209026Y283745D01*
X1208859Y283954D01*
G01X1208192Y285220D02*
X1207901Y285512D01*
X1207734Y285762D01*
X1207651Y286095D01*
X1207734Y286387D01*
X1207901Y286595D01*
X1208151Y286762D01*
X1208442Y286804D01*
X1208692Y286762D01*
X1208942Y286595D01*
X1209151Y286345D01*
X1209234Y286054D01*
X1209151Y285720D01*
X1208901Y285429D01*
X1208526Y285262D01*
X1208109Y285220D01*
X1207567Y285304D01*
X1207276Y285429D01*
X1206984Y285637D01*
X1206776Y285929D01*
X1206734Y286220D01*
X1206817Y286512D01*
X1207026Y286720D01*
G01X1208734Y288195D02*
X1209026Y288445D01*
X1209192Y288779D01*
X1209234Y289154D01*
X1209192Y289487D01*
X1208984Y289820D01*
X1208734Y290029D01*
X1208484Y290070D01*
X1208192Y289987D01*
X1207984Y289695D01*
X1207901Y289404D01*
Y289029D01*
G01Y289404D02*
X1207776Y289654D01*
X1207567Y289862D01*
X1207317Y289945D01*
X1207067Y289862D01*
X1206859Y289654D01*
X1206734Y289279D01*
X1206776Y288904D01*
X1206942Y288529D01*
G01X1206734Y292212D02*
X1206817Y291879D01*
X1207026Y291629D01*
X1207276Y291462D01*
X1207609Y291337D01*
X1207984Y291295D01*
X1208359Y291337D01*
X1208692Y291462D01*
X1208942Y291629D01*
X1209151Y291879D01*
X1209234Y292212D01*
X1209151Y292545D01*
X1208942Y292795D01*
X1208692Y292962D01*
X1208359Y293087D01*
X1207984Y293129D01*
X1207609Y293087D01*
X1207276Y292962D01*
X1207026Y292795D01*
X1206817Y292545D01*
X1206734Y292212D01*
G01X1192731Y283599D02*
X1192606Y283349D01*
X1192523Y283057D01*
Y282724D01*
X1192648Y282349D01*
X1192856Y282057D01*
X1193106Y281849D01*
X1193523Y281682D01*
X1193898Y281640D01*
X1194273Y281724D01*
X1194523Y281849D01*
X1194773Y282099D01*
X1194940Y282390D01*
X1195023Y282682D01*
Y282974D01*
X1194940Y283265D01*
X1194815Y283515D01*
X1194648Y283724D01*
G01X1195023Y286282D02*
X1192523D01*
X1194315Y284740D01*
Y286824D01*
G01X1194648Y287965D02*
X1194856Y288215D01*
X1194981Y288507D01*
X1195023Y288882D01*
X1194940Y289257D01*
X1194773Y289549D01*
X1194481Y289757D01*
X1194148Y289799D01*
X1193815Y289715D01*
X1193606Y289507D01*
X1193440Y289215D01*
X1193398Y288924D01*
X1193440Y288632D01*
X1193606Y288257D01*
X1192523Y288382D01*
Y289507D01*
G01X1195023Y291982D02*
X1194981Y292274D01*
X1194856Y292607D01*
X1194648Y292815D01*
X1194356Y292899D01*
X1194065Y292815D01*
X1193815Y292565D01*
X1193690Y292190D01*
Y291774D01*
X1193606Y291524D01*
X1193398Y291315D01*
X1193106Y291232D01*
X1192815Y291357D01*
X1192606Y291649D01*
X1192523Y291982D01*
X1192606Y292315D01*
X1192815Y292607D01*
X1193106Y292732D01*
X1193398Y292649D01*
X1193606Y292440D01*
X1193690Y292190D01*
Y291774D01*
X1193815Y291399D01*
X1194065Y291149D01*
X1194356Y291065D01*
X1194648Y291149D01*
X1194856Y291357D01*
X1194981Y291690D01*
X1195023Y291982D01*
G01X1200028Y283983D02*
X1199903Y283733D01*
X1199820Y283441D01*
Y283108D01*
X1199945Y282733D01*
X1200153Y282441D01*
X1200403Y282233D01*
X1200820Y282066D01*
X1201195Y282024D01*
X1201570Y282108D01*
X1201820Y282233D01*
X1202070Y282483D01*
X1202237Y282774D01*
X1202320Y283066D01*
Y283358D01*
X1202237Y283649D01*
X1202112Y283899D01*
X1201945Y284108D01*
G01X1202320Y286666D02*
X1199820D01*
X1201612Y285124D01*
Y287208D01*
G01X1201945Y288349D02*
X1202153Y288599D01*
X1202278Y288891D01*
X1202320Y289266D01*
X1202237Y289641D01*
X1202070Y289933D01*
X1201778Y290141D01*
X1201445Y290183D01*
X1201112Y290099D01*
X1200903Y289891D01*
X1200737Y289599D01*
X1200695Y289308D01*
X1200737Y289016D01*
X1200903Y288641D01*
X1199820Y288766D01*
Y289891D01*
G01X1202028Y291658D02*
X1202237Y291949D01*
X1202320Y292283D01*
X1202237Y292616D01*
X1201987Y292908D01*
X1201612Y293116D01*
X1201237Y293199D01*
X1200778D01*
X1200403Y293116D01*
X1200070Y292908D01*
X1199903Y292658D01*
X1199820Y292366D01*
X1199903Y292033D01*
X1200070Y291783D01*
X1200320Y291616D01*
X1200653Y291533D01*
X1200945Y291616D01*
X1201237Y291824D01*
X1201403Y292074D01*
X1201445Y292366D01*
X1201362Y292699D01*
X1201153Y292949D01*
X1200778Y293199D01*
G01X1183932Y284213D02*
X1183807Y283963D01*
X1183724Y283671D01*
Y283338D01*
X1183849Y282963D01*
X1184057Y282671D01*
X1184307Y282463D01*
X1184724Y282296D01*
X1185099Y282254D01*
X1185474Y282338D01*
X1185724Y282463D01*
X1185974Y282713D01*
X1186141Y283004D01*
X1186224Y283296D01*
Y283588D01*
X1186141Y283879D01*
X1186016Y284129D01*
X1185849Y284338D01*
G01X1186224Y286896D02*
X1183724D01*
X1185516Y285354D01*
Y287438D01*
G01X1185849Y288579D02*
X1186057Y288829D01*
X1186182Y289121D01*
X1186224Y289496D01*
X1186141Y289871D01*
X1185974Y290163D01*
X1185682Y290371D01*
X1185349Y290413D01*
X1185016Y290329D01*
X1184807Y290121D01*
X1184641Y289829D01*
X1184599Y289538D01*
X1184641Y289246D01*
X1184807Y288871D01*
X1183724Y288996D01*
Y290121D01*
G01X1185182Y291804D02*
X1184891Y292096D01*
X1184724Y292346D01*
X1184641Y292679D01*
X1184724Y292971D01*
X1184891Y293179D01*
X1185141Y293346D01*
X1185432Y293388D01*
X1185682Y293346D01*
X1185932Y293179D01*
X1186141Y292929D01*
X1186224Y292638D01*
X1186141Y292304D01*
X1185891Y292013D01*
X1185516Y291846D01*
X1185099Y291804D01*
X1184557Y291888D01*
X1184266Y292013D01*
X1183974Y292221D01*
X1183766Y292513D01*
X1183724Y292804D01*
X1183807Y293096D01*
X1184016Y293304D01*
G01X1193726Y370900D02*
Y373400D01*
X1194767D01*
X1195101Y373275D01*
X1195309Y373108D01*
X1195392Y372775D01*
X1195309Y372442D01*
X1195059Y372233D01*
X1194767Y372108D01*
X1193726D01*
G01X1194767D02*
X1195392Y370900D01*
G01X1196867Y372983D02*
X1197117Y373233D01*
X1197409Y373358D01*
X1197742Y373400D01*
X1198159Y373317D01*
X1198451Y373108D01*
X1198534Y372858D01*
X1198492Y372608D01*
X1198326Y372400D01*
X1197492Y371983D01*
X1197117Y371692D01*
X1196867Y371275D01*
X1196784Y370900D01*
X1198534D01*
G01X1200051Y371192D02*
X1200342Y370983D01*
X1200676Y370900D01*
X1201009Y370983D01*
X1201301Y371233D01*
X1201509Y371608D01*
X1201592Y371983D01*
Y372442D01*
X1201509Y372817D01*
X1201301Y373150D01*
X1201051Y373317D01*
X1200759Y373400D01*
X1200426Y373317D01*
X1200176Y373150D01*
X1200009Y372900D01*
X1199926Y372567D01*
X1200009Y372275D01*
X1200217Y371983D01*
X1200467Y371817D01*
X1200759Y371775D01*
X1201092Y371858D01*
X1201342Y372067D01*
X1201592Y372442D01*
G01X1203859Y370900D02*
Y373400D01*
X1203359Y372900D01*
G01Y370900D02*
X1204359D01*
G01X1206167Y371942D02*
X1206459Y372233D01*
X1206709Y372400D01*
X1207042Y372483D01*
X1207334Y372400D01*
X1207542Y372233D01*
X1207709Y371983D01*
X1207751Y371692D01*
X1207709Y371442D01*
X1207542Y371192D01*
X1207292Y370983D01*
X1207001Y370900D01*
X1206667Y370983D01*
X1206376Y371233D01*
X1206209Y371608D01*
X1206167Y372025D01*
X1206251Y372567D01*
X1206376Y372858D01*
X1206584Y373150D01*
X1206876Y373358D01*
X1207167Y373400D01*
X1207459Y373317D01*
X1207667Y373108D01*
G01X1210167Y366900D02*
Y369400D01*
X1211208D01*
X1211542Y369275D01*
X1211750Y369108D01*
X1211833Y368775D01*
X1211750Y368442D01*
X1211500Y368233D01*
X1211208Y368108D01*
X1210167D01*
G01X1211208D02*
X1211833Y366900D01*
G01X1213308Y368983D02*
X1213558Y369233D01*
X1213850Y369358D01*
X1214183Y369400D01*
X1214600Y369317D01*
X1214892Y369108D01*
X1214975Y368858D01*
X1214933Y368608D01*
X1214767Y368400D01*
X1213933Y367983D01*
X1213558Y367692D01*
X1213308Y367275D01*
X1213225Y366900D01*
X1214975D01*
G01X1216492Y367192D02*
X1216783Y366983D01*
X1217117Y366900D01*
X1217450Y366983D01*
X1217742Y367233D01*
X1217950Y367608D01*
X1218033Y367983D01*
Y368442D01*
X1217950Y368817D01*
X1217742Y369150D01*
X1217492Y369317D01*
X1217200Y369400D01*
X1216867Y369317D01*
X1216617Y369150D01*
X1216450Y368900D01*
X1216367Y368567D01*
X1216450Y368275D01*
X1216658Y367983D01*
X1216908Y367817D01*
X1217200Y367775D01*
X1217533Y367858D01*
X1217783Y368067D01*
X1218033Y368442D01*
G01X1220300Y366900D02*
Y369400D01*
X1219800Y368900D01*
G01Y366900D02*
X1220800D01*
G01X1222483Y367275D02*
X1222733Y367067D01*
X1223025Y366942D01*
X1223400Y366900D01*
X1223775Y366983D01*
X1224067Y367150D01*
X1224275Y367442D01*
X1224317Y367775D01*
X1224233Y368108D01*
X1224025Y368317D01*
X1223733Y368483D01*
X1223442Y368525D01*
X1223150Y368483D01*
X1222775Y368317D01*
X1222900Y369400D01*
X1224025D01*
G01X1193726Y365900D02*
Y368400D01*
X1194767D01*
X1195101Y368275D01*
X1195309Y368108D01*
X1195392Y367775D01*
X1195309Y367442D01*
X1195059Y367233D01*
X1194767Y367108D01*
X1193726D01*
G01X1194767D02*
X1195392Y365900D01*
G01X1196867Y367983D02*
X1197117Y368233D01*
X1197409Y368358D01*
X1197742Y368400D01*
X1198159Y368317D01*
X1198451Y368108D01*
X1198534Y367858D01*
X1198492Y367608D01*
X1198326Y367400D01*
X1197492Y366983D01*
X1197117Y366692D01*
X1196867Y366275D01*
X1196784Y365900D01*
X1198534D01*
G01X1200051Y366192D02*
X1200342Y365983D01*
X1200676Y365900D01*
X1201009Y365983D01*
X1201301Y366233D01*
X1201509Y366608D01*
X1201592Y366983D01*
Y367442D01*
X1201509Y367817D01*
X1201301Y368150D01*
X1201051Y368317D01*
X1200759Y368400D01*
X1200426Y368317D01*
X1200176Y368150D01*
X1200009Y367900D01*
X1199926Y367567D01*
X1200009Y367275D01*
X1200217Y366983D01*
X1200467Y366817D01*
X1200759Y366775D01*
X1201092Y366858D01*
X1201342Y367067D01*
X1201592Y367442D01*
G01X1203859Y368400D02*
X1203526Y368317D01*
X1203276Y368108D01*
X1203109Y367858D01*
X1202984Y367525D01*
X1202942Y367150D01*
X1202984Y366775D01*
X1203109Y366442D01*
X1203276Y366192D01*
X1203526Y365983D01*
X1203859Y365900D01*
X1204192Y365983D01*
X1204442Y366192D01*
X1204609Y366442D01*
X1204734Y366775D01*
X1204776Y367150D01*
X1204734Y367525D01*
X1204609Y367858D01*
X1204442Y368108D01*
X1204192Y368317D01*
X1203859Y368400D01*
G01X1206167Y366942D02*
X1206459Y367233D01*
X1206709Y367400D01*
X1207042Y367483D01*
X1207334Y367400D01*
X1207542Y367233D01*
X1207709Y366983D01*
X1207751Y366692D01*
X1207709Y366442D01*
X1207542Y366192D01*
X1207292Y365983D01*
X1207001Y365900D01*
X1206667Y365983D01*
X1206376Y366233D01*
X1206209Y366608D01*
X1206167Y367025D01*
X1206251Y367567D01*
X1206376Y367858D01*
X1206584Y368150D01*
X1206876Y368358D01*
X1207167Y368400D01*
X1207459Y368317D01*
X1207667Y368108D01*
G01X1210167Y371400D02*
Y373900D01*
X1211208D01*
X1211542Y373775D01*
X1211750Y373608D01*
X1211833Y373275D01*
X1211750Y372942D01*
X1211500Y372733D01*
X1211208Y372608D01*
X1210167D01*
G01X1211208D02*
X1211833Y371400D01*
G01X1213308Y373483D02*
X1213558Y373733D01*
X1213850Y373858D01*
X1214183Y373900D01*
X1214600Y373817D01*
X1214892Y373608D01*
X1214975Y373358D01*
X1214933Y373108D01*
X1214767Y372900D01*
X1213933Y372483D01*
X1213558Y372192D01*
X1213308Y371775D01*
X1213225Y371400D01*
X1214975D01*
G01X1216492Y371692D02*
X1216783Y371483D01*
X1217117Y371400D01*
X1217450Y371483D01*
X1217742Y371733D01*
X1217950Y372108D01*
X1218033Y372483D01*
Y372942D01*
X1217950Y373317D01*
X1217742Y373650D01*
X1217492Y373817D01*
X1217200Y373900D01*
X1216867Y373817D01*
X1216617Y373650D01*
X1216450Y373400D01*
X1216367Y373067D01*
X1216450Y372775D01*
X1216658Y372483D01*
X1216908Y372317D01*
X1217200Y372275D01*
X1217533Y372358D01*
X1217783Y372567D01*
X1218033Y372942D01*
G01X1220300Y373900D02*
X1219967Y373817D01*
X1219717Y373608D01*
X1219550Y373358D01*
X1219425Y373025D01*
X1219383Y372650D01*
X1219425Y372275D01*
X1219550Y371942D01*
X1219717Y371692D01*
X1219967Y371483D01*
X1220300Y371400D01*
X1220633Y371483D01*
X1220883Y371692D01*
X1221050Y371942D01*
X1221175Y372275D01*
X1221217Y372650D01*
X1221175Y373025D01*
X1221050Y373358D01*
X1220883Y373608D01*
X1220633Y373817D01*
X1220300Y373900D01*
G01X1222483Y371775D02*
X1222733Y371567D01*
X1223025Y371442D01*
X1223400Y371400D01*
X1223775Y371483D01*
X1224067Y371650D01*
X1224275Y371942D01*
X1224317Y372275D01*
X1224233Y372608D01*
X1224025Y372817D01*
X1223733Y372983D01*
X1223442Y373025D01*
X1223150Y372983D01*
X1222775Y372817D01*
X1222900Y373900D01*
X1224025D01*
G01X1191009Y365959D02*
X1188509D01*
Y367000D01*
X1188634Y367334D01*
X1188801Y367542D01*
X1189134Y367625D01*
X1189467Y367542D01*
X1189676Y367292D01*
X1189801Y367000D01*
Y365959D01*
G01Y367000D02*
X1191009Y367625D01*
G01X1188926Y369100D02*
X1188676Y369350D01*
X1188551Y369642D01*
X1188509Y369975D01*
X1188592Y370392D01*
X1188801Y370684D01*
X1189051Y370767D01*
X1189301Y370725D01*
X1189509Y370559D01*
X1189926Y369725D01*
X1190217Y369350D01*
X1190634Y369100D01*
X1191009Y369017D01*
Y370767D01*
G01Y372992D02*
X1188509D01*
X1189009Y372492D01*
G01X1191009D02*
Y373492D01*
G01X1189967Y375300D02*
X1189676Y375592D01*
X1189509Y375842D01*
X1189426Y376175D01*
X1189509Y376467D01*
X1189676Y376675D01*
X1189926Y376842D01*
X1190217Y376884D01*
X1190467Y376842D01*
X1190717Y376675D01*
X1190926Y376425D01*
X1191009Y376134D01*
X1190926Y375800D01*
X1190676Y375509D01*
X1190301Y375342D01*
X1189884Y375300D01*
X1189342Y375384D01*
X1189051Y375509D01*
X1188759Y375717D01*
X1188551Y376009D01*
X1188509Y376300D01*
X1188592Y376592D01*
X1188801Y376800D01*
G01X1195056Y375970D02*
Y378470D01*
X1196097D01*
X1196431Y378345D01*
X1196639Y378178D01*
X1196722Y377845D01*
X1196639Y377512D01*
X1196389Y377303D01*
X1196097Y377178D01*
X1195056D01*
G01X1196097D02*
X1196722Y375970D01*
G01X1198197Y378053D02*
X1198447Y378303D01*
X1198739Y378428D01*
X1199072Y378470D01*
X1199489Y378387D01*
X1199781Y378178D01*
X1199864Y377928D01*
X1199822Y377678D01*
X1199656Y377470D01*
X1198822Y377053D01*
X1198447Y376762D01*
X1198197Y376345D01*
X1198114Y375970D01*
X1199864D01*
G01X1202089D02*
Y378470D01*
X1201589Y377970D01*
G01Y375970D02*
X1202589D01*
G01X1205106D02*
X1205189Y376512D01*
X1205314Y376970D01*
X1205481Y377387D01*
X1205689Y377845D01*
X1206022Y378470D01*
X1204356D01*
G01X1209942Y375577D02*
Y378077D01*
X1210983D01*
X1211317Y377952D01*
X1211525Y377785D01*
X1211608Y377452D01*
X1211525Y377119D01*
X1211275Y376910D01*
X1210983Y376785D01*
X1209942D01*
G01X1210983D02*
X1211608Y375577D01*
G01X1213083Y377660D02*
X1213333Y377910D01*
X1213625Y378035D01*
X1213958Y378077D01*
X1214375Y377994D01*
X1214667Y377785D01*
X1214750Y377535D01*
X1214708Y377285D01*
X1214542Y377077D01*
X1213708Y376660D01*
X1213333Y376369D01*
X1213083Y375952D01*
X1213000Y375577D01*
X1214750D01*
G01X1216892D02*
X1216975Y376119D01*
X1217100Y376577D01*
X1217267Y376994D01*
X1217475Y377452D01*
X1217808Y378077D01*
X1216142D01*
G01X1220075Y375577D02*
X1220367Y375619D01*
X1220700Y375744D01*
X1220908Y375952D01*
X1220992Y376244D01*
X1220908Y376535D01*
X1220658Y376785D01*
X1220283Y376910D01*
X1219867D01*
X1219617Y376994D01*
X1219408Y377202D01*
X1219325Y377494D01*
X1219450Y377785D01*
X1219742Y377994D01*
X1220075Y378077D01*
X1220408Y377994D01*
X1220700Y377785D01*
X1220825Y377494D01*
X1220742Y377202D01*
X1220533Y376994D01*
X1220283Y376910D01*
X1219867D01*
X1219492Y376785D01*
X1219242Y376535D01*
X1219158Y376244D01*
X1219242Y375952D01*
X1219450Y375744D01*
X1219783Y375619D01*
X1220075Y375577D01*
G01X1178534Y384883D02*
X1180326D01*
X1180701Y385050D01*
X1180951Y385383D01*
X1181034Y385800D01*
X1180951Y386217D01*
X1180701Y386550D01*
X1180326Y386717D01*
X1178534D01*
G01X1181034Y388817D02*
X1180492Y388900D01*
X1180034Y389025D01*
X1179617Y389192D01*
X1179159Y389400D01*
X1178534Y389733D01*
Y388067D01*
G01X1180742Y391292D02*
X1180951Y391583D01*
X1181034Y391917D01*
X1180951Y392250D01*
X1180701Y392542D01*
X1180326Y392750D01*
X1179951Y392833D01*
X1179492D01*
X1179117Y392750D01*
X1178784Y392542D01*
X1178617Y392292D01*
X1178534Y392000D01*
X1178617Y391667D01*
X1178784Y391417D01*
X1179034Y391250D01*
X1179367Y391167D01*
X1179659Y391250D01*
X1179951Y391458D01*
X1180117Y391708D01*
X1180159Y392000D01*
X1180076Y392333D01*
X1179867Y392583D01*
X1179492Y392833D01*
G01X1210287Y389840D02*
Y392340D01*
X1211328D01*
X1211662Y392215D01*
X1211870Y392048D01*
X1211953Y391715D01*
X1211870Y391382D01*
X1211620Y391173D01*
X1211328Y391048D01*
X1210287D01*
G01X1211328D02*
X1211953Y389840D01*
G01X1213428Y391923D02*
X1213678Y392173D01*
X1213970Y392298D01*
X1214303Y392340D01*
X1214720Y392257D01*
X1215012Y392048D01*
X1215095Y391798D01*
X1215053Y391548D01*
X1214887Y391340D01*
X1214053Y390923D01*
X1213678Y390632D01*
X1213428Y390215D01*
X1213345Y389840D01*
X1215095D01*
G01X1216612Y390132D02*
X1216903Y389923D01*
X1217237Y389840D01*
X1217570Y389923D01*
X1217862Y390173D01*
X1218070Y390548D01*
X1218153Y390923D01*
Y391382D01*
X1218070Y391757D01*
X1217862Y392090D01*
X1217612Y392257D01*
X1217320Y392340D01*
X1216987Y392257D01*
X1216737Y392090D01*
X1216570Y391840D01*
X1216487Y391507D01*
X1216570Y391215D01*
X1216778Y390923D01*
X1217028Y390757D01*
X1217320Y390715D01*
X1217653Y390798D01*
X1217903Y391007D01*
X1218153Y391382D01*
G01X1220420Y389840D02*
Y392340D01*
X1219920Y391840D01*
G01Y389840D02*
X1220920D01*
G01X1222728Y391923D02*
X1222978Y392173D01*
X1223270Y392298D01*
X1223603Y392340D01*
X1224020Y392257D01*
X1224312Y392048D01*
X1224395Y391798D01*
X1224353Y391548D01*
X1224187Y391340D01*
X1223353Y390923D01*
X1222978Y390632D01*
X1222728Y390215D01*
X1222645Y389840D01*
X1224395D01*
G01X1194236Y384350D02*
Y386850D01*
X1195277D01*
X1195611Y386725D01*
X1195819Y386558D01*
X1195902Y386225D01*
X1195819Y385892D01*
X1195569Y385683D01*
X1195277Y385558D01*
X1194236D01*
G01X1195277D02*
X1195902Y384350D01*
G01X1197377Y386433D02*
X1197627Y386683D01*
X1197919Y386808D01*
X1198252Y386850D01*
X1198669Y386767D01*
X1198961Y386558D01*
X1199044Y386308D01*
X1199002Y386058D01*
X1198836Y385850D01*
X1198002Y385433D01*
X1197627Y385142D01*
X1197377Y384725D01*
X1197294Y384350D01*
X1199044D01*
G01X1200561Y384642D02*
X1200852Y384433D01*
X1201186Y384350D01*
X1201519Y384433D01*
X1201811Y384683D01*
X1202019Y385058D01*
X1202102Y385433D01*
Y385892D01*
X1202019Y386267D01*
X1201811Y386600D01*
X1201561Y386767D01*
X1201269Y386850D01*
X1200936Y386767D01*
X1200686Y386600D01*
X1200519Y386350D01*
X1200436Y386017D01*
X1200519Y385725D01*
X1200727Y385433D01*
X1200977Y385267D01*
X1201269Y385225D01*
X1201602Y385308D01*
X1201852Y385517D01*
X1202102Y385892D01*
G01X1204369Y384350D02*
Y386850D01*
X1203869Y386350D01*
G01Y384350D02*
X1204869D01*
G01X1207469D02*
Y386850D01*
X1206969Y386350D01*
G01Y384350D02*
X1207969D01*
G01X1194791Y398454D02*
Y400954D01*
X1195832D01*
X1196166Y400829D01*
X1196374Y400662D01*
X1196457Y400329D01*
X1196374Y399996D01*
X1196124Y399787D01*
X1195832Y399662D01*
X1194791D01*
G01X1195832D02*
X1196457Y398454D01*
G01X1197932Y400537D02*
X1198182Y400787D01*
X1198474Y400912D01*
X1198807Y400954D01*
X1199224Y400871D01*
X1199516Y400662D01*
X1199599Y400412D01*
X1199557Y400162D01*
X1199391Y399954D01*
X1198557Y399537D01*
X1198182Y399246D01*
X1197932Y398829D01*
X1197849Y398454D01*
X1199599D01*
G01X1201116Y398746D02*
X1201407Y398537D01*
X1201741Y398454D01*
X1202074Y398537D01*
X1202366Y398787D01*
X1202574Y399162D01*
X1202657Y399537D01*
Y399996D01*
X1202574Y400371D01*
X1202366Y400704D01*
X1202116Y400871D01*
X1201824Y400954D01*
X1201491Y400871D01*
X1201241Y400704D01*
X1201074Y400454D01*
X1200991Y400121D01*
X1201074Y399829D01*
X1201282Y399537D01*
X1201532Y399371D01*
X1201824Y399329D01*
X1202157Y399412D01*
X1202407Y399621D01*
X1202657Y399996D01*
G01X1204924Y398454D02*
Y400954D01*
X1204424Y400454D01*
G01Y398454D02*
X1205424D01*
G01X1208024Y400954D02*
X1207691Y400871D01*
X1207441Y400662D01*
X1207274Y400412D01*
X1207149Y400079D01*
X1207107Y399704D01*
X1207149Y399329D01*
X1207274Y398996D01*
X1207441Y398746D01*
X1207691Y398537D01*
X1208024Y398454D01*
X1208357Y398537D01*
X1208607Y398746D01*
X1208774Y398996D01*
X1208899Y399329D01*
X1208941Y399704D01*
X1208899Y400079D01*
X1208774Y400412D01*
X1208607Y400662D01*
X1208357Y400871D01*
X1208024Y400954D01*
G01X1210671Y394783D02*
Y397283D01*
X1211712D01*
X1212046Y397158D01*
X1212254Y396991D01*
X1212337Y396658D01*
X1212254Y396325D01*
X1212004Y396116D01*
X1211712Y395991D01*
X1210671D01*
G01X1211712D02*
X1212337Y394783D01*
G01X1213812Y396866D02*
X1214062Y397116D01*
X1214354Y397241D01*
X1214687Y397283D01*
X1215104Y397200D01*
X1215396Y396991D01*
X1215479Y396741D01*
X1215437Y396491D01*
X1215271Y396283D01*
X1214437Y395866D01*
X1214062Y395575D01*
X1213812Y395158D01*
X1213729Y394783D01*
X1215479D01*
G01X1216996Y395075D02*
X1217287Y394866D01*
X1217621Y394783D01*
X1217954Y394866D01*
X1218246Y395116D01*
X1218454Y395491D01*
X1218537Y395866D01*
Y396325D01*
X1218454Y396700D01*
X1218246Y397033D01*
X1217996Y397200D01*
X1217704Y397283D01*
X1217371Y397200D01*
X1217121Y397033D01*
X1216954Y396783D01*
X1216871Y396450D01*
X1216954Y396158D01*
X1217162Y395866D01*
X1217412Y395700D01*
X1217704Y395658D01*
X1218037Y395741D01*
X1218287Y395950D01*
X1218537Y396325D01*
G01X1220804Y397283D02*
X1220471Y397200D01*
X1220221Y396991D01*
X1220054Y396741D01*
X1219929Y396408D01*
X1219887Y396033D01*
X1219929Y395658D01*
X1220054Y395325D01*
X1220221Y395075D01*
X1220471Y394866D01*
X1220804Y394783D01*
X1221137Y394866D01*
X1221387Y395075D01*
X1221554Y395325D01*
X1221679Y395658D01*
X1221721Y396033D01*
X1221679Y396408D01*
X1221554Y396741D01*
X1221387Y396991D01*
X1221137Y397200D01*
X1220804Y397283D01*
G01X1223196Y395075D02*
X1223487Y394866D01*
X1223821Y394783D01*
X1224154Y394866D01*
X1224446Y395116D01*
X1224654Y395491D01*
X1224737Y395866D01*
Y396325D01*
X1224654Y396700D01*
X1224446Y397033D01*
X1224196Y397200D01*
X1223904Y397283D01*
X1223571Y397200D01*
X1223321Y397033D01*
X1223154Y396783D01*
X1223071Y396450D01*
X1223154Y396158D01*
X1223362Y395866D01*
X1223612Y395700D01*
X1223904Y395658D01*
X1224237Y395741D01*
X1224487Y395950D01*
X1224737Y396325D01*
G01X1210287Y385340D02*
Y387840D01*
X1211328D01*
X1211662Y387715D01*
X1211870Y387548D01*
X1211953Y387215D01*
X1211870Y386882D01*
X1211620Y386673D01*
X1211328Y386548D01*
X1210287D01*
G01X1211328D02*
X1211953Y385340D01*
G01X1213428Y387423D02*
X1213678Y387673D01*
X1213970Y387798D01*
X1214303Y387840D01*
X1214720Y387757D01*
X1215012Y387548D01*
X1215095Y387298D01*
X1215053Y387048D01*
X1214887Y386840D01*
X1214053Y386423D01*
X1213678Y386132D01*
X1213428Y385715D01*
X1213345Y385340D01*
X1215095D01*
G01X1216612Y385632D02*
X1216903Y385423D01*
X1217237Y385340D01*
X1217570Y385423D01*
X1217862Y385673D01*
X1218070Y386048D01*
X1218153Y386423D01*
Y386882D01*
X1218070Y387257D01*
X1217862Y387590D01*
X1217612Y387757D01*
X1217320Y387840D01*
X1216987Y387757D01*
X1216737Y387590D01*
X1216570Y387340D01*
X1216487Y387007D01*
X1216570Y386715D01*
X1216778Y386423D01*
X1217028Y386257D01*
X1217320Y386215D01*
X1217653Y386298D01*
X1217903Y386507D01*
X1218153Y386882D01*
G01X1220420Y387840D02*
X1220087Y387757D01*
X1219837Y387548D01*
X1219670Y387298D01*
X1219545Y386965D01*
X1219503Y386590D01*
X1219545Y386215D01*
X1219670Y385882D01*
X1219837Y385632D01*
X1220087Y385423D01*
X1220420Y385340D01*
X1220753Y385423D01*
X1221003Y385632D01*
X1221170Y385882D01*
X1221295Y386215D01*
X1221337Y386590D01*
X1221295Y386965D01*
X1221170Y387298D01*
X1221003Y387548D01*
X1220753Y387757D01*
X1220420Y387840D01*
G01X1224020Y385340D02*
Y387840D01*
X1222478Y386048D01*
X1224562D01*
G01X1194236Y388850D02*
Y391350D01*
X1195277D01*
X1195611Y391225D01*
X1195819Y391058D01*
X1195902Y390725D01*
X1195819Y390392D01*
X1195569Y390183D01*
X1195277Y390058D01*
X1194236D01*
G01X1195277D02*
X1195902Y388850D01*
G01X1197377Y390933D02*
X1197627Y391183D01*
X1197919Y391308D01*
X1198252Y391350D01*
X1198669Y391267D01*
X1198961Y391058D01*
X1199044Y390808D01*
X1199002Y390558D01*
X1198836Y390350D01*
X1198002Y389933D01*
X1197627Y389642D01*
X1197377Y389225D01*
X1197294Y388850D01*
X1199044D01*
G01X1200561Y389142D02*
X1200852Y388933D01*
X1201186Y388850D01*
X1201519Y388933D01*
X1201811Y389183D01*
X1202019Y389558D01*
X1202102Y389933D01*
Y390392D01*
X1202019Y390767D01*
X1201811Y391100D01*
X1201561Y391267D01*
X1201269Y391350D01*
X1200936Y391267D01*
X1200686Y391100D01*
X1200519Y390850D01*
X1200436Y390517D01*
X1200519Y390225D01*
X1200727Y389933D01*
X1200977Y389767D01*
X1201269Y389725D01*
X1201602Y389808D01*
X1201852Y390017D01*
X1202102Y390392D01*
G01X1204369Y391350D02*
X1204036Y391267D01*
X1203786Y391058D01*
X1203619Y390808D01*
X1203494Y390475D01*
X1203452Y390100D01*
X1203494Y389725D01*
X1203619Y389392D01*
X1203786Y389142D01*
X1204036Y388933D01*
X1204369Y388850D01*
X1204702Y388933D01*
X1204952Y389142D01*
X1205119Y389392D01*
X1205244Y389725D01*
X1205286Y390100D01*
X1205244Y390475D01*
X1205119Y390808D01*
X1204952Y391058D01*
X1204702Y391267D01*
X1204369Y391350D01*
G01X1206552Y389350D02*
X1206802Y389058D01*
X1207136Y388892D01*
X1207511Y388850D01*
X1207844Y388892D01*
X1208177Y389100D01*
X1208386Y389350D01*
X1208427Y389600D01*
X1208344Y389892D01*
X1208052Y390100D01*
X1207761Y390183D01*
X1207386D01*
G01X1207761D02*
X1208011Y390308D01*
X1208219Y390517D01*
X1208302Y390767D01*
X1208219Y391017D01*
X1208011Y391225D01*
X1207636Y391350D01*
X1207261Y391308D01*
X1206886Y391142D01*
G01X1210671Y399283D02*
Y401783D01*
X1211712D01*
X1212046Y401658D01*
X1212254Y401491D01*
X1212337Y401158D01*
X1212254Y400825D01*
X1212004Y400616D01*
X1211712Y400491D01*
X1210671D01*
G01X1211712D02*
X1212337Y399283D01*
G01X1213812Y401366D02*
X1214062Y401616D01*
X1214354Y401741D01*
X1214687Y401783D01*
X1215104Y401700D01*
X1215396Y401491D01*
X1215479Y401241D01*
X1215437Y400991D01*
X1215271Y400783D01*
X1214437Y400366D01*
X1214062Y400075D01*
X1213812Y399658D01*
X1213729Y399283D01*
X1215479D01*
G01X1216996Y399575D02*
X1217287Y399366D01*
X1217621Y399283D01*
X1217954Y399366D01*
X1218246Y399616D01*
X1218454Y399991D01*
X1218537Y400366D01*
Y400825D01*
X1218454Y401200D01*
X1218246Y401533D01*
X1217996Y401700D01*
X1217704Y401783D01*
X1217371Y401700D01*
X1217121Y401533D01*
X1216954Y401283D01*
X1216871Y400950D01*
X1216954Y400658D01*
X1217162Y400366D01*
X1217412Y400200D01*
X1217704Y400158D01*
X1218037Y400241D01*
X1218287Y400450D01*
X1218537Y400825D01*
G01X1220804Y401783D02*
X1220471Y401700D01*
X1220221Y401491D01*
X1220054Y401241D01*
X1219929Y400908D01*
X1219887Y400533D01*
X1219929Y400158D01*
X1220054Y399825D01*
X1220221Y399575D01*
X1220471Y399366D01*
X1220804Y399283D01*
X1221137Y399366D01*
X1221387Y399575D01*
X1221554Y399825D01*
X1221679Y400158D01*
X1221721Y400533D01*
X1221679Y400908D01*
X1221554Y401241D01*
X1221387Y401491D01*
X1221137Y401700D01*
X1220804Y401783D01*
G01X1223112Y401366D02*
X1223362Y401616D01*
X1223654Y401741D01*
X1223987Y401783D01*
X1224404Y401700D01*
X1224696Y401491D01*
X1224779Y401241D01*
X1224737Y400991D01*
X1224571Y400783D01*
X1223737Y400366D01*
X1223362Y400075D01*
X1223112Y399658D01*
X1223029Y399283D01*
X1224779D01*
G01X1194791Y393954D02*
Y396454D01*
X1195832D01*
X1196166Y396329D01*
X1196374Y396162D01*
X1196457Y395829D01*
X1196374Y395496D01*
X1196124Y395287D01*
X1195832Y395162D01*
X1194791D01*
G01X1195832D02*
X1196457Y393954D01*
G01X1197932Y396037D02*
X1198182Y396287D01*
X1198474Y396412D01*
X1198807Y396454D01*
X1199224Y396371D01*
X1199516Y396162D01*
X1199599Y395912D01*
X1199557Y395662D01*
X1199391Y395454D01*
X1198557Y395037D01*
X1198182Y394746D01*
X1197932Y394329D01*
X1197849Y393954D01*
X1199599D01*
G01X1201116Y394246D02*
X1201407Y394037D01*
X1201741Y393954D01*
X1202074Y394037D01*
X1202366Y394287D01*
X1202574Y394662D01*
X1202657Y395037D01*
Y395496D01*
X1202574Y395871D01*
X1202366Y396204D01*
X1202116Y396371D01*
X1201824Y396454D01*
X1201491Y396371D01*
X1201241Y396204D01*
X1201074Y395954D01*
X1200991Y395621D01*
X1201074Y395329D01*
X1201282Y395037D01*
X1201532Y394871D01*
X1201824Y394829D01*
X1202157Y394912D01*
X1202407Y395121D01*
X1202657Y395496D01*
G01X1204924Y396454D02*
X1204591Y396371D01*
X1204341Y396162D01*
X1204174Y395912D01*
X1204049Y395579D01*
X1204007Y395204D01*
X1204049Y394829D01*
X1204174Y394496D01*
X1204341Y394246D01*
X1204591Y394037D01*
X1204924Y393954D01*
X1205257Y394037D01*
X1205507Y394246D01*
X1205674Y394496D01*
X1205799Y394829D01*
X1205841Y395204D01*
X1205799Y395579D01*
X1205674Y395912D01*
X1205507Y396162D01*
X1205257Y396371D01*
X1204924Y396454D01*
G01X1208024Y393954D02*
Y396454D01*
X1207524Y395954D01*
G01Y393954D02*
X1208524D01*
G01X1191933Y394340D02*
X1189433D01*
Y395381D01*
X1189558Y395715D01*
X1189725Y395923D01*
X1190058Y396006D01*
X1190391Y395923D01*
X1190600Y395673D01*
X1190725Y395381D01*
Y394340D01*
G01Y395381D02*
X1191933Y396006D01*
G01X1189850Y397481D02*
X1189600Y397731D01*
X1189475Y398023D01*
X1189433Y398356D01*
X1189516Y398773D01*
X1189725Y399065D01*
X1189975Y399148D01*
X1190225Y399106D01*
X1190433Y398940D01*
X1190850Y398106D01*
X1191141Y397731D01*
X1191558Y397481D01*
X1191933Y397398D01*
Y399148D01*
G01Y401373D02*
X1189433D01*
X1189933Y400873D01*
G01X1191933D02*
Y401873D01*
G01X1191558Y403556D02*
X1191766Y403806D01*
X1191891Y404098D01*
X1191933Y404473D01*
X1191850Y404848D01*
X1191683Y405140D01*
X1191391Y405348D01*
X1191058Y405390D01*
X1190725Y405306D01*
X1190516Y405098D01*
X1190350Y404806D01*
X1190308Y404515D01*
X1190350Y404223D01*
X1190516Y403848D01*
X1189433Y403973D01*
Y405098D01*
G01X1183900Y407232D02*
Y409732D01*
X1184941D01*
X1185275Y409607D01*
X1185483Y409440D01*
X1185566Y409107D01*
X1185483Y408774D01*
X1185233Y408565D01*
X1184941Y408440D01*
X1183900D01*
G01X1184941D02*
X1185566Y407232D01*
G01X1187041Y409315D02*
X1187291Y409565D01*
X1187583Y409690D01*
X1187916Y409732D01*
X1188333Y409649D01*
X1188625Y409440D01*
X1188708Y409190D01*
X1188666Y408940D01*
X1188500Y408732D01*
X1187666Y408315D01*
X1187291Y408024D01*
X1187041Y407607D01*
X1186958Y407232D01*
X1188708D01*
G01X1190933D02*
Y409732D01*
X1190433Y409232D01*
G01Y407232D02*
X1191433D01*
G01X1193325Y407524D02*
X1193616Y407315D01*
X1193950Y407232D01*
X1194283Y407315D01*
X1194575Y407565D01*
X1194783Y407940D01*
X1194866Y408315D01*
Y408774D01*
X1194783Y409149D01*
X1194575Y409482D01*
X1194325Y409649D01*
X1194033Y409732D01*
X1193700Y409649D01*
X1193450Y409482D01*
X1193283Y409232D01*
X1193200Y408899D01*
X1193283Y408607D01*
X1193491Y408315D01*
X1193741Y408149D01*
X1194033Y408107D01*
X1194366Y408190D01*
X1194616Y408399D01*
X1194866Y408774D01*
G01X1195693Y380166D02*
Y382666D01*
X1196734D01*
X1197068Y382541D01*
X1197276Y382374D01*
X1197359Y382041D01*
X1197276Y381708D01*
X1197026Y381499D01*
X1196734Y381374D01*
X1195693D01*
G01X1196734D02*
X1197359Y380166D01*
G01X1198834Y382249D02*
X1199084Y382499D01*
X1199376Y382624D01*
X1199709Y382666D01*
X1200126Y382583D01*
X1200418Y382374D01*
X1200501Y382124D01*
X1200459Y381874D01*
X1200293Y381666D01*
X1199459Y381249D01*
X1199084Y380958D01*
X1198834Y380541D01*
X1198751Y380166D01*
X1200501D01*
G01X1201934Y382249D02*
X1202184Y382499D01*
X1202476Y382624D01*
X1202809Y382666D01*
X1203226Y382583D01*
X1203518Y382374D01*
X1203601Y382124D01*
X1203559Y381874D01*
X1203393Y381666D01*
X1202559Y381249D01*
X1202184Y380958D01*
X1201934Y380541D01*
X1201851Y380166D01*
X1203601D01*
G01X1205034Y382249D02*
X1205284Y382499D01*
X1205576Y382624D01*
X1205909Y382666D01*
X1206326Y382583D01*
X1206618Y382374D01*
X1206701Y382124D01*
X1206659Y381874D01*
X1206493Y381666D01*
X1205659Y381249D01*
X1205284Y380958D01*
X1205034Y380541D01*
X1204951Y380166D01*
X1206701D01*
G01X1191034Y378917D02*
X1188534D01*
Y379958D01*
X1188659Y380292D01*
X1188826Y380500D01*
X1189159Y380583D01*
X1189492Y380500D01*
X1189701Y380250D01*
X1189826Y379958D01*
Y378917D01*
G01Y379958D02*
X1191034Y380583D01*
G01X1188951Y382058D02*
X1188701Y382308D01*
X1188576Y382600D01*
X1188534Y382933D01*
X1188617Y383350D01*
X1188826Y383642D01*
X1189076Y383725D01*
X1189326Y383683D01*
X1189534Y383517D01*
X1189951Y382683D01*
X1190242Y382308D01*
X1190659Y382058D01*
X1191034Y381975D01*
Y383725D01*
G01X1190659Y385033D02*
X1190867Y385283D01*
X1190992Y385575D01*
X1191034Y385950D01*
X1190951Y386325D01*
X1190784Y386617D01*
X1190492Y386825D01*
X1190159Y386867D01*
X1189826Y386783D01*
X1189617Y386575D01*
X1189451Y386283D01*
X1189409Y385992D01*
X1189451Y385700D01*
X1189617Y385325D01*
X1188534Y385450D01*
Y386575D01*
G01X1190534Y388133D02*
X1190826Y388383D01*
X1190992Y388717D01*
X1191034Y389092D01*
X1190992Y389425D01*
X1190784Y389758D01*
X1190534Y389967D01*
X1190284Y390008D01*
X1189992Y389925D01*
X1189784Y389633D01*
X1189701Y389342D01*
Y388967D01*
G01Y389342D02*
X1189576Y389592D01*
X1189367Y389800D01*
X1189117Y389883D01*
X1188867Y389800D01*
X1188659Y389592D01*
X1188534Y389217D01*
X1188576Y388842D01*
X1188742Y388467D01*
G01X1210144Y379925D02*
Y382425D01*
X1211185D01*
X1211519Y382300D01*
X1211727Y382133D01*
X1211810Y381800D01*
X1211727Y381467D01*
X1211477Y381258D01*
X1211185Y381133D01*
X1210144D01*
G01X1211185D02*
X1211810Y379925D01*
G01X1213160Y380425D02*
X1213410Y380133D01*
X1213744Y379967D01*
X1214119Y379925D01*
X1214452Y379967D01*
X1214785Y380175D01*
X1214994Y380425D01*
X1215035Y380675D01*
X1214952Y380967D01*
X1214660Y381175D01*
X1214369Y381258D01*
X1213994D01*
G01X1214369D02*
X1214619Y381383D01*
X1214827Y381592D01*
X1214910Y381842D01*
X1214827Y382092D01*
X1214619Y382300D01*
X1214244Y382425D01*
X1213869Y382383D01*
X1213494Y382217D01*
G01X1216260Y380425D02*
X1216510Y380133D01*
X1216844Y379967D01*
X1217219Y379925D01*
X1217552Y379967D01*
X1217885Y380175D01*
X1218094Y380425D01*
X1218135Y380675D01*
X1218052Y380967D01*
X1217760Y381175D01*
X1217469Y381258D01*
X1217094D01*
G01X1217469D02*
X1217719Y381383D01*
X1217927Y381592D01*
X1218010Y381842D01*
X1217927Y382092D01*
X1217719Y382300D01*
X1217344Y382425D01*
X1216969Y382383D01*
X1216594Y382217D01*
G01X1219485Y382008D02*
X1219735Y382258D01*
X1220027Y382383D01*
X1220360Y382425D01*
X1220777Y382342D01*
X1221069Y382133D01*
X1221152Y381883D01*
X1221110Y381633D01*
X1220944Y381425D01*
X1220110Y381008D01*
X1219735Y380717D01*
X1219485Y380300D01*
X1219402Y379925D01*
X1221152D01*
G01X1212567Y414192D02*
X1212317Y414317D01*
X1212025Y414400D01*
X1211692D01*
X1211317Y414275D01*
X1211025Y414067D01*
X1210817Y413817D01*
X1210650Y413400D01*
X1210608Y413025D01*
X1210692Y412650D01*
X1210817Y412400D01*
X1211067Y412150D01*
X1211358Y411983D01*
X1211650Y411900D01*
X1211942D01*
X1212233Y411983D01*
X1212483Y412108D01*
X1212692Y412275D01*
G01X1214667Y411900D02*
X1214750Y412442D01*
X1214875Y412900D01*
X1215042Y413317D01*
X1215250Y413775D01*
X1215583Y414400D01*
X1213917D01*
G01X1212567Y410692D02*
X1212317Y410817D01*
X1212025Y410900D01*
X1211692D01*
X1211317Y410775D01*
X1211025Y410567D01*
X1210817Y410317D01*
X1210650Y409900D01*
X1210608Y409525D01*
X1210692Y409150D01*
X1210817Y408900D01*
X1211067Y408650D01*
X1211358Y408483D01*
X1211650Y408400D01*
X1211942D01*
X1212233Y408483D01*
X1212483Y408608D01*
X1212692Y408775D01*
G01X1213958Y410483D02*
X1214208Y410733D01*
X1214500Y410858D01*
X1214833Y410900D01*
X1215250Y410817D01*
X1215542Y410608D01*
X1215625Y410358D01*
X1215583Y410108D01*
X1215417Y409900D01*
X1214583Y409483D01*
X1214208Y409192D01*
X1213958Y408775D01*
X1213875Y408400D01*
X1215625D01*
G01X1212567Y407192D02*
X1212317Y407317D01*
X1212025Y407400D01*
X1211692D01*
X1211317Y407275D01*
X1211025Y407067D01*
X1210817Y406817D01*
X1210650Y406400D01*
X1210608Y406025D01*
X1210692Y405650D01*
X1210817Y405400D01*
X1211067Y405150D01*
X1211358Y404983D01*
X1211650Y404900D01*
X1211942D01*
X1212233Y404983D01*
X1212483Y405108D01*
X1212692Y405275D01*
G01X1214750Y404900D02*
Y407400D01*
X1214250Y406900D01*
G01Y404900D02*
X1215250D01*
G01X1212567Y417692D02*
X1212317Y417817D01*
X1212025Y417900D01*
X1211692D01*
X1211317Y417775D01*
X1211025Y417567D01*
X1210817Y417317D01*
X1210650Y416900D01*
X1210608Y416525D01*
X1210692Y416150D01*
X1210817Y415900D01*
X1211067Y415650D01*
X1211358Y415483D01*
X1211650Y415400D01*
X1211942D01*
X1212233Y415483D01*
X1212483Y415608D01*
X1212692Y415775D01*
G01X1213958Y416442D02*
X1214250Y416733D01*
X1214500Y416900D01*
X1214833Y416983D01*
X1215125Y416900D01*
X1215333Y416733D01*
X1215500Y416483D01*
X1215542Y416192D01*
X1215500Y415942D01*
X1215333Y415692D01*
X1215083Y415483D01*
X1214792Y415400D01*
X1214458Y415483D01*
X1214167Y415733D01*
X1214000Y416108D01*
X1213958Y416525D01*
X1214042Y417067D01*
X1214167Y417358D01*
X1214375Y417650D01*
X1214667Y417858D01*
X1214958Y417900D01*
X1215250Y417817D01*
X1215458Y417608D01*
G01X1180905Y818968D02*
X1180780Y818718D01*
X1180697Y818426D01*
Y818093D01*
X1180822Y817718D01*
X1181030Y817426D01*
X1181280Y817218D01*
X1181697Y817051D01*
X1182072Y817009D01*
X1182447Y817093D01*
X1182697Y817218D01*
X1182947Y817468D01*
X1183114Y817759D01*
X1183197Y818051D01*
Y818343D01*
X1183114Y818634D01*
X1182989Y818884D01*
X1182822Y819093D01*
G01X1183197Y821068D02*
X1182655Y821151D01*
X1182197Y821276D01*
X1181780Y821443D01*
X1181322Y821651D01*
X1180697Y821984D01*
Y820318D01*
G01X1183197Y824168D02*
X1182655Y824251D01*
X1182197Y824376D01*
X1181780Y824543D01*
X1181322Y824751D01*
X1180697Y825084D01*
Y823418D01*
G01X1192003Y818868D02*
X1191878Y818618D01*
X1191795Y818326D01*
Y817993D01*
X1191920Y817618D01*
X1192128Y817326D01*
X1192378Y817118D01*
X1192795Y816951D01*
X1193170Y816909D01*
X1193545Y816993D01*
X1193795Y817118D01*
X1194045Y817368D01*
X1194212Y817659D01*
X1194295Y817951D01*
Y818243D01*
X1194212Y818534D01*
X1194087Y818784D01*
X1193920Y818993D01*
G01X1194295Y820968D02*
X1193753Y821051D01*
X1193295Y821176D01*
X1192878Y821343D01*
X1192420Y821551D01*
X1191795Y821884D01*
Y820218D01*
G01X1193920Y823234D02*
X1194128Y823484D01*
X1194253Y823776D01*
X1194295Y824151D01*
X1194212Y824526D01*
X1194045Y824818D01*
X1193753Y825026D01*
X1193420Y825068D01*
X1193087Y824984D01*
X1192878Y824776D01*
X1192712Y824484D01*
X1192670Y824193D01*
X1192712Y823901D01*
X1192878Y823526D01*
X1191795Y823651D01*
Y824776D01*
G01X1188003Y818868D02*
X1187878Y818618D01*
X1187795Y818326D01*
Y817993D01*
X1187920Y817618D01*
X1188128Y817326D01*
X1188378Y817118D01*
X1188795Y816951D01*
X1189170Y816909D01*
X1189545Y816993D01*
X1189795Y817118D01*
X1190045Y817368D01*
X1190212Y817659D01*
X1190295Y817951D01*
Y818243D01*
X1190212Y818534D01*
X1190087Y818784D01*
X1189920Y818993D01*
G01X1190295Y820968D02*
X1189753Y821051D01*
X1189295Y821176D01*
X1188878Y821343D01*
X1188420Y821551D01*
X1187795Y821884D01*
Y820218D01*
G01X1190295Y824651D02*
X1187795D01*
X1189587Y823109D01*
Y825193D01*
G01X1203451Y847345D02*
X1204284D01*
Y846595D01*
X1204034Y846345D01*
X1203743Y846178D01*
X1203326Y846095D01*
X1202909Y846178D01*
X1202618Y846345D01*
X1202368Y846595D01*
X1202201Y846887D01*
X1202118Y847220D01*
Y847512D01*
X1202201Y847762D01*
X1202368Y848053D01*
X1202618Y848303D01*
X1202868Y848470D01*
X1203201Y848595D01*
X1203493D01*
X1203826Y848512D01*
X1204076Y848345D01*
G01X1205509Y846095D02*
Y848595D01*
X1207093D01*
G01X1206509Y847387D02*
X1205509D01*
G01X1209401Y846095D02*
Y848595D01*
X1208901Y848095D01*
G01Y846095D02*
X1209901D01*
G01X1212501Y848595D02*
X1212168Y848512D01*
X1211918Y848303D01*
X1211751Y848053D01*
X1211626Y847720D01*
X1211584Y847345D01*
X1211626Y846970D01*
X1211751Y846637D01*
X1211918Y846387D01*
X1212168Y846178D01*
X1212501Y846095D01*
X1212834Y846178D01*
X1213084Y846387D01*
X1213251Y846637D01*
X1213376Y846970D01*
X1213418Y847345D01*
X1213376Y847720D01*
X1213251Y848053D01*
X1213084Y848303D01*
X1212834Y848512D01*
X1212501Y848595D01*
G01X1230400Y115613D02*
X1229800Y115863D01*
X1229100Y116030D01*
X1228300D01*
X1227400Y115780D01*
X1226700Y115363D01*
X1226200Y114863D01*
X1225800Y114030D01*
X1225700Y113280D01*
X1225900Y112530D01*
X1226200Y112030D01*
X1226800Y111530D01*
X1227500Y111197D01*
X1228200Y111030D01*
X1228900D01*
X1229600Y111197D01*
X1230200Y111447D01*
X1230700Y111780D01*
G01X1225000Y120000D02*
Y125000D01*
X1231000D01*
G01X1242500D02*
X1249800D01*
G01X1239500D02*
X1234000D01*
G01X1216500Y120000D02*
X1221000D01*
G01X1244268Y143179D02*
Y139179D01*
X1251668D01*
G01X1214752Y128115D02*
X1218752D01*
Y135515D01*
G01X1221167Y162700D02*
X1220333D01*
Y159367D01*
X1221167D01*
G01X1223017Y162700D02*
Y160200D01*
X1224683D01*
G01X1227783D02*
X1226117D01*
Y162700D01*
X1227783D01*
G01X1227117Y161492D02*
X1226117D01*
G01X1229133Y160200D02*
Y162700D01*
X1229967D01*
X1230300Y162575D01*
X1230550Y162408D01*
X1230758Y162158D01*
X1230925Y161867D01*
X1230967Y161450D01*
X1230925Y161033D01*
X1230758Y160742D01*
X1230550Y160492D01*
X1230300Y160325D01*
X1229967Y160200D01*
X1229133D01*
G01X1233150D02*
Y162700D01*
X1232650Y162200D01*
G01Y160200D02*
X1233650D01*
G01X1235333Y160700D02*
X1235583Y160408D01*
X1235917Y160242D01*
X1236292Y160200D01*
X1236625Y160242D01*
X1236958Y160450D01*
X1237167Y160700D01*
X1237208Y160950D01*
X1237125Y161242D01*
X1236833Y161450D01*
X1236542Y161533D01*
X1236167D01*
G01X1236542D02*
X1236792Y161658D01*
X1237000Y161867D01*
X1237083Y162117D01*
X1237000Y162367D01*
X1236792Y162575D01*
X1236417Y162700D01*
X1236042Y162658D01*
X1235667Y162492D01*
G01X1238933Y159367D02*
X1239767D01*
Y162700D01*
X1238933D01*
G01X1227750Y155100D02*
X1227417Y155142D01*
X1227125Y155308D01*
X1226875Y155558D01*
X1226708Y155850D01*
X1226625Y156183D01*
Y156517D01*
X1226708Y156850D01*
X1226875Y157142D01*
X1227125Y157392D01*
X1227417Y157558D01*
X1227750Y157600D01*
X1228083Y157558D01*
X1228375Y157392D01*
X1228625Y157142D01*
X1228792Y156850D01*
X1228875Y156517D01*
Y156183D01*
X1228792Y155850D01*
X1228625Y155558D01*
X1228375Y155308D01*
X1228083Y155142D01*
X1227750Y155100D01*
G01X1230058D02*
Y157600D01*
X1231642D01*
G01X1231058Y156392D02*
X1230058D01*
G01X1233158Y155100D02*
Y157600D01*
X1234742D01*
G01X1234158Y156392D02*
X1233158D01*
G01X1227750Y150100D02*
X1227417Y150142D01*
X1227125Y150308D01*
X1226875Y150558D01*
X1226708Y150850D01*
X1226625Y151183D01*
Y151517D01*
X1226708Y151850D01*
X1226875Y152142D01*
X1227125Y152392D01*
X1227417Y152558D01*
X1227750Y152600D01*
X1228083Y152558D01*
X1228375Y152392D01*
X1228625Y152142D01*
X1228792Y151850D01*
X1228875Y151517D01*
Y151183D01*
X1228792Y150850D01*
X1228625Y150558D01*
X1228375Y150308D01*
X1228083Y150142D01*
X1227750Y150100D01*
G01X1229892D02*
Y152600D01*
X1231808Y150100D01*
Y152600D01*
G01X1243067Y162700D02*
X1242233D01*
Y159367D01*
X1243067D01*
G01X1244917Y162700D02*
Y160200D01*
X1246583D01*
G01X1249683D02*
X1248017D01*
Y162700D01*
X1249683D01*
G01X1249017Y161492D02*
X1248017D01*
G01X1251033Y160200D02*
Y162700D01*
X1251867D01*
X1252200Y162575D01*
X1252450Y162408D01*
X1252658Y162158D01*
X1252825Y161867D01*
X1252867Y161450D01*
X1252825Y161033D01*
X1252658Y160742D01*
X1252450Y160492D01*
X1252200Y160325D01*
X1251867Y160200D01*
X1251033D01*
G01X1255050D02*
Y162700D01*
X1254550Y162200D01*
G01Y160200D02*
X1255550D01*
G01X1257233Y160575D02*
X1257483Y160367D01*
X1257775Y160242D01*
X1258150Y160200D01*
X1258525Y160283D01*
X1258817Y160450D01*
X1259025Y160742D01*
X1259067Y161075D01*
X1258983Y161408D01*
X1258775Y161617D01*
X1258483Y161783D01*
X1258192Y161825D01*
X1257900Y161783D01*
X1257525Y161617D01*
X1257650Y162700D01*
X1258775D01*
G01X1260833Y159367D02*
X1261667D01*
Y162700D01*
X1260833D01*
G01X1227750Y145100D02*
X1227417Y145142D01*
X1227125Y145308D01*
X1226875Y145558D01*
X1226708Y145850D01*
X1226625Y146183D01*
Y146517D01*
X1226708Y146850D01*
X1226875Y147142D01*
X1227125Y147392D01*
X1227417Y147558D01*
X1227750Y147600D01*
X1228083Y147558D01*
X1228375Y147392D01*
X1228625Y147142D01*
X1228792Y146850D01*
X1228875Y146517D01*
Y146183D01*
X1228792Y145850D01*
X1228625Y145558D01*
X1228375Y145308D01*
X1228083Y145142D01*
X1227750Y145100D01*
G01X1229892D02*
Y147600D01*
X1231808Y145100D01*
Y147600D01*
G01X1242784Y147217D02*
Y143217D01*
X1250184D01*
G01X1225500Y195300D02*
Y206500D01*
G01X1243500Y195300D02*
X1225500D01*
G01X1243500Y206500D02*
Y195300D01*
G01X1225500Y233700D02*
Y222500D01*
G01X1243500Y233700D02*
X1225500D01*
G01X1243500Y222500D02*
Y233700D01*
G01Y253300D02*
Y264500D01*
G01X1225500Y253300D02*
X1243500D01*
G01X1225500Y264500D02*
Y253300D01*
G01X1229517Y294000D02*
Y296500D01*
X1230517D01*
X1230850Y296375D01*
X1231100Y296083D01*
X1231183Y295750D01*
X1231100Y295417D01*
X1230892Y295167D01*
X1230517Y295042D01*
X1229517D01*
G01X1233450Y296500D02*
Y294000D01*
G01X1232492Y296500D02*
X1234408D01*
G01X1237467Y296292D02*
X1237217Y296417D01*
X1236925Y296500D01*
X1236592D01*
X1236217Y296375D01*
X1235925Y296167D01*
X1235717Y295917D01*
X1235550Y295500D01*
X1235508Y295125D01*
X1235592Y294750D01*
X1235717Y294500D01*
X1235967Y294250D01*
X1236258Y294083D01*
X1236550Y294000D01*
X1236842D01*
X1237133Y294083D01*
X1237383Y294208D01*
X1237592Y294375D01*
G01X1240150Y294000D02*
Y296500D01*
X1238608Y294708D01*
X1240692D01*
G01X1243500Y291700D02*
Y280500D01*
G01X1225500Y291700D02*
X1243500D01*
G01X1225500Y280500D02*
Y291700D01*
G01X1212817Y284000D02*
Y286500D01*
X1213817D01*
X1214150Y286375D01*
X1214400Y286083D01*
X1214483Y285750D01*
X1214400Y285417D01*
X1214192Y285167D01*
X1213817Y285042D01*
X1212817D01*
G01X1217000Y285250D02*
X1217833D01*
Y284500D01*
X1217583Y284250D01*
X1217292Y284083D01*
X1216875Y284000D01*
X1216458Y284083D01*
X1216167Y284250D01*
X1215917Y284500D01*
X1215750Y284792D01*
X1215667Y285125D01*
Y285417D01*
X1215750Y285667D01*
X1215917Y285958D01*
X1216167Y286208D01*
X1216417Y286375D01*
X1216750Y286500D01*
X1217042D01*
X1217375Y286417D01*
X1217625Y286250D01*
G01X1219058Y285042D02*
X1219350Y285333D01*
X1219600Y285500D01*
X1219933Y285583D01*
X1220225Y285500D01*
X1220433Y285333D01*
X1220600Y285083D01*
X1220642Y284792D01*
X1220600Y284542D01*
X1220433Y284292D01*
X1220183Y284083D01*
X1219892Y284000D01*
X1219558Y284083D01*
X1219267Y284333D01*
X1219100Y284708D01*
X1219058Y285125D01*
X1219142Y285667D01*
X1219267Y285958D01*
X1219475Y286250D01*
X1219767Y286458D01*
X1220058Y286500D01*
X1220350Y286417D01*
X1220558Y286208D01*
G01X1222950Y286500D02*
X1222617Y286417D01*
X1222367Y286208D01*
X1222200Y285958D01*
X1222075Y285625D01*
X1222033Y285250D01*
X1222075Y284875D01*
X1222200Y284542D01*
X1222367Y284292D01*
X1222617Y284083D01*
X1222950Y284000D01*
X1223283Y284083D01*
X1223533Y284292D01*
X1223700Y284542D01*
X1223825Y284875D01*
X1223867Y285250D01*
X1223825Y285625D01*
X1223700Y285958D01*
X1223533Y286208D01*
X1223283Y286417D01*
X1222950Y286500D01*
G01X1212817Y304000D02*
Y306500D01*
X1213817D01*
X1214150Y306375D01*
X1214400Y306083D01*
X1214483Y305750D01*
X1214400Y305417D01*
X1214192Y305167D01*
X1213817Y305042D01*
X1212817D01*
G01X1217000Y305250D02*
X1217833D01*
Y304500D01*
X1217583Y304250D01*
X1217292Y304083D01*
X1216875Y304000D01*
X1216458Y304083D01*
X1216167Y304250D01*
X1215917Y304500D01*
X1215750Y304792D01*
X1215667Y305125D01*
Y305417D01*
X1215750Y305667D01*
X1215917Y305958D01*
X1216167Y306208D01*
X1216417Y306375D01*
X1216750Y306500D01*
X1217042D01*
X1217375Y306417D01*
X1217625Y306250D01*
G01X1218933Y304375D02*
X1219183Y304167D01*
X1219475Y304042D01*
X1219850Y304000D01*
X1220225Y304083D01*
X1220517Y304250D01*
X1220725Y304542D01*
X1220767Y304875D01*
X1220683Y305208D01*
X1220475Y305417D01*
X1220183Y305583D01*
X1219892Y305625D01*
X1219600Y305583D01*
X1219225Y305417D01*
X1219350Y306500D01*
X1220475D01*
G01X1222242Y304292D02*
X1222533Y304083D01*
X1222867Y304000D01*
X1223200Y304083D01*
X1223492Y304333D01*
X1223700Y304708D01*
X1223783Y305083D01*
Y305542D01*
X1223700Y305917D01*
X1223492Y306250D01*
X1223242Y306417D01*
X1222950Y306500D01*
X1222617Y306417D01*
X1222367Y306250D01*
X1222200Y306000D01*
X1222117Y305667D01*
X1222200Y305375D01*
X1222408Y305083D01*
X1222658Y304917D01*
X1222950Y304875D01*
X1223283Y304958D01*
X1223533Y305167D01*
X1223783Y305542D01*
G01X1212817Y300000D02*
Y302500D01*
X1213817D01*
X1214150Y302375D01*
X1214400Y302083D01*
X1214483Y301750D01*
X1214400Y301417D01*
X1214192Y301167D01*
X1213817Y301042D01*
X1212817D01*
G01X1217000Y301250D02*
X1217833D01*
Y300500D01*
X1217583Y300250D01*
X1217292Y300083D01*
X1216875Y300000D01*
X1216458Y300083D01*
X1216167Y300250D01*
X1215917Y300500D01*
X1215750Y300792D01*
X1215667Y301125D01*
Y301417D01*
X1215750Y301667D01*
X1215917Y301958D01*
X1216167Y302208D01*
X1216417Y302375D01*
X1216750Y302500D01*
X1217042D01*
X1217375Y302417D01*
X1217625Y302250D01*
G01X1220350Y300000D02*
Y302500D01*
X1218808Y300708D01*
X1220892D01*
G01X1222242Y300292D02*
X1222533Y300083D01*
X1222867Y300000D01*
X1223200Y300083D01*
X1223492Y300333D01*
X1223700Y300708D01*
X1223783Y301083D01*
Y301542D01*
X1223700Y301917D01*
X1223492Y302250D01*
X1223242Y302417D01*
X1222950Y302500D01*
X1222617Y302417D01*
X1222367Y302250D01*
X1222200Y302000D01*
X1222117Y301667D01*
X1222200Y301375D01*
X1222408Y301083D01*
X1222658Y300917D01*
X1222950Y300875D01*
X1223283Y300958D01*
X1223533Y301167D01*
X1223783Y301542D01*
G01X1212817Y296000D02*
Y298500D01*
X1213817D01*
X1214150Y298375D01*
X1214400Y298083D01*
X1214483Y297750D01*
X1214400Y297417D01*
X1214192Y297167D01*
X1213817Y297042D01*
X1212817D01*
G01X1217000Y297250D02*
X1217833D01*
Y296500D01*
X1217583Y296250D01*
X1217292Y296083D01*
X1216875Y296000D01*
X1216458Y296083D01*
X1216167Y296250D01*
X1215917Y296500D01*
X1215750Y296792D01*
X1215667Y297125D01*
Y297417D01*
X1215750Y297667D01*
X1215917Y297958D01*
X1216167Y298208D01*
X1216417Y298375D01*
X1216750Y298500D01*
X1217042D01*
X1217375Y298417D01*
X1217625Y298250D01*
G01X1220350Y296000D02*
Y298500D01*
X1218808Y296708D01*
X1220892D01*
G01X1222950Y296000D02*
X1223242Y296042D01*
X1223575Y296167D01*
X1223783Y296375D01*
X1223867Y296667D01*
X1223783Y296958D01*
X1223533Y297208D01*
X1223158Y297333D01*
X1222742D01*
X1222492Y297417D01*
X1222283Y297625D01*
X1222200Y297917D01*
X1222325Y298208D01*
X1222617Y298417D01*
X1222950Y298500D01*
X1223283Y298417D01*
X1223575Y298208D01*
X1223700Y297917D01*
X1223617Y297625D01*
X1223408Y297417D01*
X1223158Y297333D01*
X1222742D01*
X1222367Y297208D01*
X1222117Y296958D01*
X1222033Y296667D01*
X1222117Y296375D01*
X1222325Y296167D01*
X1222658Y296042D01*
X1222950Y296000D01*
G01X1212817Y292000D02*
Y294500D01*
X1213817D01*
X1214150Y294375D01*
X1214400Y294083D01*
X1214483Y293750D01*
X1214400Y293417D01*
X1214192Y293167D01*
X1213817Y293042D01*
X1212817D01*
G01X1217000Y293250D02*
X1217833D01*
Y292500D01*
X1217583Y292250D01*
X1217292Y292083D01*
X1216875Y292000D01*
X1216458Y292083D01*
X1216167Y292250D01*
X1215917Y292500D01*
X1215750Y292792D01*
X1215667Y293125D01*
Y293417D01*
X1215750Y293667D01*
X1215917Y293958D01*
X1216167Y294208D01*
X1216417Y294375D01*
X1216750Y294500D01*
X1217042D01*
X1217375Y294417D01*
X1217625Y294250D01*
G01X1220350Y292000D02*
Y294500D01*
X1218808Y292708D01*
X1220892D01*
G01X1222867Y292000D02*
X1222950Y292542D01*
X1223075Y293000D01*
X1223242Y293417D01*
X1223450Y293875D01*
X1223783Y294500D01*
X1222117D01*
G01X1212817Y288000D02*
Y290500D01*
X1213817D01*
X1214150Y290375D01*
X1214400Y290083D01*
X1214483Y289750D01*
X1214400Y289417D01*
X1214192Y289167D01*
X1213817Y289042D01*
X1212817D01*
G01X1217000Y289250D02*
X1217833D01*
Y288500D01*
X1217583Y288250D01*
X1217292Y288083D01*
X1216875Y288000D01*
X1216458Y288083D01*
X1216167Y288250D01*
X1215917Y288500D01*
X1215750Y288792D01*
X1215667Y289125D01*
Y289417D01*
X1215750Y289667D01*
X1215917Y289958D01*
X1216167Y290208D01*
X1216417Y290375D01*
X1216750Y290500D01*
X1217042D01*
X1217375Y290417D01*
X1217625Y290250D01*
G01X1220350Y288000D02*
Y290500D01*
X1218808Y288708D01*
X1220892D01*
G01X1222158Y289042D02*
X1222450Y289333D01*
X1222700Y289500D01*
X1223033Y289583D01*
X1223325Y289500D01*
X1223533Y289333D01*
X1223700Y289083D01*
X1223742Y288792D01*
X1223700Y288542D01*
X1223533Y288292D01*
X1223283Y288083D01*
X1222992Y288000D01*
X1222658Y288083D01*
X1222367Y288333D01*
X1222200Y288708D01*
X1222158Y289125D01*
X1222242Y289667D01*
X1222367Y289958D01*
X1222575Y290250D01*
X1222867Y290458D01*
X1223158Y290500D01*
X1223450Y290417D01*
X1223658Y290208D01*
G01X1212817Y308000D02*
Y310500D01*
X1213817D01*
X1214150Y310375D01*
X1214400Y310083D01*
X1214483Y309750D01*
X1214400Y309417D01*
X1214192Y309167D01*
X1213817Y309042D01*
X1212817D01*
G01X1217000Y309250D02*
X1217833D01*
Y308500D01*
X1217583Y308250D01*
X1217292Y308083D01*
X1216875Y308000D01*
X1216458Y308083D01*
X1216167Y308250D01*
X1215917Y308500D01*
X1215750Y308792D01*
X1215667Y309125D01*
Y309417D01*
X1215750Y309667D01*
X1215917Y309958D01*
X1216167Y310208D01*
X1216417Y310375D01*
X1216750Y310500D01*
X1217042D01*
X1217375Y310417D01*
X1217625Y310250D01*
G01X1220350Y308000D02*
Y310500D01*
X1218808Y308708D01*
X1220892D01*
G01X1222033Y308375D02*
X1222283Y308167D01*
X1222575Y308042D01*
X1222950Y308000D01*
X1223325Y308083D01*
X1223617Y308250D01*
X1223825Y308542D01*
X1223867Y308875D01*
X1223783Y309208D01*
X1223575Y309417D01*
X1223283Y309583D01*
X1222992Y309625D01*
X1222700Y309583D01*
X1222325Y309417D01*
X1222450Y310500D01*
X1223575D01*
G01X1212817Y340000D02*
Y342500D01*
X1213817D01*
X1214150Y342375D01*
X1214400Y342083D01*
X1214483Y341750D01*
X1214400Y341417D01*
X1214192Y341167D01*
X1213817Y341042D01*
X1212817D01*
G01X1217000Y341250D02*
X1217833D01*
Y340500D01*
X1217583Y340250D01*
X1217292Y340083D01*
X1216875Y340000D01*
X1216458Y340083D01*
X1216167Y340250D01*
X1215917Y340500D01*
X1215750Y340792D01*
X1215667Y341125D01*
Y341417D01*
X1215750Y341667D01*
X1215917Y341958D01*
X1216167Y342208D01*
X1216417Y342375D01*
X1216750Y342500D01*
X1217042D01*
X1217375Y342417D01*
X1217625Y342250D01*
G01X1219058Y341042D02*
X1219350Y341333D01*
X1219600Y341500D01*
X1219933Y341583D01*
X1220225Y341500D01*
X1220433Y341333D01*
X1220600Y341083D01*
X1220642Y340792D01*
X1220600Y340542D01*
X1220433Y340292D01*
X1220183Y340083D01*
X1219892Y340000D01*
X1219558Y340083D01*
X1219267Y340333D01*
X1219100Y340708D01*
X1219058Y341125D01*
X1219142Y341667D01*
X1219267Y341958D01*
X1219475Y342250D01*
X1219767Y342458D01*
X1220058Y342500D01*
X1220350Y342417D01*
X1220558Y342208D01*
G01X1222033Y340375D02*
X1222283Y340167D01*
X1222575Y340042D01*
X1222950Y340000D01*
X1223325Y340083D01*
X1223617Y340250D01*
X1223825Y340542D01*
X1223867Y340875D01*
X1223783Y341208D01*
X1223575Y341417D01*
X1223283Y341583D01*
X1222992Y341625D01*
X1222700Y341583D01*
X1222325Y341417D01*
X1222450Y342500D01*
X1223575D01*
G01X1212817Y324000D02*
Y326500D01*
X1213817D01*
X1214150Y326375D01*
X1214400Y326083D01*
X1214483Y325750D01*
X1214400Y325417D01*
X1214192Y325167D01*
X1213817Y325042D01*
X1212817D01*
G01X1217000Y325250D02*
X1217833D01*
Y324500D01*
X1217583Y324250D01*
X1217292Y324083D01*
X1216875Y324000D01*
X1216458Y324083D01*
X1216167Y324250D01*
X1215917Y324500D01*
X1215750Y324792D01*
X1215667Y325125D01*
Y325417D01*
X1215750Y325667D01*
X1215917Y325958D01*
X1216167Y326208D01*
X1216417Y326375D01*
X1216750Y326500D01*
X1217042D01*
X1217375Y326417D01*
X1217625Y326250D01*
G01X1218933Y324375D02*
X1219183Y324167D01*
X1219475Y324042D01*
X1219850Y324000D01*
X1220225Y324083D01*
X1220517Y324250D01*
X1220725Y324542D01*
X1220767Y324875D01*
X1220683Y325208D01*
X1220475Y325417D01*
X1220183Y325583D01*
X1219892Y325625D01*
X1219600Y325583D01*
X1219225Y325417D01*
X1219350Y326500D01*
X1220475D01*
G01X1222867Y324000D02*
X1222950Y324542D01*
X1223075Y325000D01*
X1223242Y325417D01*
X1223450Y325875D01*
X1223783Y326500D01*
X1222117D01*
G01X1212817Y344000D02*
Y346500D01*
X1213817D01*
X1214150Y346375D01*
X1214400Y346083D01*
X1214483Y345750D01*
X1214400Y345417D01*
X1214192Y345167D01*
X1213817Y345042D01*
X1212817D01*
G01X1217000Y345250D02*
X1217833D01*
Y344500D01*
X1217583Y344250D01*
X1217292Y344083D01*
X1216875Y344000D01*
X1216458Y344083D01*
X1216167Y344250D01*
X1215917Y344500D01*
X1215750Y344792D01*
X1215667Y345125D01*
Y345417D01*
X1215750Y345667D01*
X1215917Y345958D01*
X1216167Y346208D01*
X1216417Y346375D01*
X1216750Y346500D01*
X1217042D01*
X1217375Y346417D01*
X1217625Y346250D01*
G01X1218933Y344375D02*
X1219183Y344167D01*
X1219475Y344042D01*
X1219850Y344000D01*
X1220225Y344083D01*
X1220517Y344250D01*
X1220725Y344542D01*
X1220767Y344875D01*
X1220683Y345208D01*
X1220475Y345417D01*
X1220183Y345583D01*
X1219892Y345625D01*
X1219600Y345583D01*
X1219225Y345417D01*
X1219350Y346500D01*
X1220475D01*
G01X1222033Y344375D02*
X1222283Y344167D01*
X1222575Y344042D01*
X1222950Y344000D01*
X1223325Y344083D01*
X1223617Y344250D01*
X1223825Y344542D01*
X1223867Y344875D01*
X1223783Y345208D01*
X1223575Y345417D01*
X1223283Y345583D01*
X1222992Y345625D01*
X1222700Y345583D01*
X1222325Y345417D01*
X1222450Y346500D01*
X1223575D01*
G01X1212817Y320000D02*
Y322500D01*
X1213817D01*
X1214150Y322375D01*
X1214400Y322083D01*
X1214483Y321750D01*
X1214400Y321417D01*
X1214192Y321167D01*
X1213817Y321042D01*
X1212817D01*
G01X1217000Y321250D02*
X1217833D01*
Y320500D01*
X1217583Y320250D01*
X1217292Y320083D01*
X1216875Y320000D01*
X1216458Y320083D01*
X1216167Y320250D01*
X1215917Y320500D01*
X1215750Y320792D01*
X1215667Y321125D01*
Y321417D01*
X1215750Y321667D01*
X1215917Y321958D01*
X1216167Y322208D01*
X1216417Y322375D01*
X1216750Y322500D01*
X1217042D01*
X1217375Y322417D01*
X1217625Y322250D01*
G01X1218933Y320375D02*
X1219183Y320167D01*
X1219475Y320042D01*
X1219850Y320000D01*
X1220225Y320083D01*
X1220517Y320250D01*
X1220725Y320542D01*
X1220767Y320875D01*
X1220683Y321208D01*
X1220475Y321417D01*
X1220183Y321583D01*
X1219892Y321625D01*
X1219600Y321583D01*
X1219225Y321417D01*
X1219350Y322500D01*
X1220475D01*
G01X1222950Y320000D02*
Y322500D01*
X1222450Y322000D01*
G01Y320000D02*
X1223450D01*
G01X1212817Y316000D02*
Y318500D01*
X1213817D01*
X1214150Y318375D01*
X1214400Y318083D01*
X1214483Y317750D01*
X1214400Y317417D01*
X1214192Y317167D01*
X1213817Y317042D01*
X1212817D01*
G01X1217000Y317250D02*
X1217833D01*
Y316500D01*
X1217583Y316250D01*
X1217292Y316083D01*
X1216875Y316000D01*
X1216458Y316083D01*
X1216167Y316250D01*
X1215917Y316500D01*
X1215750Y316792D01*
X1215667Y317125D01*
Y317417D01*
X1215750Y317667D01*
X1215917Y317958D01*
X1216167Y318208D01*
X1216417Y318375D01*
X1216750Y318500D01*
X1217042D01*
X1217375Y318417D01*
X1217625Y318250D01*
G01X1218933Y316375D02*
X1219183Y316167D01*
X1219475Y316042D01*
X1219850Y316000D01*
X1220225Y316083D01*
X1220517Y316250D01*
X1220725Y316542D01*
X1220767Y316875D01*
X1220683Y317208D01*
X1220475Y317417D01*
X1220183Y317583D01*
X1219892Y317625D01*
X1219600Y317583D01*
X1219225Y317417D01*
X1219350Y318500D01*
X1220475D01*
G01X1222950D02*
X1222617Y318417D01*
X1222367Y318208D01*
X1222200Y317958D01*
X1222075Y317625D01*
X1222033Y317250D01*
X1222075Y316875D01*
X1222200Y316542D01*
X1222367Y316292D01*
X1222617Y316083D01*
X1222950Y316000D01*
X1223283Y316083D01*
X1223533Y316292D01*
X1223700Y316542D01*
X1223825Y316875D01*
X1223867Y317250D01*
X1223825Y317625D01*
X1223700Y317958D01*
X1223533Y318208D01*
X1223283Y318417D01*
X1222950Y318500D01*
G01X1212817Y312000D02*
Y314500D01*
X1213817D01*
X1214150Y314375D01*
X1214400Y314083D01*
X1214483Y313750D01*
X1214400Y313417D01*
X1214192Y313167D01*
X1213817Y313042D01*
X1212817D01*
G01X1217000Y313250D02*
X1217833D01*
Y312500D01*
X1217583Y312250D01*
X1217292Y312083D01*
X1216875Y312000D01*
X1216458Y312083D01*
X1216167Y312250D01*
X1215917Y312500D01*
X1215750Y312792D01*
X1215667Y313125D01*
Y313417D01*
X1215750Y313667D01*
X1215917Y313958D01*
X1216167Y314208D01*
X1216417Y314375D01*
X1216750Y314500D01*
X1217042D01*
X1217375Y314417D01*
X1217625Y314250D01*
G01X1220350Y312000D02*
Y314500D01*
X1218808Y312708D01*
X1220892D01*
G01X1223450Y312000D02*
Y314500D01*
X1221908Y312708D01*
X1223992D01*
G01X1212817Y328000D02*
Y330500D01*
X1213817D01*
X1214150Y330375D01*
X1214400Y330083D01*
X1214483Y329750D01*
X1214400Y329417D01*
X1214192Y329167D01*
X1213817Y329042D01*
X1212817D01*
G01X1217000Y329250D02*
X1217833D01*
Y328500D01*
X1217583Y328250D01*
X1217292Y328083D01*
X1216875Y328000D01*
X1216458Y328083D01*
X1216167Y328250D01*
X1215917Y328500D01*
X1215750Y328792D01*
X1215667Y329125D01*
Y329417D01*
X1215750Y329667D01*
X1215917Y329958D01*
X1216167Y330208D01*
X1216417Y330375D01*
X1216750Y330500D01*
X1217042D01*
X1217375Y330417D01*
X1217625Y330250D01*
G01X1220350Y328000D02*
Y330500D01*
X1218808Y328708D01*
X1220892D01*
G01X1222033Y328500D02*
X1222283Y328208D01*
X1222617Y328042D01*
X1222992Y328000D01*
X1223325Y328042D01*
X1223658Y328250D01*
X1223867Y328500D01*
X1223908Y328750D01*
X1223825Y329042D01*
X1223533Y329250D01*
X1223242Y329333D01*
X1222867D01*
G01X1223242D02*
X1223492Y329458D01*
X1223700Y329667D01*
X1223783Y329917D01*
X1223700Y330167D01*
X1223492Y330375D01*
X1223117Y330500D01*
X1222742Y330458D01*
X1222367Y330292D01*
G01X1212817Y332000D02*
Y334500D01*
X1213817D01*
X1214150Y334375D01*
X1214400Y334083D01*
X1214483Y333750D01*
X1214400Y333417D01*
X1214192Y333167D01*
X1213817Y333042D01*
X1212817D01*
G01X1217000Y333250D02*
X1217833D01*
Y332500D01*
X1217583Y332250D01*
X1217292Y332083D01*
X1216875Y332000D01*
X1216458Y332083D01*
X1216167Y332250D01*
X1215917Y332500D01*
X1215750Y332792D01*
X1215667Y333125D01*
Y333417D01*
X1215750Y333667D01*
X1215917Y333958D01*
X1216167Y334208D01*
X1216417Y334375D01*
X1216750Y334500D01*
X1217042D01*
X1217375Y334417D01*
X1217625Y334250D01*
G01X1220350Y332000D02*
Y334500D01*
X1218808Y332708D01*
X1220892D01*
G01X1222158Y334083D02*
X1222408Y334333D01*
X1222700Y334458D01*
X1223033Y334500D01*
X1223450Y334417D01*
X1223742Y334208D01*
X1223825Y333958D01*
X1223783Y333708D01*
X1223617Y333500D01*
X1222783Y333083D01*
X1222408Y332792D01*
X1222158Y332375D01*
X1222075Y332000D01*
X1223825D01*
G01X1212817Y336000D02*
Y338500D01*
X1213817D01*
X1214150Y338375D01*
X1214400Y338083D01*
X1214483Y337750D01*
X1214400Y337417D01*
X1214192Y337167D01*
X1213817Y337042D01*
X1212817D01*
G01X1217000Y337250D02*
X1217833D01*
Y336500D01*
X1217583Y336250D01*
X1217292Y336083D01*
X1216875Y336000D01*
X1216458Y336083D01*
X1216167Y336250D01*
X1215917Y336500D01*
X1215750Y336792D01*
X1215667Y337125D01*
Y337417D01*
X1215750Y337667D01*
X1215917Y337958D01*
X1216167Y338208D01*
X1216417Y338375D01*
X1216750Y338500D01*
X1217042D01*
X1217375Y338417D01*
X1217625Y338250D01*
G01X1218933Y336500D02*
X1219183Y336208D01*
X1219517Y336042D01*
X1219892Y336000D01*
X1220225Y336042D01*
X1220558Y336250D01*
X1220767Y336500D01*
X1220808Y336750D01*
X1220725Y337042D01*
X1220433Y337250D01*
X1220142Y337333D01*
X1219767D01*
G01X1220142D02*
X1220392Y337458D01*
X1220600Y337667D01*
X1220683Y337917D01*
X1220600Y338167D01*
X1220392Y338375D01*
X1220017Y338500D01*
X1219642Y338458D01*
X1219267Y338292D01*
G01X1222867Y336000D02*
X1222950Y336542D01*
X1223075Y337000D01*
X1223242Y337417D01*
X1223450Y337875D01*
X1223783Y338500D01*
X1222117D01*
G01X1223974Y818195D02*
X1223849Y817945D01*
X1223766Y817653D01*
Y817320D01*
X1223891Y816945D01*
X1224099Y816653D01*
X1224349Y816445D01*
X1224766Y816278D01*
X1225141Y816236D01*
X1225516Y816320D01*
X1225766Y816445D01*
X1226016Y816695D01*
X1226183Y816986D01*
X1226266Y817278D01*
Y817570D01*
X1226183Y817861D01*
X1226058Y818111D01*
X1225891Y818320D01*
G01X1226266Y820295D02*
X1225724Y820378D01*
X1225266Y820503D01*
X1224849Y820670D01*
X1224391Y820878D01*
X1223766Y821211D01*
Y819545D01*
G01X1225766Y822561D02*
X1226058Y822811D01*
X1226224Y823145D01*
X1226266Y823520D01*
X1226224Y823853D01*
X1226016Y824186D01*
X1225766Y824395D01*
X1225516Y824436D01*
X1225224Y824353D01*
X1225016Y824061D01*
X1224933Y823770D01*
Y823395D01*
G01Y823770D02*
X1224808Y824020D01*
X1224599Y824228D01*
X1224349Y824311D01*
X1224099Y824228D01*
X1223891Y824020D01*
X1223766Y823645D01*
X1223808Y823270D01*
X1223974Y822895D01*
G01X1219974Y818195D02*
X1219849Y817945D01*
X1219766Y817653D01*
Y817320D01*
X1219891Y816945D01*
X1220099Y816653D01*
X1220349Y816445D01*
X1220766Y816278D01*
X1221141Y816236D01*
X1221516Y816320D01*
X1221766Y816445D01*
X1222016Y816695D01*
X1222183Y816986D01*
X1222266Y817278D01*
Y817570D01*
X1222183Y817861D01*
X1222058Y818111D01*
X1221891Y818320D01*
G01X1222266Y820295D02*
X1221724Y820378D01*
X1221266Y820503D01*
X1220849Y820670D01*
X1220391Y820878D01*
X1219766Y821211D01*
Y819545D01*
G01X1220183Y822686D02*
X1219933Y822936D01*
X1219808Y823228D01*
X1219766Y823561D01*
X1219849Y823978D01*
X1220058Y824270D01*
X1220308Y824353D01*
X1220558Y824311D01*
X1220766Y824145D01*
X1221183Y823311D01*
X1221474Y822936D01*
X1221891Y822686D01*
X1222266Y822603D01*
Y824353D01*
G01X1236573Y818195D02*
X1236448Y817945D01*
X1236365Y817653D01*
Y817320D01*
X1236490Y816945D01*
X1236698Y816653D01*
X1236948Y816445D01*
X1237365Y816278D01*
X1237740Y816236D01*
X1238115Y816320D01*
X1238365Y816445D01*
X1238615Y816695D01*
X1238782Y816986D01*
X1238865Y817278D01*
Y817570D01*
X1238782Y817861D01*
X1238657Y818111D01*
X1238490Y818320D01*
G01X1238865Y820295D02*
X1238323Y820378D01*
X1237865Y820503D01*
X1237448Y820670D01*
X1236990Y820878D01*
X1236365Y821211D01*
Y819545D01*
G01X1238865Y823478D02*
X1236365D01*
X1236865Y822978D01*
G01X1238865D02*
Y823978D01*
G01X1232573Y818195D02*
X1232448Y817945D01*
X1232365Y817653D01*
Y817320D01*
X1232490Y816945D01*
X1232698Y816653D01*
X1232948Y816445D01*
X1233365Y816278D01*
X1233740Y816236D01*
X1234115Y816320D01*
X1234365Y816445D01*
X1234615Y816695D01*
X1234782Y816986D01*
X1234865Y817278D01*
Y817570D01*
X1234782Y817861D01*
X1234657Y818111D01*
X1234490Y818320D01*
G01X1234865Y820295D02*
X1234323Y820378D01*
X1233865Y820503D01*
X1233448Y820670D01*
X1232990Y820878D01*
X1232365Y821211D01*
Y819545D01*
G01Y823478D02*
X1232448Y823145D01*
X1232657Y822895D01*
X1232907Y822728D01*
X1233240Y822603D01*
X1233615Y822561D01*
X1233990Y822603D01*
X1234323Y822728D01*
X1234573Y822895D01*
X1234782Y823145D01*
X1234865Y823478D01*
X1234782Y823811D01*
X1234573Y824061D01*
X1234323Y824228D01*
X1233990Y824353D01*
X1233615Y824395D01*
X1233240Y824353D01*
X1232907Y824228D01*
X1232657Y824061D01*
X1232448Y823811D01*
X1232365Y823478D01*
G01X1266100Y111500D02*
Y116500D01*
X1268100D01*
X1268900Y116250D01*
X1269500Y115917D01*
X1270000Y115417D01*
X1270400Y114833D01*
X1270500Y114000D01*
X1270400Y113167D01*
X1270000Y112583D01*
X1269500Y112083D01*
X1268900Y111750D01*
X1268100Y111500D01*
X1266100D01*
G01X1258500Y125000D02*
X1253500D01*
G01X1283000D02*
X1277000D01*
G01X1274000D02*
X1269700D01*
G01X1261500D02*
X1266100D01*
G01X1251679Y135295D02*
X1247679D01*
Y127895D01*
G01X1255719Y135295D02*
X1251719D01*
Y127895D01*
G01X1268005Y128221D02*
X1272005D01*
Y135621D01*
G01X1263997Y128222D02*
X1267997D01*
Y135622D01*
G01X1271450Y155200D02*
X1271117Y155242D01*
X1270825Y155408D01*
X1270575Y155658D01*
X1270408Y155950D01*
X1270325Y156283D01*
Y156617D01*
X1270408Y156950D01*
X1270575Y157242D01*
X1270825Y157492D01*
X1271117Y157658D01*
X1271450Y157700D01*
X1271783Y157658D01*
X1272075Y157492D01*
X1272325Y157242D01*
X1272492Y156950D01*
X1272575Y156617D01*
Y156283D01*
X1272492Y155950D01*
X1272325Y155658D01*
X1272075Y155408D01*
X1271783Y155242D01*
X1271450Y155200D01*
G01X1273758D02*
Y157700D01*
X1275342D01*
G01X1274758Y156492D02*
X1273758D01*
G01X1276858Y155200D02*
Y157700D01*
X1278442D01*
G01X1277858Y156492D02*
X1276858D01*
G01X1271450Y150200D02*
X1271117Y150242D01*
X1270825Y150408D01*
X1270575Y150658D01*
X1270408Y150950D01*
X1270325Y151283D01*
Y151617D01*
X1270408Y151950D01*
X1270575Y152242D01*
X1270825Y152492D01*
X1271117Y152658D01*
X1271450Y152700D01*
X1271783Y152658D01*
X1272075Y152492D01*
X1272325Y152242D01*
X1272492Y151950D01*
X1272575Y151617D01*
Y151283D01*
X1272492Y150950D01*
X1272325Y150658D01*
X1272075Y150408D01*
X1271783Y150242D01*
X1271450Y150200D01*
G01X1273758D02*
Y152700D01*
X1275342D01*
G01X1274758Y151492D02*
X1273758D01*
G01X1276858Y150200D02*
Y152700D01*
X1278442D01*
G01X1277858Y151492D02*
X1276858D01*
G01X1265467Y162700D02*
X1264633D01*
Y159367D01*
X1265467D01*
G01X1267317Y162700D02*
Y160200D01*
X1268983D01*
G01X1272083D02*
X1270417D01*
Y162700D01*
X1272083D01*
G01X1271417Y161492D02*
X1270417D01*
G01X1273433Y160200D02*
Y162700D01*
X1274267D01*
X1274600Y162575D01*
X1274850Y162408D01*
X1275058Y162158D01*
X1275225Y161867D01*
X1275267Y161450D01*
X1275225Y161033D01*
X1275058Y160742D01*
X1274850Y160492D01*
X1274600Y160325D01*
X1274267Y160200D01*
X1273433D01*
G01X1277450D02*
Y162700D01*
X1276950Y162200D01*
G01Y160200D02*
X1277950D01*
G01X1279758Y161242D02*
X1280050Y161533D01*
X1280300Y161700D01*
X1280633Y161783D01*
X1280925Y161700D01*
X1281133Y161533D01*
X1281300Y161283D01*
X1281342Y160992D01*
X1281300Y160742D01*
X1281133Y160492D01*
X1280883Y160283D01*
X1280592Y160200D01*
X1280258Y160283D01*
X1279967Y160533D01*
X1279800Y160908D01*
X1279758Y161325D01*
X1279842Y161867D01*
X1279967Y162158D01*
X1280175Y162450D01*
X1280467Y162658D01*
X1280758Y162700D01*
X1281050Y162617D01*
X1281258Y162408D01*
G01X1283233Y159367D02*
X1284067D01*
Y162700D01*
X1283233D01*
G01X1271450Y145200D02*
X1271117Y145242D01*
X1270825Y145408D01*
X1270575Y145658D01*
X1270408Y145950D01*
X1270325Y146283D01*
Y146617D01*
X1270408Y146950D01*
X1270575Y147242D01*
X1270825Y147492D01*
X1271117Y147658D01*
X1271450Y147700D01*
X1271783Y147658D01*
X1272075Y147492D01*
X1272325Y147242D01*
X1272492Y146950D01*
X1272575Y146617D01*
Y146283D01*
X1272492Y145950D01*
X1272325Y145658D01*
X1272075Y145408D01*
X1271783Y145242D01*
X1271450Y145200D01*
G01X1273592D02*
Y147700D01*
X1275508Y145200D01*
Y147700D01*
G01X1251050Y155500D02*
X1250717Y155542D01*
X1250425Y155708D01*
X1250175Y155958D01*
X1250008Y156250D01*
X1249925Y156583D01*
Y156917D01*
X1250008Y157250D01*
X1250175Y157542D01*
X1250425Y157792D01*
X1250717Y157958D01*
X1251050Y158000D01*
X1251383Y157958D01*
X1251675Y157792D01*
X1251925Y157542D01*
X1252092Y157250D01*
X1252175Y156917D01*
Y156583D01*
X1252092Y156250D01*
X1251925Y155958D01*
X1251675Y155708D01*
X1251383Y155542D01*
X1251050Y155500D01*
G01X1253358D02*
Y158000D01*
X1254942D01*
G01X1254358Y156792D02*
X1253358D01*
G01X1256458Y155500D02*
Y158000D01*
X1258042D01*
G01X1257458Y156792D02*
X1256458D01*
G01X1251050Y150500D02*
X1250717Y150542D01*
X1250425Y150708D01*
X1250175Y150958D01*
X1250008Y151250D01*
X1249925Y151583D01*
Y151917D01*
X1250008Y152250D01*
X1250175Y152542D01*
X1250425Y152792D01*
X1250717Y152958D01*
X1251050Y153000D01*
X1251383Y152958D01*
X1251675Y152792D01*
X1251925Y152542D01*
X1252092Y152250D01*
X1252175Y151917D01*
Y151583D01*
X1252092Y151250D01*
X1251925Y150958D01*
X1251675Y150708D01*
X1251383Y150542D01*
X1251050Y150500D01*
G01X1253358D02*
Y153000D01*
X1254942D01*
G01X1254358Y151792D02*
X1253358D01*
G01X1256458Y150500D02*
Y153000D01*
X1258042D01*
G01X1257458Y151792D02*
X1256458D01*
G01X1251050Y145500D02*
X1250717Y145542D01*
X1250425Y145708D01*
X1250175Y145958D01*
X1250008Y146250D01*
X1249925Y146583D01*
Y146917D01*
X1250008Y147250D01*
X1250175Y147542D01*
X1250425Y147792D01*
X1250717Y147958D01*
X1251050Y148000D01*
X1251383Y147958D01*
X1251675Y147792D01*
X1251925Y147542D01*
X1252092Y147250D01*
X1252175Y146917D01*
Y146583D01*
X1252092Y146250D01*
X1251925Y145958D01*
X1251675Y145708D01*
X1251383Y145542D01*
X1251050Y145500D01*
G01X1253192D02*
Y148000D01*
X1255108Y145500D01*
Y148000D01*
G01X1262000Y143500D02*
X1287000D01*
Y147500D01*
X1300000D01*
Y133000D01*
G01X1268979Y207820D02*
Y202820D01*
X1272313D01*
G01X1274163D02*
X1276246Y207820D01*
X1278329Y202820D01*
G01X1277579Y204570D02*
X1274913D01*
G01X1281846Y207820D02*
Y202820D01*
G01X1279929Y207820D02*
X1283763D01*
G01X1289279Y207403D02*
X1288779Y207653D01*
X1288196Y207820D01*
X1287529D01*
X1286779Y207570D01*
X1286196Y207153D01*
X1285779Y206653D01*
X1285446Y205820D01*
X1285363Y205070D01*
X1285529Y204320D01*
X1285779Y203820D01*
X1286279Y203320D01*
X1286863Y202987D01*
X1287446Y202820D01*
X1288029D01*
X1288613Y202987D01*
X1289113Y203237D01*
X1289529Y203570D01*
G01X1291296Y202820D02*
Y207820D01*
G01X1294796D02*
Y202820D01*
G01Y205320D02*
X1291296D01*
G01X1268979Y194820D02*
Y199820D01*
X1271063D01*
X1271729Y199570D01*
X1272146Y199237D01*
X1272313Y198570D01*
X1272146Y197903D01*
X1271646Y197487D01*
X1271063Y197237D01*
X1268979D01*
G01X1271063D02*
X1272313Y194820D01*
G01X1277913D02*
X1274579D01*
Y199820D01*
X1277913D01*
G01X1276579Y197403D02*
X1274579D01*
G01X1280179Y199820D02*
Y194820D01*
X1283513D01*
G01X1289113D02*
X1285779D01*
Y199820D01*
X1289113D01*
G01X1287779Y197403D02*
X1285779D01*
G01X1290963Y194820D02*
X1293046Y199820D01*
X1295129Y194820D01*
G01X1294379Y196570D02*
X1291713D01*
G01X1296896Y195487D02*
X1297563Y195070D01*
X1298313Y194820D01*
X1298979D01*
X1299646Y195070D01*
X1300146Y195487D01*
X1300396Y196070D01*
X1300229Y196653D01*
X1299813Y197153D01*
X1299063Y197487D01*
X1298063Y197653D01*
X1297479Y197987D01*
X1297229Y198570D01*
X1297396Y199153D01*
X1297813Y199570D01*
X1298396Y199820D01*
X1298979D01*
X1299563Y199653D01*
X1300063Y199237D01*
G01X1305913Y194820D02*
X1302579D01*
Y199820D01*
X1305913D01*
G01X1304579Y197403D02*
X1302579D01*
G01X1246000Y195300D02*
Y206500D01*
G01X1264000Y195300D02*
X1246000D01*
G01X1264000Y206500D02*
Y195300D01*
G01X1265750Y269500D02*
X1322250D01*
Y217500D01*
X1265750D01*
Y269500D01*
G01X1246000Y233700D02*
Y222500D01*
G01X1264000Y233700D02*
X1246000D01*
G01X1264000Y222500D02*
Y233700D01*
G01X1268270Y210511D02*
Y213011D01*
X1269270D01*
X1269603Y212886D01*
X1269853Y212594D01*
X1269936Y212261D01*
X1269853Y211928D01*
X1269645Y211678D01*
X1269270Y211553D01*
X1268270D01*
G01X1272203Y213011D02*
Y210511D01*
G01X1271245Y213011D02*
X1273161D01*
G01X1276220Y212803D02*
X1275970Y212928D01*
X1275678Y213011D01*
X1275345D01*
X1274970Y212886D01*
X1274678Y212678D01*
X1274470Y212428D01*
X1274303Y212011D01*
X1274261Y211636D01*
X1274345Y211261D01*
X1274470Y211011D01*
X1274720Y210761D01*
X1275011Y210594D01*
X1275303Y210511D01*
X1275595D01*
X1275886Y210594D01*
X1276136Y210719D01*
X1276345Y210886D01*
G01X1277486D02*
X1277736Y210678D01*
X1278028Y210553D01*
X1278403Y210511D01*
X1278778Y210594D01*
X1279070Y210761D01*
X1279278Y211053D01*
X1279320Y211386D01*
X1279236Y211719D01*
X1279028Y211928D01*
X1278736Y212094D01*
X1278445Y212136D01*
X1278153Y212094D01*
X1277778Y211928D01*
X1277903Y213011D01*
X1279028D01*
G01X1271710Y272072D02*
Y274572D01*
X1272710D01*
X1273043Y274447D01*
X1273293Y274155D01*
X1273376Y273822D01*
X1273293Y273489D01*
X1273085Y273239D01*
X1272710Y273114D01*
X1271710D01*
G01X1274810Y274572D02*
Y272072D01*
X1276476D01*
G01X1278035Y272364D02*
X1278326Y272155D01*
X1278660Y272072D01*
X1278993Y272155D01*
X1279285Y272405D01*
X1279493Y272780D01*
X1279576Y273155D01*
Y273614D01*
X1279493Y273989D01*
X1279285Y274322D01*
X1279035Y274489D01*
X1278743Y274572D01*
X1278410Y274489D01*
X1278160Y274322D01*
X1277993Y274072D01*
X1277910Y273739D01*
X1277993Y273447D01*
X1278201Y273155D01*
X1278451Y272989D01*
X1278743Y272947D01*
X1279076Y273030D01*
X1279326Y273239D01*
X1279576Y273614D01*
G01X1264000Y253300D02*
Y264500D01*
G01X1246000Y253300D02*
X1264000D01*
G01X1246000Y264500D02*
Y253300D01*
G01X1250017Y294000D02*
Y296500D01*
X1251017D01*
X1251350Y296375D01*
X1251600Y296083D01*
X1251683Y295750D01*
X1251600Y295417D01*
X1251392Y295167D01*
X1251017Y295042D01*
X1250017D01*
G01X1253950Y296500D02*
Y294000D01*
G01X1252992Y296500D02*
X1254908D01*
G01X1257967Y296292D02*
X1257717Y296417D01*
X1257425Y296500D01*
X1257092D01*
X1256717Y296375D01*
X1256425Y296167D01*
X1256217Y295917D01*
X1256050Y295500D01*
X1256008Y295125D01*
X1256092Y294750D01*
X1256217Y294500D01*
X1256467Y294250D01*
X1256758Y294083D01*
X1257050Y294000D01*
X1257342D01*
X1257633Y294083D01*
X1257883Y294208D01*
X1258092Y294375D01*
G01X1259358Y295042D02*
X1259650Y295333D01*
X1259900Y295500D01*
X1260233Y295583D01*
X1260525Y295500D01*
X1260733Y295333D01*
X1260900Y295083D01*
X1260942Y294792D01*
X1260900Y294542D01*
X1260733Y294292D01*
X1260483Y294083D01*
X1260192Y294000D01*
X1259858Y294083D01*
X1259567Y294333D01*
X1259400Y294708D01*
X1259358Y295125D01*
X1259442Y295667D01*
X1259567Y295958D01*
X1259775Y296250D01*
X1260067Y296458D01*
X1260358Y296500D01*
X1260650Y296417D01*
X1260858Y296208D01*
G01X1264000Y291700D02*
Y280500D01*
G01X1246000Y291700D02*
X1264000D01*
G01X1246000Y280500D02*
Y291700D01*
G01X1259748Y321093D02*
X1257248D01*
Y322134D01*
X1257373Y322468D01*
X1257540Y322676D01*
X1257873Y322759D01*
X1258206Y322676D01*
X1258415Y322426D01*
X1258540Y322134D01*
Y321093D01*
G01Y322134D02*
X1259748Y322759D01*
G01X1259373Y324109D02*
X1259581Y324359D01*
X1259706Y324651D01*
X1259748Y325026D01*
X1259665Y325401D01*
X1259498Y325693D01*
X1259206Y325901D01*
X1258873Y325943D01*
X1258540Y325859D01*
X1258331Y325651D01*
X1258165Y325359D01*
X1258123Y325068D01*
X1258165Y324776D01*
X1258331Y324401D01*
X1257248Y324526D01*
Y325651D01*
G01X1257665Y327334D02*
X1257415Y327584D01*
X1257290Y327876D01*
X1257248Y328209D01*
X1257331Y328626D01*
X1257540Y328918D01*
X1257790Y329001D01*
X1258040Y328959D01*
X1258248Y328793D01*
X1258665Y327959D01*
X1258956Y327584D01*
X1259373Y327334D01*
X1259748Y327251D01*
Y329001D01*
G01Y331143D02*
X1259206Y331226D01*
X1258748Y331351D01*
X1258331Y331518D01*
X1257873Y331726D01*
X1257248Y332059D01*
Y330393D01*
G01X1256500Y336800D02*
X1260500D01*
Y344200D01*
G01X1271748Y321093D02*
X1269248D01*
Y322134D01*
X1269373Y322468D01*
X1269540Y322676D01*
X1269873Y322759D01*
X1270206Y322676D01*
X1270415Y322426D01*
X1270540Y322134D01*
Y321093D01*
G01Y322134D02*
X1271748Y322759D01*
G01X1271373Y324109D02*
X1271581Y324359D01*
X1271706Y324651D01*
X1271748Y325026D01*
X1271665Y325401D01*
X1271498Y325693D01*
X1271206Y325901D01*
X1270873Y325943D01*
X1270540Y325859D01*
X1270331Y325651D01*
X1270165Y325359D01*
X1270123Y325068D01*
X1270165Y324776D01*
X1270331Y324401D01*
X1269248Y324526D01*
Y325651D01*
G01X1271373Y327209D02*
X1271581Y327459D01*
X1271706Y327751D01*
X1271748Y328126D01*
X1271665Y328501D01*
X1271498Y328793D01*
X1271206Y329001D01*
X1270873Y329043D01*
X1270540Y328959D01*
X1270331Y328751D01*
X1270165Y328459D01*
X1270123Y328168D01*
X1270165Y327876D01*
X1270331Y327501D01*
X1269248Y327626D01*
Y328751D01*
G01X1271456Y330518D02*
X1271665Y330809D01*
X1271748Y331143D01*
X1271665Y331476D01*
X1271415Y331768D01*
X1271040Y331976D01*
X1270665Y332059D01*
X1270206D01*
X1269831Y331976D01*
X1269498Y331768D01*
X1269331Y331518D01*
X1269248Y331226D01*
X1269331Y330893D01*
X1269498Y330643D01*
X1269748Y330476D01*
X1270081Y330393D01*
X1270373Y330476D01*
X1270665Y330684D01*
X1270831Y330934D01*
X1270873Y331226D01*
X1270790Y331559D01*
X1270581Y331809D01*
X1270206Y332059D01*
G01X1268500Y336800D02*
X1272500D01*
Y344200D01*
G01X1263748Y321093D02*
X1261248D01*
Y322134D01*
X1261373Y322468D01*
X1261540Y322676D01*
X1261873Y322759D01*
X1262206Y322676D01*
X1262415Y322426D01*
X1262540Y322134D01*
Y321093D01*
G01Y322134D02*
X1263748Y322759D01*
G01X1263373Y324109D02*
X1263581Y324359D01*
X1263706Y324651D01*
X1263748Y325026D01*
X1263665Y325401D01*
X1263498Y325693D01*
X1263206Y325901D01*
X1262873Y325943D01*
X1262540Y325859D01*
X1262331Y325651D01*
X1262165Y325359D01*
X1262123Y325068D01*
X1262165Y324776D01*
X1262331Y324401D01*
X1261248Y324526D01*
Y325651D01*
G01X1262706Y327334D02*
X1262415Y327626D01*
X1262248Y327876D01*
X1262165Y328209D01*
X1262248Y328501D01*
X1262415Y328709D01*
X1262665Y328876D01*
X1262956Y328918D01*
X1263206Y328876D01*
X1263456Y328709D01*
X1263665Y328459D01*
X1263748Y328168D01*
X1263665Y327834D01*
X1263415Y327543D01*
X1263040Y327376D01*
X1262623Y327334D01*
X1262081Y327418D01*
X1261790Y327543D01*
X1261498Y327751D01*
X1261290Y328043D01*
X1261248Y328334D01*
X1261331Y328626D01*
X1261540Y328834D01*
G01X1263748Y331226D02*
X1263706Y331518D01*
X1263581Y331851D01*
X1263373Y332059D01*
X1263081Y332143D01*
X1262790Y332059D01*
X1262540Y331809D01*
X1262415Y331434D01*
Y331018D01*
X1262331Y330768D01*
X1262123Y330559D01*
X1261831Y330476D01*
X1261540Y330601D01*
X1261331Y330893D01*
X1261248Y331226D01*
X1261331Y331559D01*
X1261540Y331851D01*
X1261831Y331976D01*
X1262123Y331893D01*
X1262331Y331684D01*
X1262415Y331434D01*
Y331018D01*
X1262540Y330643D01*
X1262790Y330393D01*
X1263081Y330309D01*
X1263373Y330393D01*
X1263581Y330601D01*
X1263706Y330934D01*
X1263748Y331226D01*
G01X1260500Y336800D02*
X1264500D01*
Y344200D01*
G01X1267748Y321093D02*
X1265248D01*
Y322134D01*
X1265373Y322468D01*
X1265540Y322676D01*
X1265873Y322759D01*
X1266206Y322676D01*
X1266415Y322426D01*
X1266540Y322134D01*
Y321093D01*
G01Y322134D02*
X1267748Y322759D01*
G01X1267373Y324109D02*
X1267581Y324359D01*
X1267706Y324651D01*
X1267748Y325026D01*
X1267665Y325401D01*
X1267498Y325693D01*
X1267206Y325901D01*
X1266873Y325943D01*
X1266540Y325859D01*
X1266331Y325651D01*
X1266165Y325359D01*
X1266123Y325068D01*
X1266165Y324776D01*
X1266331Y324401D01*
X1265248Y324526D01*
Y325651D01*
G01X1265665Y327334D02*
X1265415Y327584D01*
X1265290Y327876D01*
X1265248Y328209D01*
X1265331Y328626D01*
X1265540Y328918D01*
X1265790Y329001D01*
X1266040Y328959D01*
X1266248Y328793D01*
X1266665Y327959D01*
X1266956Y327584D01*
X1267373Y327334D01*
X1267748Y327251D01*
Y329001D01*
G01X1266706Y330434D02*
X1266415Y330726D01*
X1266248Y330976D01*
X1266165Y331309D01*
X1266248Y331601D01*
X1266415Y331809D01*
X1266665Y331976D01*
X1266956Y332018D01*
X1267206Y331976D01*
X1267456Y331809D01*
X1267665Y331559D01*
X1267748Y331268D01*
X1267665Y330934D01*
X1267415Y330643D01*
X1267040Y330476D01*
X1266623Y330434D01*
X1266081Y330518D01*
X1265790Y330643D01*
X1265498Y330851D01*
X1265290Y331143D01*
X1265248Y331434D01*
X1265331Y331726D01*
X1265540Y331934D01*
G01X1264500Y336800D02*
X1268500D01*
Y344200D01*
G01X1275752Y320891D02*
X1273252D01*
Y321932D01*
X1273377Y322266D01*
X1273544Y322474D01*
X1273877Y322557D01*
X1274210Y322474D01*
X1274419Y322224D01*
X1274544Y321932D01*
Y320891D01*
G01Y321932D02*
X1275752Y322557D01*
G01Y325324D02*
X1273252D01*
X1275044Y323782D01*
Y325866D01*
G01X1275752Y327924D02*
X1273252D01*
X1273752Y327424D01*
G01X1275752D02*
Y328424D01*
G01Y330941D02*
X1275210Y331024D01*
X1274752Y331149D01*
X1274335Y331316D01*
X1273877Y331524D01*
X1273252Y331857D01*
Y330191D01*
G01X1275377Y333207D02*
X1275585Y333457D01*
X1275710Y333749D01*
X1275752Y334124D01*
X1275669Y334499D01*
X1275502Y334791D01*
X1275210Y334999D01*
X1274877Y335041D01*
X1274544Y334957D01*
X1274335Y334749D01*
X1274169Y334457D01*
X1274127Y334166D01*
X1274169Y333874D01*
X1274335Y333499D01*
X1273252Y333624D01*
Y334749D01*
G01X1276500Y344200D02*
X1272500D01*
Y336800D01*
G01X1279752Y320891D02*
X1277252D01*
Y321932D01*
X1277377Y322266D01*
X1277544Y322474D01*
X1277877Y322557D01*
X1278210Y322474D01*
X1278419Y322224D01*
X1278544Y321932D01*
Y320891D01*
G01Y321932D02*
X1279752Y322557D01*
G01Y325324D02*
X1277252D01*
X1279044Y323782D01*
Y325866D01*
G01X1279752Y327924D02*
X1277252D01*
X1277752Y327424D01*
G01X1279752D02*
Y328424D01*
G01X1279377Y330107D02*
X1279585Y330357D01*
X1279710Y330649D01*
X1279752Y331024D01*
X1279669Y331399D01*
X1279502Y331691D01*
X1279210Y331899D01*
X1278877Y331941D01*
X1278544Y331857D01*
X1278335Y331649D01*
X1278169Y331357D01*
X1278127Y331066D01*
X1278169Y330774D01*
X1278335Y330399D01*
X1277252Y330524D01*
Y331649D01*
G01X1279460Y333416D02*
X1279669Y333707D01*
X1279752Y334041D01*
X1279669Y334374D01*
X1279419Y334666D01*
X1279044Y334874D01*
X1278669Y334957D01*
X1278210D01*
X1277835Y334874D01*
X1277502Y334666D01*
X1277335Y334416D01*
X1277252Y334124D01*
X1277335Y333791D01*
X1277502Y333541D01*
X1277752Y333374D01*
X1278085Y333291D01*
X1278377Y333374D01*
X1278669Y333582D01*
X1278835Y333832D01*
X1278877Y334124D01*
X1278794Y334457D01*
X1278585Y334707D01*
X1278210Y334957D01*
G01X1280500Y344200D02*
X1276500D01*
Y336800D01*
G01X1257426Y357873D02*
X1259218D01*
X1259593Y358040D01*
X1259843Y358373D01*
X1259926Y358790D01*
X1259843Y359207D01*
X1259593Y359540D01*
X1259218Y359707D01*
X1257426D01*
G01X1257843Y361098D02*
X1257593Y361348D01*
X1257468Y361640D01*
X1257426Y361973D01*
X1257509Y362390D01*
X1257718Y362682D01*
X1257968Y362765D01*
X1258218Y362723D01*
X1258426Y362557D01*
X1258843Y361723D01*
X1259134Y361348D01*
X1259551Y361098D01*
X1259926Y361015D01*
Y362765D01*
G01X1257426Y364990D02*
X1257509Y364657D01*
X1257718Y364407D01*
X1257968Y364240D01*
X1258301Y364115D01*
X1258676Y364073D01*
X1259051Y364115D01*
X1259384Y364240D01*
X1259634Y364407D01*
X1259843Y364657D01*
X1259926Y364990D01*
X1259843Y365323D01*
X1259634Y365573D01*
X1259384Y365740D01*
X1259051Y365865D01*
X1258676Y365907D01*
X1258301Y365865D01*
X1257968Y365740D01*
X1257718Y365573D01*
X1257509Y365323D01*
X1257426Y364990D01*
G01X1259426Y367173D02*
X1259718Y367423D01*
X1259884Y367757D01*
X1259926Y368132D01*
X1259884Y368465D01*
X1259676Y368798D01*
X1259426Y369007D01*
X1259176Y369048D01*
X1258884Y368965D01*
X1258676Y368673D01*
X1258593Y368382D01*
Y368007D01*
G01Y368382D02*
X1258468Y368632D01*
X1258259Y368840D01*
X1258009Y368923D01*
X1257759Y368840D01*
X1257551Y368632D01*
X1257426Y368257D01*
X1257468Y367882D01*
X1257634Y367507D01*
G01X1293400Y359400D02*
X1262700D01*
G01Y373400D02*
X1293400D01*
G01X1262700D02*
Y359400D01*
G01X1263800Y366400D02*
X1262700Y367500D01*
G01X1263800Y366400D02*
X1262700Y365300D01*
G01X1264715Y401396D02*
X1262215D01*
Y402437D01*
X1262340Y402771D01*
X1262507Y402979D01*
X1262840Y403062D01*
X1263173Y402979D01*
X1263382Y402729D01*
X1263507Y402437D01*
Y401396D01*
G01Y402437D02*
X1264715Y403062D01*
G01Y405246D02*
X1264173Y405329D01*
X1263715Y405454D01*
X1263298Y405621D01*
X1262840Y405829D01*
X1262215Y406162D01*
Y404496D01*
G01X1264423Y407721D02*
X1264632Y408012D01*
X1264715Y408346D01*
X1264632Y408679D01*
X1264382Y408971D01*
X1264007Y409179D01*
X1263632Y409262D01*
X1263173D01*
X1262798Y409179D01*
X1262465Y408971D01*
X1262298Y408721D01*
X1262215Y408429D01*
X1262298Y408096D01*
X1262465Y407846D01*
X1262715Y407679D01*
X1263048Y407596D01*
X1263340Y407679D01*
X1263632Y407887D01*
X1263798Y408137D01*
X1263840Y408429D01*
X1263757Y408762D01*
X1263548Y409012D01*
X1263173Y409262D01*
G01X1264423Y410821D02*
X1264632Y411112D01*
X1264715Y411446D01*
X1264632Y411779D01*
X1264382Y412071D01*
X1264007Y412279D01*
X1263632Y412362D01*
X1263173D01*
X1262798Y412279D01*
X1262465Y412071D01*
X1262298Y411821D01*
X1262215Y411529D01*
X1262298Y411196D01*
X1262465Y410946D01*
X1262715Y410779D01*
X1263048Y410696D01*
X1263340Y410779D01*
X1263632Y410987D01*
X1263798Y411237D01*
X1263840Y411529D01*
X1263757Y411862D01*
X1263548Y412112D01*
X1263173Y412362D01*
G01X1264715Y414629D02*
X1264673Y414921D01*
X1264548Y415254D01*
X1264340Y415462D01*
X1264048Y415546D01*
X1263757Y415462D01*
X1263507Y415212D01*
X1263382Y414837D01*
Y414421D01*
X1263298Y414171D01*
X1263090Y413962D01*
X1262798Y413879D01*
X1262507Y414004D01*
X1262298Y414296D01*
X1262215Y414629D01*
X1262298Y414962D01*
X1262507Y415254D01*
X1262798Y415379D01*
X1263090Y415296D01*
X1263298Y415087D01*
X1263382Y414837D01*
Y414421D01*
X1263507Y414046D01*
X1263757Y413796D01*
X1264048Y413712D01*
X1264340Y413796D01*
X1264548Y414004D01*
X1264673Y414337D01*
X1264715Y414629D01*
G01X1267500Y395700D02*
X1263500D01*
Y388300D01*
G01X1268715Y401446D02*
X1266215D01*
Y402487D01*
X1266340Y402821D01*
X1266507Y403029D01*
X1266840Y403112D01*
X1267173Y403029D01*
X1267382Y402779D01*
X1267507Y402487D01*
Y401446D01*
G01Y402487D02*
X1268715Y403112D01*
G01X1268340Y404462D02*
X1268548Y404712D01*
X1268673Y405004D01*
X1268715Y405379D01*
X1268632Y405754D01*
X1268465Y406046D01*
X1268173Y406254D01*
X1267840Y406296D01*
X1267507Y406212D01*
X1267298Y406004D01*
X1267132Y405712D01*
X1267090Y405421D01*
X1267132Y405129D01*
X1267298Y404754D01*
X1266215Y404879D01*
Y406004D01*
G01X1268423Y407771D02*
X1268632Y408062D01*
X1268715Y408396D01*
X1268632Y408729D01*
X1268382Y409021D01*
X1268007Y409229D01*
X1267632Y409312D01*
X1267173D01*
X1266798Y409229D01*
X1266465Y409021D01*
X1266298Y408771D01*
X1266215Y408479D01*
X1266298Y408146D01*
X1266465Y407896D01*
X1266715Y407729D01*
X1267048Y407646D01*
X1267340Y407729D01*
X1267632Y407937D01*
X1267798Y408187D01*
X1267840Y408479D01*
X1267757Y408812D01*
X1267548Y409062D01*
X1267173Y409312D01*
G01X1268215Y410662D02*
X1268507Y410912D01*
X1268673Y411246D01*
X1268715Y411621D01*
X1268673Y411954D01*
X1268465Y412287D01*
X1268215Y412496D01*
X1267965Y412537D01*
X1267673Y412454D01*
X1267465Y412162D01*
X1267382Y411871D01*
Y411496D01*
G01Y411871D02*
X1267257Y412121D01*
X1267048Y412329D01*
X1266798Y412412D01*
X1266548Y412329D01*
X1266340Y412121D01*
X1266215Y411746D01*
X1266257Y411371D01*
X1266423Y410996D01*
G01X1271500Y395700D02*
X1267500D01*
Y388300D01*
G01X1272715Y401446D02*
X1270215D01*
Y402487D01*
X1270340Y402821D01*
X1270507Y403029D01*
X1270840Y403112D01*
X1271173Y403029D01*
X1271382Y402779D01*
X1271507Y402487D01*
Y401446D01*
G01Y402487D02*
X1272715Y403112D01*
G01X1272340Y404462D02*
X1272548Y404712D01*
X1272673Y405004D01*
X1272715Y405379D01*
X1272632Y405754D01*
X1272465Y406046D01*
X1272173Y406254D01*
X1271840Y406296D01*
X1271507Y406212D01*
X1271298Y406004D01*
X1271132Y405712D01*
X1271090Y405421D01*
X1271132Y405129D01*
X1271298Y404754D01*
X1270215Y404879D01*
Y406004D01*
G01X1272715Y408479D02*
X1270215D01*
X1270715Y407979D01*
G01X1272715D02*
Y408979D01*
G01X1272215Y410662D02*
X1272507Y410912D01*
X1272673Y411246D01*
X1272715Y411621D01*
X1272673Y411954D01*
X1272465Y412287D01*
X1272215Y412496D01*
X1271965Y412537D01*
X1271673Y412454D01*
X1271465Y412162D01*
X1271382Y411871D01*
Y411496D01*
G01Y411871D02*
X1271257Y412121D01*
X1271048Y412329D01*
X1270798Y412412D01*
X1270548Y412329D01*
X1270340Y412121D01*
X1270215Y411746D01*
X1270257Y411371D01*
X1270423Y410996D01*
G01X1275500Y395700D02*
X1271500D01*
Y388300D01*
G01X1275500Y395800D02*
X1279500D01*
Y403200D01*
G01X1278458Y404891D02*
X1275958D01*
Y405932D01*
X1276083Y406266D01*
X1276250Y406474D01*
X1276583Y406557D01*
X1276916Y406474D01*
X1277125Y406224D01*
X1277250Y405932D01*
Y404891D01*
G01Y405932D02*
X1278458Y406557D01*
G01Y408741D02*
X1277916Y408824D01*
X1277458Y408949D01*
X1277041Y409116D01*
X1276583Y409324D01*
X1275958Y409657D01*
Y407991D01*
G01X1278166Y411216D02*
X1278375Y411507D01*
X1278458Y411841D01*
X1278375Y412174D01*
X1278125Y412466D01*
X1277750Y412674D01*
X1277375Y412757D01*
X1276916D01*
X1276541Y412674D01*
X1276208Y412466D01*
X1276041Y412216D01*
X1275958Y411924D01*
X1276041Y411591D01*
X1276208Y411341D01*
X1276458Y411174D01*
X1276791Y411091D01*
X1277083Y411174D01*
X1277375Y411382D01*
X1277541Y411632D01*
X1277583Y411924D01*
X1277500Y412257D01*
X1277291Y412507D01*
X1276916Y412757D01*
G01X1278166Y414316D02*
X1278375Y414607D01*
X1278458Y414941D01*
X1278375Y415274D01*
X1278125Y415566D01*
X1277750Y415774D01*
X1277375Y415857D01*
X1276916D01*
X1276541Y415774D01*
X1276208Y415566D01*
X1276041Y415316D01*
X1275958Y415024D01*
X1276041Y414691D01*
X1276208Y414441D01*
X1276458Y414274D01*
X1276791Y414191D01*
X1277083Y414274D01*
X1277375Y414482D01*
X1277541Y414732D01*
X1277583Y415024D01*
X1277500Y415357D01*
X1277291Y415607D01*
X1276916Y415857D01*
G01X1275958Y418124D02*
X1276041Y417791D01*
X1276250Y417541D01*
X1276500Y417374D01*
X1276833Y417249D01*
X1277208Y417207D01*
X1277583Y417249D01*
X1277916Y417374D01*
X1278166Y417541D01*
X1278375Y417791D01*
X1278458Y418124D01*
X1278375Y418457D01*
X1278166Y418707D01*
X1277916Y418874D01*
X1277583Y418999D01*
X1277208Y419041D01*
X1276833Y418999D01*
X1276500Y418874D01*
X1276250Y418707D01*
X1276041Y418457D01*
X1275958Y418124D01*
G01X1275500Y388300D02*
X1279500D01*
Y395700D01*
G01X1260715Y401396D02*
X1258215D01*
Y402437D01*
X1258340Y402771D01*
X1258507Y402979D01*
X1258840Y403062D01*
X1259173Y402979D01*
X1259382Y402729D01*
X1259507Y402437D01*
Y401396D01*
G01Y402437D02*
X1260715Y403062D01*
G01Y405246D02*
X1260173Y405329D01*
X1259715Y405454D01*
X1259298Y405621D01*
X1258840Y405829D01*
X1258215Y406162D01*
Y404496D01*
G01X1260423Y407721D02*
X1260632Y408012D01*
X1260715Y408346D01*
X1260632Y408679D01*
X1260382Y408971D01*
X1260007Y409179D01*
X1259632Y409262D01*
X1259173D01*
X1258798Y409179D01*
X1258465Y408971D01*
X1258298Y408721D01*
X1258215Y408429D01*
X1258298Y408096D01*
X1258465Y407846D01*
X1258715Y407679D01*
X1259048Y407596D01*
X1259340Y407679D01*
X1259632Y407887D01*
X1259798Y408137D01*
X1259840Y408429D01*
X1259757Y408762D01*
X1259548Y409012D01*
X1259173Y409262D01*
G01X1260715Y411529D02*
X1258215D01*
X1258715Y411029D01*
G01X1260715D02*
Y412029D01*
G01Y415129D02*
X1258215D01*
X1260007Y413587D01*
Y415671D01*
G01X1263500Y395700D02*
X1259500D01*
Y388300D01*
G01X1254423Y403146D02*
X1254298Y402896D01*
X1254215Y402604D01*
Y402271D01*
X1254340Y401896D01*
X1254548Y401604D01*
X1254798Y401396D01*
X1255215Y401229D01*
X1255590Y401187D01*
X1255965Y401271D01*
X1256215Y401396D01*
X1256465Y401646D01*
X1256632Y401937D01*
X1256715Y402229D01*
Y402521D01*
X1256632Y402812D01*
X1256507Y403062D01*
X1256340Y403271D01*
G01X1256215Y404412D02*
X1256507Y404662D01*
X1256673Y404996D01*
X1256715Y405371D01*
X1256673Y405704D01*
X1256465Y406037D01*
X1256215Y406246D01*
X1255965Y406287D01*
X1255673Y406204D01*
X1255465Y405912D01*
X1255382Y405621D01*
Y405246D01*
G01Y405621D02*
X1255257Y405871D01*
X1255048Y406079D01*
X1254798Y406162D01*
X1254548Y406079D01*
X1254340Y405871D01*
X1254215Y405496D01*
X1254257Y405121D01*
X1254423Y404746D01*
G01X1256715Y408346D02*
X1256173Y408429D01*
X1255715Y408554D01*
X1255298Y408721D01*
X1254840Y408929D01*
X1254215Y409262D01*
Y407596D01*
G01Y411529D02*
X1254298Y411196D01*
X1254507Y410946D01*
X1254757Y410779D01*
X1255090Y410654D01*
X1255465Y410612D01*
X1255840Y410654D01*
X1256173Y410779D01*
X1256423Y410946D01*
X1256632Y411196D01*
X1256715Y411529D01*
X1256632Y411862D01*
X1256423Y412112D01*
X1256173Y412279D01*
X1255840Y412404D01*
X1255465Y412446D01*
X1255090Y412404D01*
X1254757Y412279D01*
X1254507Y412112D01*
X1254298Y411862D01*
X1254215Y411529D01*
G01X1254632Y413837D02*
X1254382Y414087D01*
X1254257Y414379D01*
X1254215Y414712D01*
X1254298Y415129D01*
X1254507Y415421D01*
X1254757Y415504D01*
X1255007Y415462D01*
X1255215Y415296D01*
X1255632Y414462D01*
X1255923Y414087D01*
X1256340Y413837D01*
X1256715Y413754D01*
Y415504D01*
G01X1250423Y403146D02*
X1250298Y402896D01*
X1250215Y402604D01*
Y402271D01*
X1250340Y401896D01*
X1250548Y401604D01*
X1250798Y401396D01*
X1251215Y401229D01*
X1251590Y401187D01*
X1251965Y401271D01*
X1252215Y401396D01*
X1252465Y401646D01*
X1252632Y401937D01*
X1252715Y402229D01*
Y402521D01*
X1252632Y402812D01*
X1252507Y403062D01*
X1252340Y403271D01*
G01X1252215Y404412D02*
X1252507Y404662D01*
X1252673Y404996D01*
X1252715Y405371D01*
X1252673Y405704D01*
X1252465Y406037D01*
X1252215Y406246D01*
X1251965Y406287D01*
X1251673Y406204D01*
X1251465Y405912D01*
X1251382Y405621D01*
Y405246D01*
G01Y405621D02*
X1251257Y405871D01*
X1251048Y406079D01*
X1250798Y406162D01*
X1250548Y406079D01*
X1250340Y405871D01*
X1250215Y405496D01*
X1250257Y405121D01*
X1250423Y404746D01*
G01X1252715Y408346D02*
X1252173Y408429D01*
X1251715Y408554D01*
X1251298Y408721D01*
X1250840Y408929D01*
X1250215Y409262D01*
Y407596D01*
G01Y411529D02*
X1250298Y411196D01*
X1250507Y410946D01*
X1250757Y410779D01*
X1251090Y410654D01*
X1251465Y410612D01*
X1251840Y410654D01*
X1252173Y410779D01*
X1252423Y410946D01*
X1252632Y411196D01*
X1252715Y411529D01*
X1252632Y411862D01*
X1252423Y412112D01*
X1252173Y412279D01*
X1251840Y412404D01*
X1251465Y412446D01*
X1251090Y412404D01*
X1250757Y412279D01*
X1250507Y412112D01*
X1250298Y411862D01*
X1250215Y411529D01*
G01X1252715Y414629D02*
X1250215D01*
X1250715Y414129D01*
G01X1252715D02*
Y415129D01*
G01X1278445Y420950D02*
X1275945D01*
Y421991D01*
X1276070Y422325D01*
X1276237Y422533D01*
X1276570Y422616D01*
X1276903Y422533D01*
X1277112Y422283D01*
X1277237Y421991D01*
Y420950D01*
G01Y421991D02*
X1278445Y422616D01*
G01Y425383D02*
X1275945D01*
X1277737Y423841D01*
Y425925D01*
G01X1278445Y427983D02*
X1275945D01*
X1276445Y427483D01*
G01X1278445D02*
Y428483D01*
G01Y431000D02*
X1277903Y431083D01*
X1277445Y431208D01*
X1277028Y431375D01*
X1276570Y431583D01*
X1275945Y431916D01*
Y430250D01*
G01X1278445Y434183D02*
X1278403Y434475D01*
X1278278Y434808D01*
X1278070Y435016D01*
X1277778Y435100D01*
X1277487Y435016D01*
X1277237Y434766D01*
X1277112Y434391D01*
Y433975D01*
X1277028Y433725D01*
X1276820Y433516D01*
X1276528Y433433D01*
X1276237Y433558D01*
X1276028Y433850D01*
X1275945Y434183D01*
X1276028Y434516D01*
X1276237Y434808D01*
X1276528Y434933D01*
X1276820Y434850D01*
X1277028Y434641D01*
X1277112Y434391D01*
Y433975D01*
X1277237Y433600D01*
X1277487Y433350D01*
X1277778Y433266D01*
X1278070Y433350D01*
X1278278Y433558D01*
X1278403Y433891D01*
X1278445Y434183D01*
G01X1249171Y818195D02*
X1249046Y817945D01*
X1248963Y817653D01*
Y817320D01*
X1249088Y816945D01*
X1249296Y816653D01*
X1249546Y816445D01*
X1249963Y816278D01*
X1250338Y816236D01*
X1250713Y816320D01*
X1250963Y816445D01*
X1251213Y816695D01*
X1251380Y816986D01*
X1251463Y817278D01*
Y817570D01*
X1251380Y817861D01*
X1251255Y818111D01*
X1251088Y818320D01*
G01X1250421Y819586D02*
X1250130Y819878D01*
X1249963Y820128D01*
X1249880Y820461D01*
X1249963Y820753D01*
X1250130Y820961D01*
X1250380Y821128D01*
X1250671Y821170D01*
X1250921Y821128D01*
X1251171Y820961D01*
X1251380Y820711D01*
X1251463Y820420D01*
X1251380Y820086D01*
X1251130Y819795D01*
X1250755Y819628D01*
X1250338Y819586D01*
X1249796Y819670D01*
X1249505Y819795D01*
X1249213Y820003D01*
X1249005Y820295D01*
X1248963Y820586D01*
X1249046Y820878D01*
X1249255Y821086D01*
G01X1251171Y822770D02*
X1251380Y823061D01*
X1251463Y823395D01*
X1251380Y823728D01*
X1251130Y824020D01*
X1250755Y824228D01*
X1250380Y824311D01*
X1249921D01*
X1249546Y824228D01*
X1249213Y824020D01*
X1249046Y823770D01*
X1248963Y823478D01*
X1249046Y823145D01*
X1249213Y822895D01*
X1249463Y822728D01*
X1249796Y822645D01*
X1250088Y822728D01*
X1250380Y822936D01*
X1250546Y823186D01*
X1250588Y823478D01*
X1250505Y823811D01*
X1250296Y824061D01*
X1249921Y824311D01*
G01X1245171Y818195D02*
X1245046Y817945D01*
X1244963Y817653D01*
Y817320D01*
X1245088Y816945D01*
X1245296Y816653D01*
X1245546Y816445D01*
X1245963Y816278D01*
X1246338Y816236D01*
X1246713Y816320D01*
X1246963Y816445D01*
X1247213Y816695D01*
X1247380Y816986D01*
X1247463Y817278D01*
Y817570D01*
X1247380Y817861D01*
X1247255Y818111D01*
X1247088Y818320D01*
G01X1246421Y819586D02*
X1246130Y819878D01*
X1245963Y820128D01*
X1245880Y820461D01*
X1245963Y820753D01*
X1246130Y820961D01*
X1246380Y821128D01*
X1246671Y821170D01*
X1246921Y821128D01*
X1247171Y820961D01*
X1247380Y820711D01*
X1247463Y820420D01*
X1247380Y820086D01*
X1247130Y819795D01*
X1246755Y819628D01*
X1246338Y819586D01*
X1245796Y819670D01*
X1245505Y819795D01*
X1245213Y820003D01*
X1245005Y820295D01*
X1244963Y820586D01*
X1245046Y820878D01*
X1245255Y821086D01*
G01X1247463Y823478D02*
X1247421Y823770D01*
X1247296Y824103D01*
X1247088Y824311D01*
X1246796Y824395D01*
X1246505Y824311D01*
X1246255Y824061D01*
X1246130Y823686D01*
Y823270D01*
X1246046Y823020D01*
X1245838Y822811D01*
X1245546Y822728D01*
X1245255Y822853D01*
X1245046Y823145D01*
X1244963Y823478D01*
X1245046Y823811D01*
X1245255Y824103D01*
X1245546Y824228D01*
X1245838Y824145D01*
X1246046Y823936D01*
X1246130Y823686D01*
Y823270D01*
X1246255Y822895D01*
X1246505Y822645D01*
X1246796Y822561D01*
X1247088Y822645D01*
X1247296Y822853D01*
X1247421Y823186D01*
X1247463Y823478D01*
G01X1257770Y818195D02*
X1257645Y817945D01*
X1257562Y817653D01*
Y817320D01*
X1257687Y816945D01*
X1257895Y816653D01*
X1258145Y816445D01*
X1258562Y816278D01*
X1258937Y816236D01*
X1259312Y816320D01*
X1259562Y816445D01*
X1259812Y816695D01*
X1259979Y816986D01*
X1260062Y817278D01*
Y817570D01*
X1259979Y817861D01*
X1259854Y818111D01*
X1259687Y818320D01*
G01X1259020Y819586D02*
X1258729Y819878D01*
X1258562Y820128D01*
X1258479Y820461D01*
X1258562Y820753D01*
X1258729Y820961D01*
X1258979Y821128D01*
X1259270Y821170D01*
X1259520Y821128D01*
X1259770Y820961D01*
X1259979Y820711D01*
X1260062Y820420D01*
X1259979Y820086D01*
X1259729Y819795D01*
X1259354Y819628D01*
X1258937Y819586D01*
X1258395Y819670D01*
X1258104Y819795D01*
X1257812Y820003D01*
X1257604Y820295D01*
X1257562Y820586D01*
X1257645Y820878D01*
X1257854Y821086D01*
G01X1260062Y823395D02*
X1259520Y823478D01*
X1259062Y823603D01*
X1258645Y823770D01*
X1258187Y823978D01*
X1257562Y824311D01*
Y822645D01*
G01X1261770Y818195D02*
X1261645Y817945D01*
X1261562Y817653D01*
Y817320D01*
X1261687Y816945D01*
X1261895Y816653D01*
X1262145Y816445D01*
X1262562Y816278D01*
X1262937Y816236D01*
X1263312Y816320D01*
X1263562Y816445D01*
X1263812Y816695D01*
X1263979Y816986D01*
X1264062Y817278D01*
Y817570D01*
X1263979Y817861D01*
X1263854Y818111D01*
X1263687Y818320D01*
G01X1263020Y819586D02*
X1262729Y819878D01*
X1262562Y820128D01*
X1262479Y820461D01*
X1262562Y820753D01*
X1262729Y820961D01*
X1262979Y821128D01*
X1263270Y821170D01*
X1263520Y821128D01*
X1263770Y820961D01*
X1263979Y820711D01*
X1264062Y820420D01*
X1263979Y820086D01*
X1263729Y819795D01*
X1263354Y819628D01*
X1262937Y819586D01*
X1262395Y819670D01*
X1262104Y819795D01*
X1261812Y820003D01*
X1261604Y820295D01*
X1261562Y820586D01*
X1261645Y820878D01*
X1261854Y821086D01*
G01X1263020Y822686D02*
X1262729Y822978D01*
X1262562Y823228D01*
X1262479Y823561D01*
X1262562Y823853D01*
X1262729Y824061D01*
X1262979Y824228D01*
X1263270Y824270D01*
X1263520Y824228D01*
X1263770Y824061D01*
X1263979Y823811D01*
X1264062Y823520D01*
X1263979Y823186D01*
X1263729Y822895D01*
X1263354Y822728D01*
X1262937Y822686D01*
X1262395Y822770D01*
X1262104Y822895D01*
X1261812Y823103D01*
X1261604Y823395D01*
X1261562Y823686D01*
X1261645Y823978D01*
X1261854Y824186D01*
G01X1274368Y818195D02*
X1274243Y817945D01*
X1274160Y817653D01*
Y817320D01*
X1274285Y816945D01*
X1274493Y816653D01*
X1274743Y816445D01*
X1275160Y816278D01*
X1275535Y816236D01*
X1275910Y816320D01*
X1276160Y816445D01*
X1276410Y816695D01*
X1276577Y816986D01*
X1276660Y817278D01*
Y817570D01*
X1276577Y817861D01*
X1276452Y818111D01*
X1276285Y818320D01*
G01X1275618Y819586D02*
X1275327Y819878D01*
X1275160Y820128D01*
X1275077Y820461D01*
X1275160Y820753D01*
X1275327Y820961D01*
X1275577Y821128D01*
X1275868Y821170D01*
X1276118Y821128D01*
X1276368Y820961D01*
X1276577Y820711D01*
X1276660Y820420D01*
X1276577Y820086D01*
X1276327Y819795D01*
X1275952Y819628D01*
X1275535Y819586D01*
X1274993Y819670D01*
X1274702Y819795D01*
X1274410Y820003D01*
X1274202Y820295D01*
X1274160Y820586D01*
X1274243Y820878D01*
X1274452Y821086D01*
G01X1276285Y822561D02*
X1276493Y822811D01*
X1276618Y823103D01*
X1276660Y823478D01*
X1276577Y823853D01*
X1276410Y824145D01*
X1276118Y824353D01*
X1275785Y824395D01*
X1275452Y824311D01*
X1275243Y824103D01*
X1275077Y823811D01*
X1275035Y823520D01*
X1275077Y823228D01*
X1275243Y822853D01*
X1274160Y822978D01*
Y824103D01*
G01X1270368Y818195D02*
X1270243Y817945D01*
X1270160Y817653D01*
Y817320D01*
X1270285Y816945D01*
X1270493Y816653D01*
X1270743Y816445D01*
X1271160Y816278D01*
X1271535Y816236D01*
X1271910Y816320D01*
X1272160Y816445D01*
X1272410Y816695D01*
X1272577Y816986D01*
X1272660Y817278D01*
Y817570D01*
X1272577Y817861D01*
X1272452Y818111D01*
X1272285Y818320D01*
G01X1271618Y819586D02*
X1271327Y819878D01*
X1271160Y820128D01*
X1271077Y820461D01*
X1271160Y820753D01*
X1271327Y820961D01*
X1271577Y821128D01*
X1271868Y821170D01*
X1272118Y821128D01*
X1272368Y820961D01*
X1272577Y820711D01*
X1272660Y820420D01*
X1272577Y820086D01*
X1272327Y819795D01*
X1271952Y819628D01*
X1271535Y819586D01*
X1270993Y819670D01*
X1270702Y819795D01*
X1270410Y820003D01*
X1270202Y820295D01*
X1270160Y820586D01*
X1270243Y820878D01*
X1270452Y821086D01*
G01X1272660Y823978D02*
X1270160D01*
X1271952Y822436D01*
Y824520D01*
G01X1309001Y5675D02*
X1309209Y6008D01*
X1309334Y6383D01*
Y6717D01*
X1309209Y7050D01*
X1309001Y7300D01*
X1308709Y7425D01*
X1308417Y7342D01*
X1308167Y7133D01*
X1308001Y6758D01*
X1307917Y6258D01*
X1307751Y5967D01*
X1307459Y5842D01*
X1307167Y5925D01*
X1306959Y6133D01*
X1306834Y6425D01*
Y6717D01*
X1306917Y7008D01*
X1307126Y7258D01*
G01X1309334Y8817D02*
X1306834D01*
Y9858D01*
X1306959Y10192D01*
X1307126Y10400D01*
X1307459Y10483D01*
X1307792Y10400D01*
X1308001Y10150D01*
X1308126Y9858D01*
Y8817D01*
G01Y9858D02*
X1309334Y10483D01*
G01Y12667D02*
X1308792Y12750D01*
X1308334Y12875D01*
X1307917Y13042D01*
X1307459Y13250D01*
X1306834Y13583D01*
Y11917D01*
G01X1309334Y15850D02*
X1306834D01*
X1307334Y15350D01*
G01X1309334D02*
Y16350D01*
G01X1308834Y18033D02*
X1309126Y18283D01*
X1309292Y18617D01*
X1309334Y18992D01*
X1309292Y19325D01*
X1309084Y19658D01*
X1308834Y19867D01*
X1308584Y19908D01*
X1308292Y19825D01*
X1308084Y19533D01*
X1308001Y19242D01*
Y18867D01*
G01Y19242D02*
X1307876Y19492D01*
X1307667Y19700D01*
X1307417Y19783D01*
X1307167Y19700D01*
X1306959Y19492D01*
X1306834Y19117D01*
X1306876Y18742D01*
X1307042Y18367D01*
G01X1297067Y-10159D02*
X1299567D01*
Y-8493D01*
G01Y-5393D02*
Y-7059D01*
X1297067D01*
Y-5393D01*
G01X1298275Y-6059D02*
Y-7059D01*
G01X1299567Y-4043D02*
X1297067D01*
Y-3209D01*
X1297192Y-2876D01*
X1297359Y-2626D01*
X1297609Y-2418D01*
X1297900Y-2251D01*
X1298317Y-2209D01*
X1298734Y-2251D01*
X1299025Y-2418D01*
X1299275Y-2626D01*
X1299442Y-2876D01*
X1299567Y-3209D01*
Y-4043D01*
G01Y-26D02*
X1297067D01*
X1297567Y-526D01*
G01X1299567D02*
Y474D01*
G01X1298525Y2282D02*
X1298234Y2574D01*
X1298067Y2824D01*
X1297984Y3157D01*
X1298067Y3449D01*
X1298234Y3657D01*
X1298484Y3824D01*
X1298775Y3866D01*
X1299025Y3824D01*
X1299275Y3657D01*
X1299484Y3407D01*
X1299567Y3116D01*
X1299484Y2782D01*
X1299234Y2491D01*
X1298859Y2324D01*
X1298442Y2282D01*
X1297900Y2366D01*
X1297609Y2491D01*
X1297317Y2699D01*
X1297109Y2991D01*
X1297067Y3282D01*
X1297150Y3574D01*
X1297359Y3782D01*
G01X1294206Y10474D02*
X1305006D01*
Y5274D01*
X1294206D01*
Y10474D01*
G01X1306000Y18200D02*
X1302000D01*
Y10800D01*
G01X1309167Y28925D02*
X1309375Y29258D01*
X1309500Y29633D01*
Y29967D01*
X1309375Y30300D01*
X1309167Y30550D01*
X1308875Y30675D01*
X1308583Y30592D01*
X1308333Y30383D01*
X1308167Y30008D01*
X1308083Y29508D01*
X1307917Y29217D01*
X1307625Y29092D01*
X1307333Y29175D01*
X1307125Y29383D01*
X1307000Y29675D01*
Y29967D01*
X1307083Y30258D01*
X1307292Y30508D01*
G01X1309500Y32067D02*
X1307000D01*
Y33108D01*
X1307125Y33442D01*
X1307292Y33650D01*
X1307625Y33733D01*
X1307958Y33650D01*
X1308167Y33400D01*
X1308292Y33108D01*
Y32067D01*
G01Y33108D02*
X1309500Y33733D01*
G01Y35917D02*
X1308958Y36000D01*
X1308500Y36125D01*
X1308083Y36292D01*
X1307625Y36500D01*
X1307000Y36833D01*
Y35167D01*
G01X1309500Y39100D02*
X1307000D01*
X1307500Y38600D01*
G01X1309500D02*
Y39600D01*
G01X1307417Y41408D02*
X1307167Y41658D01*
X1307042Y41950D01*
X1307000Y42283D01*
X1307083Y42700D01*
X1307292Y42992D01*
X1307542Y43075D01*
X1307792Y43033D01*
X1308000Y42867D01*
X1308417Y42033D01*
X1308708Y41658D01*
X1309125Y41408D01*
X1309500Y41325D01*
Y43075D01*
G01X1306000Y41700D02*
X1302000D01*
Y34300D01*
G01X1295967Y26500D02*
Y24000D01*
X1297633D01*
G01X1300733D02*
X1299067D01*
Y26500D01*
X1300733D01*
G01X1300067Y25292D02*
X1299067D01*
G01X1302083Y24000D02*
Y26500D01*
X1302917D01*
X1303250Y26375D01*
X1303500Y26208D01*
X1303708Y25958D01*
X1303875Y25667D01*
X1303917Y25250D01*
X1303875Y24833D01*
X1303708Y24542D01*
X1303500Y24292D01*
X1303250Y24125D01*
X1302917Y24000D01*
X1302083D01*
G01X1306100D02*
Y26500D01*
X1305600Y26000D01*
G01Y24000D02*
X1306600D01*
G01X1308283Y24375D02*
X1308533Y24167D01*
X1308825Y24042D01*
X1309200Y24000D01*
X1309575Y24083D01*
X1309867Y24250D01*
X1310075Y24542D01*
X1310117Y24875D01*
X1310033Y25208D01*
X1309825Y25417D01*
X1309533Y25583D01*
X1309242Y25625D01*
X1308950Y25583D01*
X1308575Y25417D01*
X1308700Y26500D01*
X1309825D01*
G01X1294206Y34096D02*
X1305006D01*
Y28896D01*
X1294206D01*
Y34096D01*
G01X1309167Y51925D02*
X1309375Y52258D01*
X1309500Y52633D01*
Y52967D01*
X1309375Y53300D01*
X1309167Y53550D01*
X1308875Y53675D01*
X1308583Y53592D01*
X1308333Y53383D01*
X1308167Y53008D01*
X1308083Y52508D01*
X1307917Y52217D01*
X1307625Y52092D01*
X1307333Y52175D01*
X1307125Y52383D01*
X1307000Y52675D01*
Y52967D01*
X1307083Y53258D01*
X1307292Y53508D01*
G01X1309500Y55067D02*
X1307000D01*
Y56108D01*
X1307125Y56442D01*
X1307292Y56650D01*
X1307625Y56733D01*
X1307958Y56650D01*
X1308167Y56400D01*
X1308292Y56108D01*
Y55067D01*
G01Y56108D02*
X1309500Y56733D01*
G01Y58917D02*
X1308958Y59000D01*
X1308500Y59125D01*
X1308083Y59292D01*
X1307625Y59500D01*
X1307000Y59833D01*
Y58167D01*
G01X1309500Y62100D02*
X1307000D01*
X1307500Y61600D01*
G01X1309500D02*
Y62600D01*
G01X1309125Y64283D02*
X1309333Y64533D01*
X1309458Y64825D01*
X1309500Y65200D01*
X1309417Y65575D01*
X1309250Y65867D01*
X1308958Y66075D01*
X1308625Y66117D01*
X1308292Y66033D01*
X1308083Y65825D01*
X1307917Y65533D01*
X1307875Y65242D01*
X1307917Y64950D01*
X1308083Y64575D01*
X1307000Y64700D01*
Y65825D01*
G01X1306000Y65200D02*
X1302000D01*
Y57800D01*
G01X1295967Y50500D02*
Y48000D01*
X1297633D01*
G01X1300733D02*
X1299067D01*
Y50500D01*
X1300733D01*
G01X1300067Y49292D02*
X1299067D01*
G01X1302083Y48000D02*
Y50500D01*
X1302917D01*
X1303250Y50375D01*
X1303500Y50208D01*
X1303708Y49958D01*
X1303875Y49667D01*
X1303917Y49250D01*
X1303875Y48833D01*
X1303708Y48542D01*
X1303500Y48292D01*
X1303250Y48125D01*
X1302917Y48000D01*
X1302083D01*
G01X1306100D02*
Y50500D01*
X1305600Y50000D01*
G01Y48000D02*
X1306600D01*
G01X1308283Y48500D02*
X1308533Y48208D01*
X1308867Y48042D01*
X1309242Y48000D01*
X1309575Y48042D01*
X1309908Y48250D01*
X1310117Y48500D01*
X1310158Y48750D01*
X1310075Y49042D01*
X1309783Y49250D01*
X1309492Y49333D01*
X1309117D01*
G01X1309492D02*
X1309742Y49458D01*
X1309950Y49667D01*
X1310033Y49917D01*
X1309950Y50167D01*
X1309742Y50375D01*
X1309367Y50500D01*
X1308992Y50458D01*
X1308617Y50292D01*
G01X1294206Y57718D02*
X1305006D01*
Y52518D01*
X1294206D01*
Y57718D01*
G01X1296467Y74000D02*
Y71500D01*
X1298133D01*
G01X1301233D02*
X1299567D01*
Y74000D01*
X1301233D01*
G01X1300567Y72792D02*
X1299567D01*
G01X1302583Y71500D02*
Y74000D01*
X1303417D01*
X1303750Y73875D01*
X1304000Y73708D01*
X1304208Y73458D01*
X1304375Y73167D01*
X1304417Y72750D01*
X1304375Y72333D01*
X1304208Y72042D01*
X1304000Y71792D01*
X1303750Y71625D01*
X1303417Y71500D01*
X1302583D01*
G01X1306600D02*
Y74000D01*
X1306100Y73500D01*
G01Y71500D02*
X1307100D01*
G01X1308908Y73583D02*
X1309158Y73833D01*
X1309450Y73958D01*
X1309783Y74000D01*
X1310200Y73917D01*
X1310492Y73708D01*
X1310575Y73458D01*
X1310533Y73208D01*
X1310367Y73000D01*
X1309533Y72583D01*
X1309158Y72292D01*
X1308908Y71875D01*
X1308825Y71500D01*
X1310575D01*
G01X1309667Y76425D02*
X1309875Y76758D01*
X1310000Y77133D01*
Y77467D01*
X1309875Y77800D01*
X1309667Y78050D01*
X1309375Y78175D01*
X1309083Y78092D01*
X1308833Y77883D01*
X1308667Y77508D01*
X1308583Y77008D01*
X1308417Y76717D01*
X1308125Y76592D01*
X1307833Y76675D01*
X1307625Y76883D01*
X1307500Y77175D01*
Y77467D01*
X1307583Y77758D01*
X1307792Y78008D01*
G01X1310000Y79567D02*
X1307500D01*
Y80608D01*
X1307625Y80942D01*
X1307792Y81150D01*
X1308125Y81233D01*
X1308458Y81150D01*
X1308667Y80900D01*
X1308792Y80608D01*
Y79567D01*
G01Y80608D02*
X1310000Y81233D01*
G01Y83417D02*
X1309458Y83500D01*
X1309000Y83625D01*
X1308583Y83792D01*
X1308125Y84000D01*
X1307500Y84333D01*
Y82667D01*
G01X1310000Y86600D02*
X1307500D01*
X1308000Y86100D01*
G01X1310000D02*
Y87100D01*
G01Y90200D02*
X1307500D01*
X1309292Y88658D01*
Y90742D01*
G01X1306000Y88700D02*
X1302000D01*
Y81300D01*
G01X1294206Y81340D02*
X1305006D01*
Y76140D01*
X1294206D01*
Y81340D01*
G01X1299017Y94667D02*
Y97167D01*
X1300017D01*
X1300350Y97042D01*
X1300600Y96750D01*
X1300683Y96417D01*
X1300600Y96084D01*
X1300392Y95834D01*
X1300017Y95709D01*
X1299017D01*
G01X1301908Y94667D02*
X1302950Y97167D01*
X1303992Y94667D01*
G01X1303617Y95542D02*
X1302283D01*
G01X1305133Y94667D02*
Y97167D01*
X1305967D01*
X1306300Y97042D01*
X1306550Y96875D01*
X1306758Y96625D01*
X1306925Y96334D01*
X1306967Y95917D01*
X1306925Y95500D01*
X1306758Y95209D01*
X1306550Y94959D01*
X1306300Y94792D01*
X1305967Y94667D01*
X1305133D01*
G01X1308233Y95167D02*
X1308483Y94875D01*
X1308817Y94709D01*
X1309192Y94667D01*
X1309525Y94709D01*
X1309858Y94917D01*
X1310067Y95167D01*
X1310108Y95417D01*
X1310025Y95709D01*
X1309733Y95917D01*
X1309442Y96000D01*
X1309067D01*
G01X1309442D02*
X1309692Y96125D01*
X1309900Y96334D01*
X1309983Y96584D01*
X1309900Y96834D01*
X1309692Y97042D01*
X1309317Y97167D01*
X1308942Y97125D01*
X1308567Y96959D01*
G01X1291583Y138500D02*
X1294500Y146500D01*
X1297417Y138500D01*
G01X1296367Y141300D02*
X1292633D01*
G01X1293000Y125000D02*
X1286500D01*
G01X1297000D02*
X1296000D01*
G01X1299000Y127500D02*
Y125000D01*
X1297000D01*
G01X1301517Y125091D02*
Y127591D01*
X1302558D01*
X1302892Y127466D01*
X1303100Y127299D01*
X1303183Y126966D01*
X1303100Y126633D01*
X1302850Y126424D01*
X1302558Y126299D01*
X1301517D01*
G01X1302558D02*
X1303183Y125091D01*
G01X1304658Y126133D02*
X1304950Y126424D01*
X1305200Y126591D01*
X1305533Y126674D01*
X1305825Y126591D01*
X1306033Y126424D01*
X1306200Y126174D01*
X1306242Y125883D01*
X1306200Y125633D01*
X1306033Y125383D01*
X1305783Y125174D01*
X1305492Y125091D01*
X1305158Y125174D01*
X1304867Y125424D01*
X1304700Y125799D01*
X1304658Y126216D01*
X1304742Y126758D01*
X1304867Y127049D01*
X1305075Y127341D01*
X1305367Y127549D01*
X1305658Y127591D01*
X1305950Y127508D01*
X1306158Y127299D01*
G01X1307758Y127174D02*
X1308008Y127424D01*
X1308300Y127549D01*
X1308633Y127591D01*
X1309050Y127508D01*
X1309342Y127299D01*
X1309425Y127049D01*
X1309383Y126799D01*
X1309217Y126591D01*
X1308383Y126174D01*
X1308008Y125883D01*
X1307758Y125466D01*
X1307675Y125091D01*
X1309425D01*
G01X1310733Y125466D02*
X1310983Y125258D01*
X1311275Y125133D01*
X1311650Y125091D01*
X1312025Y125174D01*
X1312317Y125341D01*
X1312525Y125633D01*
X1312567Y125966D01*
X1312483Y126299D01*
X1312275Y126508D01*
X1311983Y126674D01*
X1311692Y126716D01*
X1311400Y126674D01*
X1311025Y126508D01*
X1311150Y127591D01*
X1312275D01*
G01X1304400Y120986D02*
X1304067Y121028D01*
X1303775Y121194D01*
X1303525Y121444D01*
X1303358Y121736D01*
X1303275Y122069D01*
Y122403D01*
X1303358Y122736D01*
X1303525Y123028D01*
X1303775Y123278D01*
X1304067Y123444D01*
X1304400Y123486D01*
X1304733Y123444D01*
X1305025Y123278D01*
X1305275Y123028D01*
X1305442Y122736D01*
X1305525Y122403D01*
Y122069D01*
X1305442Y121736D01*
X1305275Y121444D01*
X1305025Y121194D01*
X1304733Y121028D01*
X1304400Y120986D01*
G01X1304733Y121653D02*
X1305233Y120986D01*
G01X1306583Y121486D02*
X1306833Y121194D01*
X1307167Y121028D01*
X1307542Y120986D01*
X1307875Y121028D01*
X1308208Y121236D01*
X1308417Y121486D01*
X1308458Y121736D01*
X1308375Y122028D01*
X1308083Y122236D01*
X1307792Y122319D01*
X1307417D01*
G01X1307792D02*
X1308042Y122444D01*
X1308250Y122653D01*
X1308333Y122903D01*
X1308250Y123153D01*
X1308042Y123361D01*
X1307667Y123486D01*
X1307292Y123444D01*
X1306917Y123278D01*
G01X1310600Y120986D02*
Y123486D01*
X1310100Y122986D01*
G01Y120986D02*
X1311100D01*
G01X1303720Y128810D02*
X1317720D01*
G01X1303720Y141810D02*
Y128810D01*
G01X1307020Y167693D02*
Y170693D01*
X1287120D01*
Y186493D01*
X1315120D01*
Y172293D01*
X1311820D01*
Y167693D01*
X1307020D01*
G01X1308110Y147310D02*
Y143310D01*
X1315510D01*
G01X1313167Y154680D02*
X1310667D01*
Y155721D01*
X1310792Y156055D01*
X1310959Y156263D01*
X1311292Y156346D01*
X1311625Y156263D01*
X1311834Y156013D01*
X1311959Y155721D01*
Y154680D01*
G01Y155721D02*
X1313167Y156346D01*
G01X1312125Y157821D02*
X1311834Y158113D01*
X1311667Y158363D01*
X1311584Y158696D01*
X1311667Y158988D01*
X1311834Y159196D01*
X1312084Y159363D01*
X1312375Y159405D01*
X1312625Y159363D01*
X1312875Y159196D01*
X1313084Y158946D01*
X1313167Y158655D01*
X1313084Y158321D01*
X1312834Y158030D01*
X1312459Y157863D01*
X1312042Y157821D01*
X1311500Y157905D01*
X1311209Y158030D01*
X1310917Y158238D01*
X1310709Y158530D01*
X1310667Y158821D01*
X1310750Y159113D01*
X1310959Y159321D01*
G01X1311084Y160921D02*
X1310834Y161171D01*
X1310709Y161463D01*
X1310667Y161796D01*
X1310750Y162213D01*
X1310959Y162505D01*
X1311209Y162588D01*
X1311459Y162546D01*
X1311667Y162380D01*
X1312084Y161546D01*
X1312375Y161171D01*
X1312792Y160921D01*
X1313167Y160838D01*
Y162588D01*
G01Y165313D02*
X1310667D01*
X1312459Y163771D01*
Y165855D01*
G01X1308826Y153199D02*
Y149199D01*
X1316226D01*
G01X1298187Y164292D02*
X1297854Y164334D01*
X1297562Y164500D01*
X1297312Y164750D01*
X1297145Y165042D01*
X1297062Y165375D01*
Y165709D01*
X1297145Y166042D01*
X1297312Y166334D01*
X1297562Y166584D01*
X1297854Y166750D01*
X1298187Y166792D01*
X1298520Y166750D01*
X1298812Y166584D01*
X1299062Y166334D01*
X1299229Y166042D01*
X1299312Y165709D01*
Y165375D01*
X1299229Y165042D01*
X1299062Y164750D01*
X1298812Y164500D01*
X1298520Y164334D01*
X1298187Y164292D01*
G01X1298520Y164959D02*
X1299020Y164292D01*
G01X1300370Y164792D02*
X1300620Y164500D01*
X1300954Y164334D01*
X1301329Y164292D01*
X1301662Y164334D01*
X1301995Y164542D01*
X1302204Y164792D01*
X1302245Y165042D01*
X1302162Y165334D01*
X1301870Y165542D01*
X1301579Y165625D01*
X1301204D01*
G01X1301579D02*
X1301829Y165750D01*
X1302037Y165959D01*
X1302120Y166209D01*
X1302037Y166459D01*
X1301829Y166667D01*
X1301454Y166792D01*
X1301079Y166750D01*
X1300704Y166584D01*
G01X1304387Y166792D02*
X1304054Y166709D01*
X1303804Y166500D01*
X1303637Y166250D01*
X1303512Y165917D01*
X1303470Y165542D01*
X1303512Y165167D01*
X1303637Y164834D01*
X1303804Y164584D01*
X1304054Y164375D01*
X1304387Y164292D01*
X1304720Y164375D01*
X1304970Y164584D01*
X1305137Y164834D01*
X1305262Y165167D01*
X1305304Y165542D01*
X1305262Y165917D01*
X1305137Y166250D01*
X1304970Y166500D01*
X1304720Y166709D01*
X1304387Y166792D01*
G01X1308043Y149085D02*
Y163085D01*
G01X1295043Y149085D02*
X1308043D01*
G01X1295043Y163085D02*
Y149085D01*
G01X1308043Y163085D02*
X1295043D01*
G01X1317720Y141810D02*
X1303720D01*
G01X1307867Y208200D02*
Y210700D01*
X1308867D01*
X1309200Y210575D01*
X1309450Y210283D01*
X1309533Y209950D01*
X1309450Y209617D01*
X1309242Y209367D01*
X1308867Y209242D01*
X1307867D01*
G01X1312717Y210492D02*
X1312467Y210617D01*
X1312175Y210700D01*
X1311842D01*
X1311467Y210575D01*
X1311175Y210367D01*
X1310967Y210117D01*
X1310800Y209700D01*
X1310758Y209325D01*
X1310842Y208950D01*
X1310967Y208700D01*
X1311217Y208450D01*
X1311508Y208283D01*
X1311800Y208200D01*
X1312092D01*
X1312383Y208283D01*
X1312633Y208408D01*
X1312842Y208575D01*
G01X1314900Y208200D02*
Y210700D01*
X1314400Y210200D01*
G01Y208200D02*
X1315400D01*
G01X1317917D02*
X1318000Y208742D01*
X1318125Y209200D01*
X1318292Y209617D01*
X1318500Y210075D01*
X1318833Y210700D01*
X1317167D01*
G01X1320183Y208575D02*
X1320433Y208367D01*
X1320725Y208242D01*
X1321100Y208200D01*
X1321475Y208283D01*
X1321767Y208450D01*
X1321975Y208742D01*
X1322017Y209075D01*
X1321933Y209408D01*
X1321725Y209617D01*
X1321433Y209783D01*
X1321142Y209825D01*
X1320850Y209783D01*
X1320475Y209617D01*
X1320600Y210700D01*
X1321725D01*
G01X1295145Y188432D02*
X1295478Y188224D01*
X1295853Y188099D01*
X1296187D01*
X1296520Y188224D01*
X1296770Y188432D01*
X1296895Y188724D01*
X1296812Y189016D01*
X1296603Y189266D01*
X1296228Y189432D01*
X1295728Y189516D01*
X1295437Y189682D01*
X1295312Y189974D01*
X1295395Y190266D01*
X1295603Y190474D01*
X1295895Y190599D01*
X1296187D01*
X1296478Y190516D01*
X1296728Y190307D01*
G01X1297870Y190599D02*
X1298453Y188099D01*
X1299120Y190599D01*
X1299787Y188099D01*
X1300370Y190599D01*
G01X1301303Y188474D02*
X1301553Y188266D01*
X1301845Y188141D01*
X1302220Y188099D01*
X1302595Y188182D01*
X1302887Y188349D01*
X1303095Y188641D01*
X1303137Y188974D01*
X1303053Y189307D01*
X1302845Y189516D01*
X1302553Y189682D01*
X1302262Y189724D01*
X1301970Y189682D01*
X1301595Y189516D01*
X1301720Y190599D01*
X1302845D01*
G01X1307867Y191700D02*
Y194200D01*
X1308867D01*
X1309200Y194075D01*
X1309450Y193783D01*
X1309533Y193450D01*
X1309450Y193117D01*
X1309242Y192867D01*
X1308867Y192742D01*
X1307867D01*
G01X1312717Y193992D02*
X1312467Y194117D01*
X1312175Y194200D01*
X1311842D01*
X1311467Y194075D01*
X1311175Y193867D01*
X1310967Y193617D01*
X1310800Y193200D01*
X1310758Y192825D01*
X1310842Y192450D01*
X1310967Y192200D01*
X1311217Y191950D01*
X1311508Y191783D01*
X1311800Y191700D01*
X1312092D01*
X1312383Y191783D01*
X1312633Y191908D01*
X1312842Y192075D01*
G01X1314108Y193783D02*
X1314358Y194033D01*
X1314650Y194158D01*
X1314983Y194200D01*
X1315400Y194117D01*
X1315692Y193908D01*
X1315775Y193658D01*
X1315733Y193408D01*
X1315567Y193200D01*
X1314733Y192783D01*
X1314358Y192492D01*
X1314108Y192075D01*
X1314025Y191700D01*
X1315775D01*
G01X1318000D02*
Y194200D01*
X1317500Y193700D01*
G01Y191700D02*
X1318500D01*
G01X1320183Y192075D02*
X1320433Y191867D01*
X1320725Y191742D01*
X1321100Y191700D01*
X1321475Y191783D01*
X1321767Y191950D01*
X1321975Y192242D01*
X1322017Y192575D01*
X1321933Y192908D01*
X1321725Y193117D01*
X1321433Y193283D01*
X1321142Y193325D01*
X1320850Y193283D01*
X1320475Y193117D01*
X1320600Y194200D01*
X1321725D01*
G01X1307867Y195600D02*
Y198100D01*
X1308867D01*
X1309200Y197975D01*
X1309450Y197683D01*
X1309533Y197350D01*
X1309450Y197017D01*
X1309242Y196767D01*
X1308867Y196642D01*
X1307867D01*
G01X1312717Y197892D02*
X1312467Y198017D01*
X1312175Y198100D01*
X1311842D01*
X1311467Y197975D01*
X1311175Y197767D01*
X1310967Y197517D01*
X1310800Y197100D01*
X1310758Y196725D01*
X1310842Y196350D01*
X1310967Y196100D01*
X1311217Y195850D01*
X1311508Y195683D01*
X1311800Y195600D01*
X1312092D01*
X1312383Y195683D01*
X1312633Y195808D01*
X1312842Y195975D01*
G01X1314108Y197683D02*
X1314358Y197933D01*
X1314650Y198058D01*
X1314983Y198100D01*
X1315400Y198017D01*
X1315692Y197808D01*
X1315775Y197558D01*
X1315733Y197308D01*
X1315567Y197100D01*
X1314733Y196683D01*
X1314358Y196392D01*
X1314108Y195975D01*
X1314025Y195600D01*
X1315775D01*
G01X1318000D02*
Y198100D01*
X1317500Y197600D01*
G01Y195600D02*
X1318500D01*
G01X1320308Y196642D02*
X1320600Y196933D01*
X1320850Y197100D01*
X1321183Y197183D01*
X1321475Y197100D01*
X1321683Y196933D01*
X1321850Y196683D01*
X1321892Y196392D01*
X1321850Y196142D01*
X1321683Y195892D01*
X1321433Y195683D01*
X1321142Y195600D01*
X1320808Y195683D01*
X1320517Y195933D01*
X1320350Y196308D01*
X1320308Y196725D01*
X1320392Y197267D01*
X1320517Y197558D01*
X1320725Y197850D01*
X1321017Y198058D01*
X1321308Y198100D01*
X1321600Y198017D01*
X1321808Y197808D01*
G01X1307867Y204000D02*
Y206500D01*
X1308867D01*
X1309200Y206375D01*
X1309450Y206083D01*
X1309533Y205750D01*
X1309450Y205417D01*
X1309242Y205167D01*
X1308867Y205042D01*
X1307867D01*
G01X1312717Y206292D02*
X1312467Y206417D01*
X1312175Y206500D01*
X1311842D01*
X1311467Y206375D01*
X1311175Y206167D01*
X1310967Y205917D01*
X1310800Y205500D01*
X1310758Y205125D01*
X1310842Y204750D01*
X1310967Y204500D01*
X1311217Y204250D01*
X1311508Y204083D01*
X1311800Y204000D01*
X1312092D01*
X1312383Y204083D01*
X1312633Y204208D01*
X1312842Y204375D01*
G01X1314108Y206083D02*
X1314358Y206333D01*
X1314650Y206458D01*
X1314983Y206500D01*
X1315400Y206417D01*
X1315692Y206208D01*
X1315775Y205958D01*
X1315733Y205708D01*
X1315567Y205500D01*
X1314733Y205083D01*
X1314358Y204792D01*
X1314108Y204375D01*
X1314025Y204000D01*
X1315775D01*
G01X1318000D02*
Y206500D01*
X1317500Y206000D01*
G01Y204000D02*
X1318500D01*
G01X1321100D02*
X1321392Y204042D01*
X1321725Y204167D01*
X1321933Y204375D01*
X1322017Y204667D01*
X1321933Y204958D01*
X1321683Y205208D01*
X1321308Y205333D01*
X1320892D01*
X1320642Y205417D01*
X1320433Y205625D01*
X1320350Y205917D01*
X1320475Y206208D01*
X1320767Y206417D01*
X1321100Y206500D01*
X1321433Y206417D01*
X1321725Y206208D01*
X1321850Y205917D01*
X1321767Y205625D01*
X1321558Y205417D01*
X1321308Y205333D01*
X1320892D01*
X1320517Y205208D01*
X1320267Y204958D01*
X1320183Y204667D01*
X1320267Y204375D01*
X1320475Y204167D01*
X1320808Y204042D01*
X1321100Y204000D01*
G01X1307867Y199800D02*
Y202300D01*
X1308867D01*
X1309200Y202175D01*
X1309450Y201883D01*
X1309533Y201550D01*
X1309450Y201217D01*
X1309242Y200967D01*
X1308867Y200842D01*
X1307867D01*
G01X1312717Y202092D02*
X1312467Y202217D01*
X1312175Y202300D01*
X1311842D01*
X1311467Y202175D01*
X1311175Y201967D01*
X1310967Y201717D01*
X1310800Y201300D01*
X1310758Y200925D01*
X1310842Y200550D01*
X1310967Y200300D01*
X1311217Y200050D01*
X1311508Y199883D01*
X1311800Y199800D01*
X1312092D01*
X1312383Y199883D01*
X1312633Y200008D01*
X1312842Y200175D01*
G01X1314108Y201883D02*
X1314358Y202133D01*
X1314650Y202258D01*
X1314983Y202300D01*
X1315400Y202217D01*
X1315692Y202008D01*
X1315775Y201758D01*
X1315733Y201508D01*
X1315567Y201300D01*
X1314733Y200883D01*
X1314358Y200592D01*
X1314108Y200175D01*
X1314025Y199800D01*
X1315775D01*
G01X1317208Y201883D02*
X1317458Y202133D01*
X1317750Y202258D01*
X1318083Y202300D01*
X1318500Y202217D01*
X1318792Y202008D01*
X1318875Y201758D01*
X1318833Y201508D01*
X1318667Y201300D01*
X1317833Y200883D01*
X1317458Y200592D01*
X1317208Y200175D01*
X1317125Y199800D01*
X1318875D01*
G01X1321100D02*
Y202300D01*
X1320600Y201800D01*
G01Y199800D02*
X1321600D01*
G01X1288770Y210011D02*
Y212511D01*
X1289770D01*
X1290103Y212386D01*
X1290353Y212094D01*
X1290436Y211761D01*
X1290353Y211428D01*
X1290145Y211178D01*
X1289770Y211053D01*
X1288770D01*
G01X1292703Y212511D02*
Y210011D01*
G01X1291745Y212511D02*
X1293661D01*
G01X1296720Y212303D02*
X1296470Y212428D01*
X1296178Y212511D01*
X1295845D01*
X1295470Y212386D01*
X1295178Y212178D01*
X1294970Y211928D01*
X1294803Y211511D01*
X1294761Y211136D01*
X1294845Y210761D01*
X1294970Y210511D01*
X1295220Y210261D01*
X1295511Y210094D01*
X1295803Y210011D01*
X1296095D01*
X1296386Y210094D01*
X1296636Y210219D01*
X1296845Y210386D01*
G01X1298820Y210011D02*
X1298903Y210553D01*
X1299028Y211011D01*
X1299195Y211428D01*
X1299403Y211886D01*
X1299736Y212511D01*
X1298070D01*
G01X1307867Y212100D02*
Y214600D01*
X1308867D01*
X1309200Y214475D01*
X1309450Y214183D01*
X1309533Y213850D01*
X1309450Y213517D01*
X1309242Y213267D01*
X1308867Y213142D01*
X1307867D01*
G01X1312717Y214392D02*
X1312467Y214517D01*
X1312175Y214600D01*
X1311842D01*
X1311467Y214475D01*
X1311175Y214267D01*
X1310967Y214017D01*
X1310800Y213600D01*
X1310758Y213225D01*
X1310842Y212850D01*
X1310967Y212600D01*
X1311217Y212350D01*
X1311508Y212183D01*
X1311800Y212100D01*
X1312092D01*
X1312383Y212183D01*
X1312633Y212308D01*
X1312842Y212475D01*
G01X1314900Y212100D02*
Y214600D01*
X1314400Y214100D01*
G01Y212100D02*
X1315400D01*
G01X1317917D02*
X1318000Y212642D01*
X1318125Y213100D01*
X1318292Y213517D01*
X1318500Y213975D01*
X1318833Y214600D01*
X1317167D01*
G01X1320308Y214183D02*
X1320558Y214433D01*
X1320850Y214558D01*
X1321183Y214600D01*
X1321600Y214517D01*
X1321892Y214308D01*
X1321975Y214058D01*
X1321933Y213808D01*
X1321767Y213600D01*
X1320933Y213183D01*
X1320558Y212892D01*
X1320308Y212475D01*
X1320225Y212100D01*
X1321975D01*
G01X1301251Y271031D02*
Y273531D01*
X1302292D01*
X1302626Y273406D01*
X1302834Y273239D01*
X1302917Y272906D01*
X1302834Y272573D01*
X1302584Y272364D01*
X1302292Y272239D01*
X1301251D01*
G01X1302292D02*
X1302917Y271031D01*
G01X1304392Y272073D02*
X1304684Y272364D01*
X1304934Y272531D01*
X1305267Y272614D01*
X1305559Y272531D01*
X1305767Y272364D01*
X1305934Y272114D01*
X1305976Y271823D01*
X1305934Y271573D01*
X1305767Y271323D01*
X1305517Y271114D01*
X1305226Y271031D01*
X1304892Y271114D01*
X1304601Y271364D01*
X1304434Y271739D01*
X1304392Y272156D01*
X1304476Y272698D01*
X1304601Y272989D01*
X1304809Y273281D01*
X1305101Y273489D01*
X1305392Y273531D01*
X1305684Y273448D01*
X1305892Y273239D01*
G01X1308284Y271031D02*
Y273531D01*
X1307784Y273031D01*
G01Y271031D02*
X1308784D01*
G01X1311384Y273531D02*
X1311051Y273448D01*
X1310801Y273239D01*
X1310634Y272989D01*
X1310509Y272656D01*
X1310467Y272281D01*
X1310509Y271906D01*
X1310634Y271573D01*
X1310801Y271323D01*
X1311051Y271114D01*
X1311384Y271031D01*
X1311717Y271114D01*
X1311967Y271323D01*
X1312134Y271573D01*
X1312259Y271906D01*
X1312301Y272281D01*
X1312259Y272656D01*
X1312134Y272989D01*
X1311967Y273239D01*
X1311717Y273448D01*
X1311384Y273531D01*
G01X1299500Y274967D02*
X1297000D01*
Y275967D01*
X1297125Y276300D01*
X1297417Y276550D01*
X1297750Y276633D01*
X1298083Y276550D01*
X1298333Y276342D01*
X1298458Y275967D01*
Y274967D01*
G01X1299500Y278067D02*
X1297000D01*
Y279108D01*
X1297125Y279442D01*
X1297292Y279650D01*
X1297625Y279733D01*
X1297958Y279650D01*
X1298167Y279400D01*
X1298292Y279108D01*
Y278067D01*
G01Y279108D02*
X1299500Y279733D01*
G01Y282000D02*
X1297000D01*
X1297500Y281500D01*
G01X1299500D02*
Y282500D01*
G01X1299125Y284183D02*
X1299333Y284433D01*
X1299458Y284725D01*
X1299500Y285100D01*
X1299417Y285475D01*
X1299250Y285767D01*
X1298958Y285975D01*
X1298625Y286017D01*
X1298292Y285933D01*
X1298083Y285725D01*
X1297917Y285433D01*
X1297875Y285142D01*
X1297917Y284850D01*
X1298083Y284475D01*
X1297000Y284600D01*
Y285725D01*
G01X1299500Y288117D02*
X1298958Y288200D01*
X1298500Y288325D01*
X1298083Y288492D01*
X1297625Y288700D01*
X1297000Y289033D01*
Y287367D01*
G01X1291500Y274967D02*
X1289000D01*
Y275967D01*
X1289125Y276300D01*
X1289417Y276550D01*
X1289750Y276633D01*
X1290083Y276550D01*
X1290333Y276342D01*
X1290458Y275967D01*
Y274967D01*
G01X1291500Y278067D02*
X1289000D01*
Y279108D01*
X1289125Y279442D01*
X1289292Y279650D01*
X1289625Y279733D01*
X1289958Y279650D01*
X1290167Y279400D01*
X1290292Y279108D01*
Y278067D01*
G01Y279108D02*
X1291500Y279733D01*
G01Y282000D02*
X1289000D01*
X1289500Y281500D01*
G01X1291500D02*
Y282500D01*
G01X1291125Y284183D02*
X1291333Y284433D01*
X1291458Y284725D01*
X1291500Y285100D01*
X1291417Y285475D01*
X1291250Y285767D01*
X1290958Y285975D01*
X1290625Y286017D01*
X1290292Y285933D01*
X1290083Y285725D01*
X1289917Y285433D01*
X1289875Y285142D01*
X1289917Y284850D01*
X1290083Y284475D01*
X1289000Y284600D01*
Y285725D01*
G01X1289417Y287408D02*
X1289167Y287658D01*
X1289042Y287950D01*
X1289000Y288283D01*
X1289083Y288700D01*
X1289292Y288992D01*
X1289542Y289075D01*
X1289792Y289033D01*
X1290000Y288867D01*
X1290417Y288033D01*
X1290708Y287658D01*
X1291125Y287408D01*
X1291500Y287325D01*
Y289075D01*
G01X1295500Y274967D02*
X1293000D01*
Y275967D01*
X1293125Y276300D01*
X1293417Y276550D01*
X1293750Y276633D01*
X1294083Y276550D01*
X1294333Y276342D01*
X1294458Y275967D01*
Y274967D01*
G01X1295500Y278067D02*
X1293000D01*
Y279108D01*
X1293125Y279442D01*
X1293292Y279650D01*
X1293625Y279733D01*
X1293958Y279650D01*
X1294167Y279400D01*
X1294292Y279108D01*
Y278067D01*
G01Y279108D02*
X1295500Y279733D01*
G01Y282000D02*
X1293000D01*
X1293500Y281500D01*
G01X1295500D02*
Y282500D01*
G01X1295125Y284183D02*
X1295333Y284433D01*
X1295458Y284725D01*
X1295500Y285100D01*
X1295417Y285475D01*
X1295250Y285767D01*
X1294958Y285975D01*
X1294625Y286017D01*
X1294292Y285933D01*
X1294083Y285725D01*
X1293917Y285433D01*
X1293875Y285142D01*
X1293917Y284850D01*
X1294083Y284475D01*
X1293000Y284600D01*
Y285725D01*
G01X1295500Y288200D02*
X1293000D01*
X1293500Y287700D01*
G01X1295500D02*
Y288700D01*
G01X1303500Y274967D02*
X1301000D01*
Y275967D01*
X1301125Y276300D01*
X1301417Y276550D01*
X1301750Y276633D01*
X1302083Y276550D01*
X1302333Y276342D01*
X1302458Y275967D01*
Y274967D01*
G01X1301208Y279817D02*
X1301083Y279567D01*
X1301000Y279275D01*
Y278942D01*
X1301125Y278567D01*
X1301333Y278275D01*
X1301583Y278067D01*
X1302000Y277900D01*
X1302375Y277858D01*
X1302750Y277942D01*
X1303000Y278067D01*
X1303250Y278317D01*
X1303417Y278608D01*
X1303500Y278900D01*
Y279192D01*
X1303417Y279483D01*
X1303292Y279733D01*
X1303125Y279942D01*
G01X1303500Y282000D02*
X1301000D01*
X1301500Y281500D01*
G01X1303500D02*
Y282500D01*
G01Y285100D02*
X1303458Y285392D01*
X1303333Y285725D01*
X1303125Y285933D01*
X1302833Y286017D01*
X1302542Y285933D01*
X1302292Y285683D01*
X1302167Y285308D01*
Y284892D01*
X1302083Y284642D01*
X1301875Y284433D01*
X1301583Y284350D01*
X1301292Y284475D01*
X1301083Y284767D01*
X1301000Y285100D01*
X1301083Y285433D01*
X1301292Y285725D01*
X1301583Y285850D01*
X1301875Y285767D01*
X1302083Y285558D01*
X1302167Y285308D01*
Y284892D01*
X1302292Y284517D01*
X1302542Y284267D01*
X1302833Y284183D01*
X1303125Y284267D01*
X1303333Y284475D01*
X1303458Y284808D01*
X1303500Y285100D01*
G01Y288117D02*
X1302958Y288200D01*
X1302500Y288325D01*
X1302083Y288492D01*
X1301625Y288700D01*
X1301000Y289033D01*
Y287367D01*
G01X1296517Y308000D02*
Y310500D01*
X1297517D01*
X1297850Y310375D01*
X1298100Y310083D01*
X1298183Y309750D01*
X1298100Y309417D01*
X1297892Y309167D01*
X1297517Y309042D01*
X1296517D01*
G01X1300450Y308000D02*
X1300117Y308042D01*
X1299825Y308208D01*
X1299575Y308458D01*
X1299408Y308750D01*
X1299325Y309083D01*
Y309417D01*
X1299408Y309750D01*
X1299575Y310042D01*
X1299825Y310292D01*
X1300117Y310458D01*
X1300450Y310500D01*
X1300783Y310458D01*
X1301075Y310292D01*
X1301325Y310042D01*
X1301492Y309750D01*
X1301575Y309417D01*
Y309083D01*
X1301492Y308750D01*
X1301325Y308458D01*
X1301075Y308208D01*
X1300783Y308042D01*
X1300450Y308000D01*
G01X1300783Y308667D02*
X1301283Y308000D01*
G01X1302758Y310083D02*
X1303008Y310333D01*
X1303300Y310458D01*
X1303633Y310500D01*
X1304050Y310417D01*
X1304342Y310208D01*
X1304425Y309958D01*
X1304383Y309708D01*
X1304217Y309500D01*
X1303383Y309083D01*
X1303008Y308792D01*
X1302758Y308375D01*
X1302675Y308000D01*
X1304425D01*
G01X1306650Y310500D02*
X1306317Y310417D01*
X1306067Y310208D01*
X1305900Y309958D01*
X1305775Y309625D01*
X1305733Y309250D01*
X1305775Y308875D01*
X1305900Y308542D01*
X1306067Y308292D01*
X1306317Y308083D01*
X1306650Y308000D01*
X1306983Y308083D01*
X1307233Y308292D01*
X1307400Y308542D01*
X1307525Y308875D01*
X1307567Y309250D01*
X1307525Y309625D01*
X1307400Y309958D01*
X1307233Y310208D01*
X1306983Y310417D01*
X1306650Y310500D01*
G01X1301700Y303400D02*
X1303700D01*
G01X1301700Y290000D02*
Y303400D01*
G01X1303700Y290000D02*
X1301700D01*
G01X1303700Y303400D02*
Y290000D01*
G01X1286567Y309200D02*
Y311700D01*
X1287608D01*
X1287942Y311575D01*
X1288150Y311408D01*
X1288233Y311075D01*
X1288150Y310742D01*
X1287900Y310533D01*
X1287608Y310408D01*
X1286567D01*
G01X1287608D02*
X1288233Y309200D01*
G01X1290500D02*
Y311700D01*
X1290000Y311200D01*
G01Y309200D02*
X1291000D01*
G01X1294100D02*
Y311700D01*
X1292558Y309908D01*
X1294642D01*
G01X1294700Y298000D02*
Y302000D01*
X1287300D01*
G01X1314133Y299805D02*
X1311633D01*
Y300805D01*
X1311758Y301138D01*
X1312050Y301388D01*
X1312383Y301471D01*
X1312716Y301388D01*
X1312966Y301180D01*
X1313091Y300805D01*
Y299805D01*
G01X1314133Y302905D02*
X1311633D01*
Y303946D01*
X1311758Y304280D01*
X1311925Y304488D01*
X1312258Y304571D01*
X1312591Y304488D01*
X1312800Y304238D01*
X1312925Y303946D01*
Y302905D01*
G01Y303946D02*
X1314133Y304571D01*
G01Y306838D02*
X1311633D01*
X1312133Y306338D01*
G01X1314133D02*
Y307338D01*
G01X1313758Y309021D02*
X1313966Y309271D01*
X1314091Y309563D01*
X1314133Y309938D01*
X1314050Y310313D01*
X1313883Y310605D01*
X1313591Y310813D01*
X1313258Y310855D01*
X1312925Y310771D01*
X1312716Y310563D01*
X1312550Y310271D01*
X1312508Y309980D01*
X1312550Y309688D01*
X1312716Y309313D01*
X1311633Y309438D01*
Y310563D01*
G01X1313091Y312246D02*
X1312800Y312538D01*
X1312633Y312788D01*
X1312550Y313121D01*
X1312633Y313413D01*
X1312800Y313621D01*
X1313050Y313788D01*
X1313341Y313830D01*
X1313591Y313788D01*
X1313841Y313621D01*
X1314050Y313371D01*
X1314133Y313080D01*
X1314050Y312746D01*
X1313800Y312455D01*
X1313425Y312288D01*
X1313008Y312246D01*
X1312466Y312330D01*
X1312175Y312455D01*
X1311883Y312663D01*
X1311675Y312955D01*
X1311633Y313246D01*
X1311716Y313538D01*
X1311925Y313746D01*
G01X1311000Y287800D02*
X1315000D01*
Y295200D01*
G01X1305000Y276800D02*
X1309000D01*
Y284200D01*
G01X1313000D02*
X1309000D01*
Y276800D01*
G01X1286617Y305200D02*
Y307700D01*
X1287658D01*
X1287992Y307575D01*
X1288200Y307408D01*
X1288283Y307075D01*
X1288200Y306742D01*
X1287950Y306533D01*
X1287658Y306408D01*
X1286617D01*
G01X1287658D02*
X1288283Y305200D01*
G01X1289758Y307283D02*
X1290008Y307533D01*
X1290300Y307658D01*
X1290633Y307700D01*
X1291050Y307617D01*
X1291342Y307408D01*
X1291425Y307158D01*
X1291383Y306908D01*
X1291217Y306700D01*
X1290383Y306283D01*
X1290008Y305992D01*
X1289758Y305575D01*
X1289675Y305200D01*
X1291425D01*
G01X1287300Y297000D02*
Y293000D01*
X1294700D01*
G01X1283752Y320891D02*
X1281252D01*
Y321932D01*
X1281377Y322266D01*
X1281544Y322474D01*
X1281877Y322557D01*
X1282210Y322474D01*
X1282419Y322224D01*
X1282544Y321932D01*
Y320891D01*
G01Y321932D02*
X1283752Y322557D01*
G01Y325324D02*
X1281252D01*
X1283044Y323782D01*
Y325866D01*
G01X1283752Y327924D02*
X1281252D01*
X1281752Y327424D01*
G01X1283752D02*
Y328424D01*
G01X1282710Y330232D02*
X1282419Y330524D01*
X1282252Y330774D01*
X1282169Y331107D01*
X1282252Y331399D01*
X1282419Y331607D01*
X1282669Y331774D01*
X1282960Y331816D01*
X1283210Y331774D01*
X1283460Y331607D01*
X1283669Y331357D01*
X1283752Y331066D01*
X1283669Y330732D01*
X1283419Y330441D01*
X1283044Y330274D01*
X1282627Y330232D01*
X1282085Y330316D01*
X1281794Y330441D01*
X1281502Y330649D01*
X1281294Y330941D01*
X1281252Y331232D01*
X1281335Y331524D01*
X1281544Y331732D01*
G01X1282710Y333332D02*
X1282419Y333624D01*
X1282252Y333874D01*
X1282169Y334207D01*
X1282252Y334499D01*
X1282419Y334707D01*
X1282669Y334874D01*
X1282960Y334916D01*
X1283210Y334874D01*
X1283460Y334707D01*
X1283669Y334457D01*
X1283752Y334166D01*
X1283669Y333832D01*
X1283419Y333541D01*
X1283044Y333374D01*
X1282627Y333332D01*
X1282085Y333416D01*
X1281794Y333541D01*
X1281502Y333749D01*
X1281294Y334041D01*
X1281252Y334332D01*
X1281335Y334624D01*
X1281544Y334832D01*
G01X1284500Y344200D02*
X1280500D01*
Y336800D01*
G01X1287752Y320891D02*
X1285252D01*
Y321932D01*
X1285377Y322266D01*
X1285544Y322474D01*
X1285877Y322557D01*
X1286210Y322474D01*
X1286419Y322224D01*
X1286544Y321932D01*
Y320891D01*
G01Y321932D02*
X1287752Y322557D01*
G01Y325324D02*
X1285252D01*
X1287044Y323782D01*
Y325866D01*
G01X1287752Y327924D02*
X1285252D01*
X1285752Y327424D01*
G01X1287752D02*
Y328424D01*
G01X1286710Y330232D02*
X1286419Y330524D01*
X1286252Y330774D01*
X1286169Y331107D01*
X1286252Y331399D01*
X1286419Y331607D01*
X1286669Y331774D01*
X1286960Y331816D01*
X1287210Y331774D01*
X1287460Y331607D01*
X1287669Y331357D01*
X1287752Y331066D01*
X1287669Y330732D01*
X1287419Y330441D01*
X1287044Y330274D01*
X1286627Y330232D01*
X1286085Y330316D01*
X1285794Y330441D01*
X1285502Y330649D01*
X1285294Y330941D01*
X1285252Y331232D01*
X1285335Y331524D01*
X1285544Y331732D01*
G01X1287752Y334124D02*
X1287710Y334416D01*
X1287585Y334749D01*
X1287377Y334957D01*
X1287085Y335041D01*
X1286794Y334957D01*
X1286544Y334707D01*
X1286419Y334332D01*
Y333916D01*
X1286335Y333666D01*
X1286127Y333457D01*
X1285835Y333374D01*
X1285544Y333499D01*
X1285335Y333791D01*
X1285252Y334124D01*
X1285335Y334457D01*
X1285544Y334749D01*
X1285835Y334874D01*
X1286127Y334791D01*
X1286335Y334582D01*
X1286419Y334332D01*
Y333916D01*
X1286544Y333541D01*
X1286794Y333291D01*
X1287085Y333207D01*
X1287377Y333291D01*
X1287585Y333499D01*
X1287710Y333832D01*
X1287752Y334124D01*
G01X1288500Y344200D02*
X1284500D01*
Y336800D01*
G01X1291752Y320891D02*
X1289252D01*
Y321932D01*
X1289377Y322266D01*
X1289544Y322474D01*
X1289877Y322557D01*
X1290210Y322474D01*
X1290419Y322224D01*
X1290544Y321932D01*
Y320891D01*
G01Y321932D02*
X1291752Y322557D01*
G01Y325324D02*
X1289252D01*
X1291044Y323782D01*
Y325866D01*
G01X1291752Y327924D02*
X1289252D01*
X1289752Y327424D01*
G01X1291752D02*
Y328424D01*
G01Y330941D02*
X1291210Y331024D01*
X1290752Y331149D01*
X1290335Y331316D01*
X1289877Y331524D01*
X1289252Y331857D01*
Y330191D01*
G01Y334124D02*
X1289335Y333791D01*
X1289544Y333541D01*
X1289794Y333374D01*
X1290127Y333249D01*
X1290502Y333207D01*
X1290877Y333249D01*
X1291210Y333374D01*
X1291460Y333541D01*
X1291669Y333791D01*
X1291752Y334124D01*
X1291669Y334457D01*
X1291460Y334707D01*
X1291210Y334874D01*
X1290877Y334999D01*
X1290502Y335041D01*
X1290127Y334999D01*
X1289794Y334874D01*
X1289544Y334707D01*
X1289335Y334457D01*
X1289252Y334124D01*
G01X1292500Y344200D02*
X1288500D01*
Y336800D01*
G01X1295752Y320891D02*
X1293252D01*
Y321932D01*
X1293377Y322266D01*
X1293544Y322474D01*
X1293877Y322557D01*
X1294210Y322474D01*
X1294419Y322224D01*
X1294544Y321932D01*
Y320891D01*
G01Y321932D02*
X1295752Y322557D01*
G01Y325324D02*
X1293252D01*
X1295044Y323782D01*
Y325866D01*
G01X1295752Y327924D02*
X1293252D01*
X1293752Y327424D01*
G01X1295752D02*
Y328424D01*
G01Y330941D02*
X1295210Y331024D01*
X1294752Y331149D01*
X1294335Y331316D01*
X1293877Y331524D01*
X1293252Y331857D01*
Y330191D01*
G01X1293669Y333332D02*
X1293419Y333582D01*
X1293294Y333874D01*
X1293252Y334207D01*
X1293335Y334624D01*
X1293544Y334916D01*
X1293794Y334999D01*
X1294044Y334957D01*
X1294252Y334791D01*
X1294669Y333957D01*
X1294960Y333582D01*
X1295377Y333332D01*
X1295752Y333249D01*
Y334999D01*
G01X1296500Y344200D02*
X1292500D01*
Y336800D01*
G01X1303752Y320891D02*
X1301252D01*
Y321932D01*
X1301377Y322266D01*
X1301544Y322474D01*
X1301877Y322557D01*
X1302210Y322474D01*
X1302419Y322224D01*
X1302544Y321932D01*
Y320891D01*
G01Y321932D02*
X1303752Y322557D01*
G01Y325324D02*
X1301252D01*
X1303044Y323782D01*
Y325866D01*
G01X1303752Y327924D02*
X1301252D01*
X1301752Y327424D01*
G01X1303752D02*
Y328424D01*
G01Y330941D02*
X1303210Y331024D01*
X1302752Y331149D01*
X1302335Y331316D01*
X1301877Y331524D01*
X1301252Y331857D01*
Y330191D01*
G01X1303752Y334624D02*
X1301252D01*
X1303044Y333082D01*
Y335166D01*
G01X1304500Y344200D02*
X1300500D01*
Y336800D01*
G01X1299752Y320891D02*
X1297252D01*
Y321932D01*
X1297377Y322266D01*
X1297544Y322474D01*
X1297877Y322557D01*
X1298210Y322474D01*
X1298419Y322224D01*
X1298544Y321932D01*
Y320891D01*
G01Y321932D02*
X1299752Y322557D01*
G01Y325324D02*
X1297252D01*
X1299044Y323782D01*
Y325866D01*
G01X1299752Y327924D02*
X1297252D01*
X1297752Y327424D01*
G01X1299752D02*
Y328424D01*
G01Y330941D02*
X1299210Y331024D01*
X1298752Y331149D01*
X1298335Y331316D01*
X1297877Y331524D01*
X1297252Y331857D01*
Y330191D01*
G01X1298710Y333332D02*
X1298419Y333624D01*
X1298252Y333874D01*
X1298169Y334207D01*
X1298252Y334499D01*
X1298419Y334707D01*
X1298669Y334874D01*
X1298960Y334916D01*
X1299210Y334874D01*
X1299460Y334707D01*
X1299669Y334457D01*
X1299752Y334166D01*
X1299669Y333832D01*
X1299419Y333541D01*
X1299044Y333374D01*
X1298627Y333332D01*
X1298085Y333416D01*
X1297794Y333541D01*
X1297502Y333749D01*
X1297294Y334041D01*
X1297252Y334332D01*
X1297335Y334624D01*
X1297544Y334832D01*
G01X1300500Y344200D02*
X1296500D01*
Y336800D01*
G01X1293400Y373400D02*
Y359400D01*
G01X1280543Y389914D02*
X1283043D01*
G01X1280543Y388956D02*
Y390872D01*
G01X1283043Y392181D02*
X1280543D01*
Y393181D01*
X1280668Y393514D01*
X1280960Y393764D01*
X1281293Y393847D01*
X1281626Y393764D01*
X1281876Y393556D01*
X1282001Y393181D01*
Y392181D01*
G01X1282543Y395197D02*
X1282835Y395447D01*
X1283001Y395781D01*
X1283043Y396156D01*
X1283001Y396489D01*
X1282793Y396822D01*
X1282543Y397031D01*
X1282293Y397072D01*
X1282001Y396989D01*
X1281793Y396697D01*
X1281710Y396406D01*
Y396031D01*
G01Y396406D02*
X1281585Y396656D01*
X1281376Y396864D01*
X1281126Y396947D01*
X1280876Y396864D01*
X1280668Y396656D01*
X1280543Y396281D01*
X1280585Y395906D01*
X1280751Y395531D01*
G01X1280543Y399214D02*
X1280626Y398881D01*
X1280835Y398631D01*
X1281085Y398464D01*
X1281418Y398339D01*
X1281793Y398297D01*
X1282168Y398339D01*
X1282501Y398464D01*
X1282751Y398631D01*
X1282960Y398881D01*
X1283043Y399214D01*
X1282960Y399547D01*
X1282751Y399797D01*
X1282501Y399964D01*
X1282168Y400089D01*
X1281793Y400131D01*
X1281418Y400089D01*
X1281085Y399964D01*
X1280835Y399797D01*
X1280626Y399547D01*
X1280543Y399214D01*
G01X1283043Y402314D02*
X1280543D01*
X1281043Y401814D01*
G01X1283043D02*
Y402814D01*
G01X1303500Y397467D02*
X1301000D01*
Y398508D01*
X1301125Y398842D01*
X1301292Y399050D01*
X1301625Y399133D01*
X1301958Y399050D01*
X1302167Y398800D01*
X1302292Y398508D01*
Y397467D01*
G01Y398508D02*
X1303500Y399133D01*
G01Y401900D02*
X1301000D01*
X1302792Y400358D01*
Y402442D01*
G01X1303500Y404500D02*
X1301000D01*
X1301500Y404000D01*
G01X1303500D02*
Y405000D01*
G01X1302458Y406808D02*
X1302167Y407100D01*
X1302000Y407350D01*
X1301917Y407683D01*
X1302000Y407975D01*
X1302167Y408183D01*
X1302417Y408350D01*
X1302708Y408392D01*
X1302958Y408350D01*
X1303208Y408183D01*
X1303417Y407933D01*
X1303500Y407642D01*
X1303417Y407308D01*
X1303167Y407017D01*
X1302792Y406850D01*
X1302375Y406808D01*
X1301833Y406892D01*
X1301542Y407017D01*
X1301250Y407225D01*
X1301042Y407517D01*
X1301000Y407808D01*
X1301083Y408100D01*
X1301292Y408308D01*
G01X1303500Y411200D02*
X1301000D01*
X1302792Y409658D01*
Y411742D01*
G01X1299500Y388300D02*
X1303500D01*
Y395700D01*
G01X1295500Y397467D02*
X1293000D01*
Y398508D01*
X1293125Y398842D01*
X1293292Y399050D01*
X1293625Y399133D01*
X1293958Y399050D01*
X1294167Y398800D01*
X1294292Y398508D01*
Y397467D01*
G01Y398508D02*
X1295500Y399133D01*
G01Y401900D02*
X1293000D01*
X1294792Y400358D01*
Y402442D01*
G01X1295500Y404500D02*
X1293000D01*
X1293500Y404000D01*
G01X1295500D02*
Y405000D01*
G01X1294458Y406808D02*
X1294167Y407100D01*
X1294000Y407350D01*
X1293917Y407683D01*
X1294000Y407975D01*
X1294167Y408183D01*
X1294417Y408350D01*
X1294708Y408392D01*
X1294958Y408350D01*
X1295208Y408183D01*
X1295417Y407933D01*
X1295500Y407642D01*
X1295417Y407308D01*
X1295167Y407017D01*
X1294792Y406850D01*
X1294375Y406808D01*
X1293833Y406892D01*
X1293542Y407017D01*
X1293250Y407225D01*
X1293042Y407517D01*
X1293000Y407808D01*
X1293083Y408100D01*
X1293292Y408308D01*
G01X1295500Y410617D02*
X1294958Y410700D01*
X1294500Y410825D01*
X1294083Y410992D01*
X1293625Y411200D01*
X1293000Y411533D01*
Y409867D01*
G01X1291500Y388300D02*
X1295500D01*
Y395700D01*
G01X1299500Y397467D02*
X1297000D01*
Y398508D01*
X1297125Y398842D01*
X1297292Y399050D01*
X1297625Y399133D01*
X1297958Y399050D01*
X1298167Y398800D01*
X1298292Y398508D01*
Y397467D01*
G01Y398508D02*
X1299500Y399133D01*
G01Y401900D02*
X1297000D01*
X1298792Y400358D01*
Y402442D01*
G01X1299500Y404500D02*
X1297000D01*
X1297500Y404000D01*
G01X1299500D02*
Y405000D01*
G01X1298458Y406808D02*
X1298167Y407100D01*
X1298000Y407350D01*
X1297917Y407683D01*
X1298000Y407975D01*
X1298167Y408183D01*
X1298417Y408350D01*
X1298708Y408392D01*
X1298958Y408350D01*
X1299208Y408183D01*
X1299417Y407933D01*
X1299500Y407642D01*
X1299417Y407308D01*
X1299167Y407017D01*
X1298792Y406850D01*
X1298375Y406808D01*
X1297833Y406892D01*
X1297542Y407017D01*
X1297250Y407225D01*
X1297042Y407517D01*
X1297000Y407808D01*
X1297083Y408100D01*
X1297292Y408308D01*
G01X1299208Y409992D02*
X1299417Y410283D01*
X1299500Y410617D01*
X1299417Y410950D01*
X1299167Y411242D01*
X1298792Y411450D01*
X1298417Y411533D01*
X1297958D01*
X1297583Y411450D01*
X1297250Y411242D01*
X1297083Y410992D01*
X1297000Y410700D01*
X1297083Y410367D01*
X1297250Y410117D01*
X1297500Y409950D01*
X1297833Y409867D01*
X1298125Y409950D01*
X1298417Y410158D01*
X1298583Y410408D01*
X1298625Y410700D01*
X1298542Y411033D01*
X1298333Y411283D01*
X1297958Y411533D01*
G01X1295500Y388300D02*
X1299500D01*
Y395700D01*
G01X1287500Y397467D02*
X1285000D01*
Y398508D01*
X1285125Y398842D01*
X1285292Y399050D01*
X1285625Y399133D01*
X1285958Y399050D01*
X1286167Y398800D01*
X1286292Y398508D01*
Y397467D01*
G01Y398508D02*
X1287500Y399133D01*
G01Y401900D02*
X1285000D01*
X1286792Y400358D01*
Y402442D01*
G01X1287500Y404500D02*
X1285000D01*
X1285500Y404000D01*
G01X1287500D02*
Y405000D01*
G01Y407517D02*
X1286958Y407600D01*
X1286500Y407725D01*
X1286083Y407892D01*
X1285625Y408100D01*
X1285000Y408433D01*
Y406767D01*
G01X1287500Y410700D02*
X1285000D01*
X1285500Y410200D01*
G01X1287500D02*
Y411200D01*
G01X1283500Y388300D02*
X1287500D01*
Y395700D01*
G01X1307500Y397467D02*
X1305000D01*
Y398508D01*
X1305125Y398842D01*
X1305292Y399050D01*
X1305625Y399133D01*
X1305958Y399050D01*
X1306167Y398800D01*
X1306292Y398508D01*
Y397467D01*
G01Y398508D02*
X1307500Y399133D01*
G01Y401900D02*
X1305000D01*
X1306792Y400358D01*
Y402442D01*
G01X1307500Y404500D02*
X1305000D01*
X1305500Y404000D01*
G01X1307500D02*
Y405000D01*
G01X1307125Y406683D02*
X1307333Y406933D01*
X1307458Y407225D01*
X1307500Y407600D01*
X1307417Y407975D01*
X1307250Y408267D01*
X1306958Y408475D01*
X1306625Y408517D01*
X1306292Y408433D01*
X1306083Y408225D01*
X1305917Y407933D01*
X1305875Y407642D01*
X1305917Y407350D01*
X1306083Y406975D01*
X1305000Y407100D01*
Y408225D01*
G01X1307500Y410700D02*
X1307458Y410992D01*
X1307333Y411325D01*
X1307125Y411533D01*
X1306833Y411617D01*
X1306542Y411533D01*
X1306292Y411283D01*
X1306167Y410908D01*
Y410492D01*
X1306083Y410242D01*
X1305875Y410033D01*
X1305583Y409950D01*
X1305292Y410075D01*
X1305083Y410367D01*
X1305000Y410700D01*
X1305083Y411033D01*
X1305292Y411325D01*
X1305583Y411450D01*
X1305875Y411367D01*
X1306083Y411158D01*
X1306167Y410908D01*
Y410492D01*
X1306292Y410117D01*
X1306542Y409867D01*
X1306833Y409783D01*
X1307125Y409867D01*
X1307333Y410075D01*
X1307458Y410408D01*
X1307500Y410700D01*
G01X1303500Y388300D02*
X1307500D01*
Y395700D01*
G01X1291500Y397467D02*
X1289000D01*
Y398508D01*
X1289125Y398842D01*
X1289292Y399050D01*
X1289625Y399133D01*
X1289958Y399050D01*
X1290167Y398800D01*
X1290292Y398508D01*
Y397467D01*
G01Y398508D02*
X1291500Y399133D01*
G01Y401900D02*
X1289000D01*
X1290792Y400358D01*
Y402442D01*
G01X1291500Y404500D02*
X1289000D01*
X1289500Y404000D01*
G01X1291500D02*
Y405000D01*
G01Y407517D02*
X1290958Y407600D01*
X1290500Y407725D01*
X1290083Y407892D01*
X1289625Y408100D01*
X1289000Y408433D01*
Y406767D01*
G01X1291000Y409783D02*
X1291292Y410033D01*
X1291458Y410367D01*
X1291500Y410742D01*
X1291458Y411075D01*
X1291250Y411408D01*
X1291000Y411617D01*
X1290750Y411658D01*
X1290458Y411575D01*
X1290250Y411283D01*
X1290167Y410992D01*
Y410617D01*
G01Y410992D02*
X1290042Y411242D01*
X1289833Y411450D01*
X1289583Y411533D01*
X1289333Y411450D01*
X1289125Y411242D01*
X1289000Y410867D01*
X1289042Y410492D01*
X1289208Y410117D01*
G01X1287500Y388300D02*
X1291500D01*
Y395700D01*
G01X1311972Y645945D02*
X1309472D01*
Y646986D01*
X1309597Y647320D01*
X1309764Y647528D01*
X1310097Y647611D01*
X1310430Y647528D01*
X1310639Y647278D01*
X1310764Y646986D01*
Y645945D01*
G01Y646986D02*
X1311972Y647611D01*
G01Y649795D02*
X1311430Y649878D01*
X1310972Y650003D01*
X1310555Y650170D01*
X1310097Y650378D01*
X1309472Y650711D01*
Y649045D01*
G01X1311680Y652270D02*
X1311889Y652561D01*
X1311972Y652895D01*
X1311889Y653228D01*
X1311639Y653520D01*
X1311264Y653728D01*
X1310889Y653811D01*
X1310430D01*
X1310055Y653728D01*
X1309722Y653520D01*
X1309555Y653270D01*
X1309472Y652978D01*
X1309555Y652645D01*
X1309722Y652395D01*
X1309972Y652228D01*
X1310305Y652145D01*
X1310597Y652228D01*
X1310889Y652436D01*
X1311055Y652686D01*
X1311097Y652978D01*
X1311014Y653311D01*
X1310805Y653561D01*
X1310430Y653811D01*
G01X1309889Y655286D02*
X1309639Y655536D01*
X1309514Y655828D01*
X1309472Y656161D01*
X1309555Y656578D01*
X1309764Y656870D01*
X1310014Y656953D01*
X1310264Y656911D01*
X1310472Y656745D01*
X1310889Y655911D01*
X1311180Y655536D01*
X1311597Y655286D01*
X1311972Y655203D01*
Y656953D01*
G01Y659678D02*
X1309472D01*
X1311264Y658136D01*
Y660220D01*
G01X1303568Y645947D02*
X1301068D01*
Y646988D01*
X1301193Y647322D01*
X1301360Y647530D01*
X1301693Y647613D01*
X1302026Y647530D01*
X1302235Y647280D01*
X1302360Y646988D01*
Y645947D01*
G01Y646988D02*
X1303568Y647613D01*
G01X1303193Y648963D02*
X1303401Y649213D01*
X1303526Y649505D01*
X1303568Y649880D01*
X1303485Y650255D01*
X1303318Y650547D01*
X1303026Y650755D01*
X1302693Y650797D01*
X1302360Y650713D01*
X1302151Y650505D01*
X1301985Y650213D01*
X1301943Y649922D01*
X1301985Y649630D01*
X1302151Y649255D01*
X1301068Y649380D01*
Y650505D01*
G01X1303568Y652897D02*
X1303026Y652980D01*
X1302568Y653105D01*
X1302151Y653272D01*
X1301693Y653480D01*
X1301068Y653813D01*
Y652147D01*
G01X1303193Y655163D02*
X1303401Y655413D01*
X1303526Y655705D01*
X1303568Y656080D01*
X1303485Y656455D01*
X1303318Y656747D01*
X1303026Y656955D01*
X1302693Y656997D01*
X1302360Y656913D01*
X1302151Y656705D01*
X1301985Y656413D01*
X1301943Y656122D01*
X1301985Y655830D01*
X1302151Y655455D01*
X1301068Y655580D01*
Y656705D01*
G01X1307568Y645947D02*
X1305068D01*
Y646988D01*
X1305193Y647322D01*
X1305360Y647530D01*
X1305693Y647613D01*
X1306026Y647530D01*
X1306235Y647280D01*
X1306360Y646988D01*
Y645947D01*
G01Y646988D02*
X1307568Y647613D01*
G01X1307193Y648963D02*
X1307401Y649213D01*
X1307526Y649505D01*
X1307568Y649880D01*
X1307485Y650255D01*
X1307318Y650547D01*
X1307026Y650755D01*
X1306693Y650797D01*
X1306360Y650713D01*
X1306151Y650505D01*
X1305985Y650213D01*
X1305943Y649922D01*
X1305985Y649630D01*
X1306151Y649255D01*
X1305068Y649380D01*
Y650505D01*
G01X1307568Y652897D02*
X1307026Y652980D01*
X1306568Y653105D01*
X1306151Y653272D01*
X1305693Y653480D01*
X1305068Y653813D01*
Y652147D01*
G01X1307568Y656580D02*
X1305068D01*
X1306860Y655038D01*
Y657122D01*
G01X1316128Y682567D02*
X1312128D01*
Y675167D01*
G01Y682567D02*
X1308128D01*
Y675167D01*
G01X1300128D02*
X1304128D01*
Y682567D01*
G01Y675167D02*
X1308128D01*
Y682567D01*
G01X1289547Y708174D02*
Y706382D01*
X1289714Y706007D01*
X1290047Y705757D01*
X1290464Y705674D01*
X1290881Y705757D01*
X1291214Y706007D01*
X1291381Y706382D01*
Y708174D01*
G01X1292772Y707757D02*
X1293022Y708007D01*
X1293314Y708132D01*
X1293647Y708174D01*
X1294064Y708091D01*
X1294356Y707882D01*
X1294439Y707632D01*
X1294397Y707382D01*
X1294231Y707174D01*
X1293397Y706757D01*
X1293022Y706466D01*
X1292772Y706049D01*
X1292689Y705674D01*
X1294439D01*
G01X1296664Y708174D02*
X1296331Y708091D01*
X1296081Y707882D01*
X1295914Y707632D01*
X1295789Y707299D01*
X1295747Y706924D01*
X1295789Y706549D01*
X1295914Y706216D01*
X1296081Y705966D01*
X1296331Y705757D01*
X1296664Y705674D01*
X1296997Y705757D01*
X1297247Y705966D01*
X1297414Y706216D01*
X1297539Y706549D01*
X1297581Y706924D01*
X1297539Y707299D01*
X1297414Y707632D01*
X1297247Y707882D01*
X1296997Y708091D01*
X1296664Y708174D01*
G01X1299764Y705674D02*
Y708174D01*
X1299264Y707674D01*
G01Y705674D02*
X1300264D01*
G01X1334128Y696867D02*
X1303428D01*
G01Y710867D02*
X1334128D01*
G01X1303428D02*
Y696867D01*
G01X1304528Y703867D02*
X1303428Y704967D01*
G01X1304528Y703867D02*
X1303428Y702767D01*
G01X1312800Y745398D02*
Y742898D01*
G01X1311842Y745398D02*
X1313758D01*
G01X1315067Y742898D02*
Y745398D01*
X1316067D01*
X1316400Y745273D01*
X1316650Y744981D01*
X1316733Y744648D01*
X1316650Y744315D01*
X1316442Y744065D01*
X1316067Y743940D01*
X1315067D01*
G01X1319000Y742898D02*
Y745398D01*
X1318500Y744898D01*
G01Y742898D02*
X1319500D01*
G01X1322100D02*
X1322392Y742940D01*
X1322725Y743065D01*
X1322933Y743273D01*
X1323017Y743565D01*
X1322933Y743856D01*
X1322683Y744106D01*
X1322308Y744231D01*
X1321892D01*
X1321642Y744315D01*
X1321433Y744523D01*
X1321350Y744815D01*
X1321475Y745106D01*
X1321767Y745315D01*
X1322100Y745398D01*
X1322433Y745315D01*
X1322725Y745106D01*
X1322850Y744815D01*
X1322767Y744523D01*
X1322558Y744315D01*
X1322308Y744231D01*
X1321892D01*
X1321517Y744106D01*
X1321267Y743856D01*
X1321183Y743565D01*
X1321267Y743273D01*
X1321475Y743065D01*
X1321808Y742940D01*
X1322100Y742898D01*
G01X1325700D02*
Y745398D01*
X1324158Y743606D01*
X1326242D01*
G01X1312800Y749404D02*
Y746904D01*
G01X1311842Y749404D02*
X1313758D01*
G01X1315067Y746904D02*
Y749404D01*
X1316067D01*
X1316400Y749279D01*
X1316650Y748987D01*
X1316733Y748654D01*
X1316650Y748321D01*
X1316442Y748071D01*
X1316067Y747946D01*
X1315067D01*
G01X1319000Y746904D02*
Y749404D01*
X1318500Y748904D01*
G01Y746904D02*
X1319500D01*
G01X1321308Y747946D02*
X1321600Y748237D01*
X1321850Y748404D01*
X1322183Y748487D01*
X1322475Y748404D01*
X1322683Y748237D01*
X1322850Y747987D01*
X1322892Y747696D01*
X1322850Y747446D01*
X1322683Y747196D01*
X1322433Y746987D01*
X1322142Y746904D01*
X1321808Y746987D01*
X1321517Y747237D01*
X1321350Y747612D01*
X1321308Y748029D01*
X1321392Y748571D01*
X1321517Y748862D01*
X1321725Y749154D01*
X1322017Y749362D01*
X1322308Y749404D01*
X1322600Y749321D01*
X1322808Y749112D01*
G01X1325117Y746904D02*
X1325200Y747446D01*
X1325325Y747904D01*
X1325492Y748321D01*
X1325700Y748779D01*
X1326033Y749404D01*
X1324367D01*
G01X1309600Y735467D02*
X1307100D01*
Y736508D01*
X1307225Y736842D01*
X1307392Y737050D01*
X1307725Y737133D01*
X1308058Y737050D01*
X1308267Y736800D01*
X1308392Y736508D01*
Y735467D01*
G01Y736508D02*
X1309600Y737133D01*
G01Y739317D02*
X1309058Y739400D01*
X1308600Y739525D01*
X1308183Y739692D01*
X1307725Y739900D01*
X1307100Y740233D01*
Y738567D01*
G01X1309308Y741792D02*
X1309517Y742083D01*
X1309600Y742417D01*
X1309517Y742750D01*
X1309267Y743042D01*
X1308892Y743250D01*
X1308517Y743333D01*
X1308058D01*
X1307683Y743250D01*
X1307350Y743042D01*
X1307183Y742792D01*
X1307100Y742500D01*
X1307183Y742167D01*
X1307350Y741917D01*
X1307600Y741750D01*
X1307933Y741667D01*
X1308225Y741750D01*
X1308517Y741958D01*
X1308683Y742208D01*
X1308725Y742500D01*
X1308642Y742833D01*
X1308433Y743083D01*
X1308058Y743333D01*
G01X1309308Y744892D02*
X1309517Y745183D01*
X1309600Y745517D01*
X1309517Y745850D01*
X1309267Y746142D01*
X1308892Y746350D01*
X1308517Y746433D01*
X1308058D01*
X1307683Y746350D01*
X1307350Y746142D01*
X1307183Y745892D01*
X1307100Y745600D01*
X1307183Y745267D01*
X1307350Y745017D01*
X1307600Y744850D01*
X1307933Y744767D01*
X1308225Y744850D01*
X1308517Y745058D01*
X1308683Y745308D01*
X1308725Y745600D01*
X1308642Y745933D01*
X1308433Y746183D01*
X1308058Y746433D01*
G01X1309308Y747992D02*
X1309517Y748283D01*
X1309600Y748617D01*
X1309517Y748950D01*
X1309267Y749242D01*
X1308892Y749450D01*
X1308517Y749533D01*
X1308058D01*
X1307683Y749450D01*
X1307350Y749242D01*
X1307183Y748992D01*
X1307100Y748700D01*
X1307183Y748367D01*
X1307350Y748117D01*
X1307600Y747950D01*
X1307933Y747867D01*
X1308225Y747950D01*
X1308517Y748158D01*
X1308683Y748408D01*
X1308725Y748700D01*
X1308642Y749033D01*
X1308433Y749283D01*
X1308058Y749533D01*
G01X1302200Y735367D02*
X1299700D01*
Y736408D01*
X1299825Y736742D01*
X1299992Y736950D01*
X1300325Y737033D01*
X1300658Y736950D01*
X1300867Y736700D01*
X1300992Y736408D01*
Y735367D01*
G01Y736408D02*
X1302200Y737033D01*
G01Y739217D02*
X1301658Y739300D01*
X1301200Y739425D01*
X1300783Y739592D01*
X1300325Y739800D01*
X1299700Y740133D01*
Y738467D01*
G01X1301908Y741692D02*
X1302117Y741983D01*
X1302200Y742317D01*
X1302117Y742650D01*
X1301867Y742942D01*
X1301492Y743150D01*
X1301117Y743233D01*
X1300658D01*
X1300283Y743150D01*
X1299950Y742942D01*
X1299783Y742692D01*
X1299700Y742400D01*
X1299783Y742067D01*
X1299950Y741817D01*
X1300200Y741650D01*
X1300533Y741567D01*
X1300825Y741650D01*
X1301117Y741858D01*
X1301283Y742108D01*
X1301325Y742400D01*
X1301242Y742733D01*
X1301033Y742983D01*
X1300658Y743233D01*
G01X1301158Y744708D02*
X1300867Y745000D01*
X1300700Y745250D01*
X1300617Y745583D01*
X1300700Y745875D01*
X1300867Y746083D01*
X1301117Y746250D01*
X1301408Y746292D01*
X1301658Y746250D01*
X1301908Y746083D01*
X1302117Y745833D01*
X1302200Y745542D01*
X1302117Y745208D01*
X1301867Y744917D01*
X1301492Y744750D01*
X1301075Y744708D01*
X1300533Y744792D01*
X1300242Y744917D01*
X1299950Y745125D01*
X1299742Y745417D01*
X1299700Y745708D01*
X1299783Y746000D01*
X1299992Y746208D01*
G01X1301158Y747808D02*
X1300867Y748100D01*
X1300700Y748350D01*
X1300617Y748683D01*
X1300700Y748975D01*
X1300867Y749183D01*
X1301117Y749350D01*
X1301408Y749392D01*
X1301658Y749350D01*
X1301908Y749183D01*
X1302117Y748933D01*
X1302200Y748642D01*
X1302117Y748308D01*
X1301867Y748017D01*
X1301492Y747850D01*
X1301075Y747808D01*
X1300533Y747892D01*
X1300242Y748017D01*
X1299950Y748225D01*
X1299742Y748517D01*
X1299700Y748808D01*
X1299783Y749100D01*
X1299992Y749308D01*
G01X1308128Y731567D02*
X1304128D01*
Y724167D01*
G01X1298000Y735367D02*
X1295500D01*
Y736408D01*
X1295625Y736742D01*
X1295792Y736950D01*
X1296125Y737033D01*
X1296458Y736950D01*
X1296667Y736700D01*
X1296792Y736408D01*
Y735367D01*
G01Y736408D02*
X1298000Y737033D01*
G01Y739217D02*
X1297458Y739300D01*
X1297000Y739425D01*
X1296583Y739592D01*
X1296125Y739800D01*
X1295500Y740133D01*
Y738467D01*
G01X1297708Y741692D02*
X1297917Y741983D01*
X1298000Y742317D01*
X1297917Y742650D01*
X1297667Y742942D01*
X1297292Y743150D01*
X1296917Y743233D01*
X1296458D01*
X1296083Y743150D01*
X1295750Y742942D01*
X1295583Y742692D01*
X1295500Y742400D01*
X1295583Y742067D01*
X1295750Y741817D01*
X1296000Y741650D01*
X1296333Y741567D01*
X1296625Y741650D01*
X1296917Y741858D01*
X1297083Y742108D01*
X1297125Y742400D01*
X1297042Y742733D01*
X1296833Y742983D01*
X1296458Y743233D01*
G01X1295917Y744708D02*
X1295667Y744958D01*
X1295542Y745250D01*
X1295500Y745583D01*
X1295583Y746000D01*
X1295792Y746292D01*
X1296042Y746375D01*
X1296292Y746333D01*
X1296500Y746167D01*
X1296917Y745333D01*
X1297208Y744958D01*
X1297625Y744708D01*
X1298000Y744625D01*
Y746375D01*
G01X1295500Y748600D02*
X1295583Y748267D01*
X1295792Y748017D01*
X1296042Y747850D01*
X1296375Y747725D01*
X1296750Y747683D01*
X1297125Y747725D01*
X1297458Y747850D01*
X1297708Y748017D01*
X1297917Y748267D01*
X1298000Y748600D01*
X1297917Y748933D01*
X1297708Y749183D01*
X1297458Y749350D01*
X1297125Y749475D01*
X1296750Y749517D01*
X1296375Y749475D01*
X1296042Y749350D01*
X1295792Y749183D01*
X1295583Y748933D01*
X1295500Y748600D01*
G01X1304128Y731567D02*
X1300128D01*
Y724167D01*
G01X1306000Y735417D02*
X1303500D01*
Y736458D01*
X1303625Y736792D01*
X1303792Y737000D01*
X1304125Y737083D01*
X1304458Y737000D01*
X1304667Y736750D01*
X1304792Y736458D01*
Y735417D01*
G01Y736458D02*
X1306000Y737083D01*
G01X1305625Y738433D02*
X1305833Y738683D01*
X1305958Y738975D01*
X1306000Y739350D01*
X1305917Y739725D01*
X1305750Y740017D01*
X1305458Y740225D01*
X1305125Y740267D01*
X1304792Y740183D01*
X1304583Y739975D01*
X1304417Y739683D01*
X1304375Y739392D01*
X1304417Y739100D01*
X1304583Y738725D01*
X1303500Y738850D01*
Y739975D01*
G01X1304958Y741658D02*
X1304667Y741950D01*
X1304500Y742200D01*
X1304417Y742533D01*
X1304500Y742825D01*
X1304667Y743033D01*
X1304917Y743200D01*
X1305208Y743242D01*
X1305458Y743200D01*
X1305708Y743033D01*
X1305917Y742783D01*
X1306000Y742492D01*
X1305917Y742158D01*
X1305667Y741867D01*
X1305292Y741700D01*
X1304875Y741658D01*
X1304333Y741742D01*
X1304042Y741867D01*
X1303750Y742075D01*
X1303542Y742367D01*
X1303500Y742658D01*
X1303583Y742950D01*
X1303792Y743158D01*
G01X1305500Y744633D02*
X1305792Y744883D01*
X1305958Y745217D01*
X1306000Y745592D01*
X1305958Y745925D01*
X1305750Y746258D01*
X1305500Y746467D01*
X1305250Y746508D01*
X1304958Y746425D01*
X1304750Y746133D01*
X1304667Y745842D01*
Y745467D01*
G01Y745842D02*
X1304542Y746092D01*
X1304333Y746300D01*
X1304083Y746383D01*
X1303833Y746300D01*
X1303625Y746092D01*
X1303500Y745717D01*
X1303542Y745342D01*
X1303708Y744967D01*
G01X1312200Y731600D02*
X1308200D01*
Y724200D01*
G01X1292108Y737067D02*
X1291983Y736817D01*
X1291900Y736525D01*
Y736192D01*
X1292025Y735817D01*
X1292233Y735525D01*
X1292483Y735317D01*
X1292900Y735150D01*
X1293275Y735108D01*
X1293650Y735192D01*
X1293900Y735317D01*
X1294150Y735567D01*
X1294317Y735858D01*
X1294400Y736150D01*
Y736442D01*
X1294317Y736733D01*
X1294192Y736983D01*
X1294025Y737192D01*
G01X1294400Y739750D02*
X1291900D01*
X1293692Y738208D01*
Y740292D01*
G01X1294400Y742350D02*
X1291900D01*
X1292400Y741850D01*
G01X1294400D02*
Y742850D01*
G01Y745367D02*
X1293858Y745450D01*
X1293400Y745575D01*
X1292983Y745742D01*
X1292525Y745950D01*
X1291900Y746283D01*
Y744617D01*
G01X1312800Y753409D02*
Y750909D01*
G01X1311842Y753409D02*
X1313758D01*
G01X1315067Y750909D02*
Y753409D01*
X1316067D01*
X1316400Y753284D01*
X1316650Y752992D01*
X1316733Y752659D01*
X1316650Y752326D01*
X1316442Y752076D01*
X1316067Y751951D01*
X1315067D01*
G01X1319000Y750909D02*
Y753409D01*
X1318500Y752909D01*
G01Y750909D02*
X1319500D01*
G01X1321308Y751951D02*
X1321600Y752242D01*
X1321850Y752409D01*
X1322183Y752492D01*
X1322475Y752409D01*
X1322683Y752242D01*
X1322850Y751992D01*
X1322892Y751701D01*
X1322850Y751451D01*
X1322683Y751201D01*
X1322433Y750992D01*
X1322142Y750909D01*
X1321808Y750992D01*
X1321517Y751242D01*
X1321350Y751617D01*
X1321308Y752034D01*
X1321392Y752576D01*
X1321517Y752867D01*
X1321725Y753159D01*
X1322017Y753367D01*
X1322308Y753409D01*
X1322600Y753326D01*
X1322808Y753117D01*
G01X1324492Y751201D02*
X1324783Y750992D01*
X1325117Y750909D01*
X1325450Y750992D01*
X1325742Y751242D01*
X1325950Y751617D01*
X1326033Y751992D01*
Y752451D01*
X1325950Y752826D01*
X1325742Y753159D01*
X1325492Y753326D01*
X1325200Y753409D01*
X1324867Y753326D01*
X1324617Y753159D01*
X1324450Y752909D01*
X1324367Y752576D01*
X1324450Y752284D01*
X1324658Y751992D01*
X1324908Y751826D01*
X1325200Y751784D01*
X1325533Y751867D01*
X1325783Y752076D01*
X1326033Y752451D01*
G01X1303806Y808530D02*
X1303556Y808655D01*
X1303264Y808738D01*
X1302931D01*
X1302556Y808613D01*
X1302264Y808405D01*
X1302056Y808155D01*
X1301889Y807738D01*
X1301847Y807363D01*
X1301931Y806988D01*
X1302056Y806738D01*
X1302306Y806488D01*
X1302597Y806321D01*
X1302889Y806238D01*
X1303181D01*
X1303472Y806321D01*
X1303722Y806446D01*
X1303931Y806613D01*
G01X1306489Y806238D02*
Y808738D01*
X1304947Y806946D01*
X1307031D01*
G01X1309089Y806238D02*
Y808738D01*
X1308589Y808238D01*
G01Y806238D02*
X1309589D01*
G01X1311272Y806613D02*
X1311522Y806405D01*
X1311814Y806280D01*
X1312189Y806238D01*
X1312564Y806321D01*
X1312856Y806488D01*
X1313064Y806780D01*
X1313106Y807113D01*
X1313022Y807446D01*
X1312814Y807655D01*
X1312522Y807821D01*
X1312231Y807863D01*
X1311939Y807821D01*
X1311564Y807655D01*
X1311689Y808738D01*
X1312814D01*
G01X1314497Y807280D02*
X1314789Y807571D01*
X1315039Y807738D01*
X1315372Y807821D01*
X1315664Y807738D01*
X1315872Y807571D01*
X1316039Y807321D01*
X1316081Y807030D01*
X1316039Y806780D01*
X1315872Y806530D01*
X1315622Y806321D01*
X1315331Y806238D01*
X1314997Y806321D01*
X1314706Y806571D01*
X1314539Y806946D01*
X1314497Y807363D01*
X1314581Y807905D01*
X1314706Y808196D01*
X1314914Y808488D01*
X1315206Y808696D01*
X1315497Y808738D01*
X1315789Y808655D01*
X1315997Y808446D01*
G01X1286966Y818195D02*
X1286841Y817945D01*
X1286758Y817653D01*
Y817320D01*
X1286883Y816945D01*
X1287091Y816653D01*
X1287341Y816445D01*
X1287758Y816278D01*
X1288133Y816236D01*
X1288508Y816320D01*
X1288758Y816445D01*
X1289008Y816695D01*
X1289175Y816986D01*
X1289258Y817278D01*
Y817570D01*
X1289175Y817861D01*
X1289050Y818111D01*
X1288883Y818320D01*
G01X1288216Y819586D02*
X1287925Y819878D01*
X1287758Y820128D01*
X1287675Y820461D01*
X1287758Y820753D01*
X1287925Y820961D01*
X1288175Y821128D01*
X1288466Y821170D01*
X1288716Y821128D01*
X1288966Y820961D01*
X1289175Y820711D01*
X1289258Y820420D01*
X1289175Y820086D01*
X1288925Y819795D01*
X1288550Y819628D01*
X1288133Y819586D01*
X1287591Y819670D01*
X1287300Y819795D01*
X1287008Y820003D01*
X1286800Y820295D01*
X1286758Y820586D01*
X1286841Y820878D01*
X1287050Y821086D01*
G01X1288758Y822561D02*
X1289050Y822811D01*
X1289216Y823145D01*
X1289258Y823520D01*
X1289216Y823853D01*
X1289008Y824186D01*
X1288758Y824395D01*
X1288508Y824436D01*
X1288216Y824353D01*
X1288008Y824061D01*
X1287925Y823770D01*
Y823395D01*
G01Y823770D02*
X1287800Y824020D01*
X1287591Y824228D01*
X1287341Y824311D01*
X1287091Y824228D01*
X1286883Y824020D01*
X1286758Y823645D01*
X1286800Y823270D01*
X1286966Y822895D01*
G01X1282966Y818195D02*
X1282841Y817945D01*
X1282758Y817653D01*
Y817320D01*
X1282883Y816945D01*
X1283091Y816653D01*
X1283341Y816445D01*
X1283758Y816278D01*
X1284133Y816236D01*
X1284508Y816320D01*
X1284758Y816445D01*
X1285008Y816695D01*
X1285175Y816986D01*
X1285258Y817278D01*
Y817570D01*
X1285175Y817861D01*
X1285050Y818111D01*
X1284883Y818320D01*
G01X1284216Y819586D02*
X1283925Y819878D01*
X1283758Y820128D01*
X1283675Y820461D01*
X1283758Y820753D01*
X1283925Y820961D01*
X1284175Y821128D01*
X1284466Y821170D01*
X1284716Y821128D01*
X1284966Y820961D01*
X1285175Y820711D01*
X1285258Y820420D01*
X1285175Y820086D01*
X1284925Y819795D01*
X1284550Y819628D01*
X1284133Y819586D01*
X1283591Y819670D01*
X1283300Y819795D01*
X1283008Y820003D01*
X1282800Y820295D01*
X1282758Y820586D01*
X1282841Y820878D01*
X1283050Y821086D01*
G01X1283175Y822686D02*
X1282925Y822936D01*
X1282800Y823228D01*
X1282758Y823561D01*
X1282841Y823978D01*
X1283050Y824270D01*
X1283300Y824353D01*
X1283550Y824311D01*
X1283758Y824145D01*
X1284175Y823311D01*
X1284466Y822936D01*
X1284883Y822686D01*
X1285258Y822603D01*
Y824353D01*
G01X1309739Y818005D02*
X1309614Y817755D01*
X1309531Y817463D01*
Y817130D01*
X1309656Y816755D01*
X1309864Y816463D01*
X1310114Y816255D01*
X1310531Y816088D01*
X1310906Y816046D01*
X1311281Y816130D01*
X1311531Y816255D01*
X1311781Y816505D01*
X1311948Y816796D01*
X1312031Y817088D01*
Y817380D01*
X1311948Y817671D01*
X1311823Y817921D01*
X1311656Y818130D01*
G01X1310989Y819396D02*
X1310698Y819688D01*
X1310531Y819938D01*
X1310448Y820271D01*
X1310531Y820563D01*
X1310698Y820771D01*
X1310948Y820938D01*
X1311239Y820980D01*
X1311489Y820938D01*
X1311739Y820771D01*
X1311948Y820521D01*
X1312031Y820230D01*
X1311948Y819896D01*
X1311698Y819605D01*
X1311323Y819438D01*
X1310906Y819396D01*
X1310364Y819480D01*
X1310073Y819605D01*
X1309781Y819813D01*
X1309573Y820105D01*
X1309531Y820396D01*
X1309614Y820688D01*
X1309823Y820896D01*
G01X1309531Y823288D02*
X1309614Y822955D01*
X1309823Y822705D01*
X1310073Y822538D01*
X1310406Y822413D01*
X1310781Y822371D01*
X1311156Y822413D01*
X1311489Y822538D01*
X1311739Y822705D01*
X1311948Y822955D01*
X1312031Y823288D01*
X1311948Y823621D01*
X1311739Y823871D01*
X1311489Y824038D01*
X1311156Y824163D01*
X1310781Y824205D01*
X1310406Y824163D01*
X1310073Y824038D01*
X1309823Y823871D01*
X1309614Y823621D01*
X1309531Y823288D01*
G01X1342000Y120517D02*
X1339500D01*
Y121558D01*
X1339625Y121892D01*
X1339792Y122100D01*
X1340125Y122183D01*
X1340458Y122100D01*
X1340667Y121850D01*
X1340792Y121558D01*
Y120517D01*
G01Y121558D02*
X1342000Y122183D01*
G01X1340958Y123658D02*
X1340667Y123950D01*
X1340500Y124200D01*
X1340417Y124533D01*
X1340500Y124825D01*
X1340667Y125033D01*
X1340917Y125200D01*
X1341208Y125242D01*
X1341458Y125200D01*
X1341708Y125033D01*
X1341917Y124783D01*
X1342000Y124492D01*
X1341917Y124158D01*
X1341667Y123867D01*
X1341292Y123700D01*
X1340875Y123658D01*
X1340333Y123742D01*
X1340042Y123867D01*
X1339750Y124075D01*
X1339542Y124367D01*
X1339500Y124658D01*
X1339583Y124950D01*
X1339792Y125158D01*
G01X1339917Y126758D02*
X1339667Y127008D01*
X1339542Y127300D01*
X1339500Y127633D01*
X1339583Y128050D01*
X1339792Y128342D01*
X1340042Y128425D01*
X1340292Y128383D01*
X1340500Y128217D01*
X1340917Y127383D01*
X1341208Y127008D01*
X1341625Y126758D01*
X1342000Y126675D01*
Y128425D01*
G01Y130567D02*
X1341458Y130650D01*
X1341000Y130775D01*
X1340583Y130942D01*
X1340125Y131150D01*
X1339500Y131483D01*
Y129817D01*
G01X1333071Y132411D02*
X1337071D01*
Y139811D01*
G01X1337100Y147370D02*
X1333100D01*
Y139970D01*
G01X1332030Y137509D02*
Y151509D01*
G01X1319030Y137509D02*
X1332030D01*
G01X1319030Y151509D02*
Y137509D01*
G01X1336334Y121140D02*
X1336292Y120807D01*
X1336126Y120515D01*
X1335876Y120265D01*
X1335584Y120098D01*
X1335251Y120015D01*
X1334917D01*
X1334584Y120098D01*
X1334292Y120265D01*
X1334042Y120515D01*
X1333876Y120807D01*
X1333834Y121140D01*
X1333876Y121473D01*
X1334042Y121765D01*
X1334292Y122015D01*
X1334584Y122182D01*
X1334917Y122265D01*
X1335251D01*
X1335584Y122182D01*
X1335876Y122015D01*
X1336126Y121765D01*
X1336292Y121473D01*
X1336334Y121140D01*
G01X1335667Y121473D02*
X1336334Y121973D01*
G01X1334251Y123448D02*
X1334001Y123698D01*
X1333876Y123990D01*
X1333834Y124323D01*
X1333917Y124740D01*
X1334126Y125032D01*
X1334376Y125115D01*
X1334626Y125073D01*
X1334834Y124907D01*
X1335251Y124073D01*
X1335542Y123698D01*
X1335959Y123448D01*
X1336334Y123365D01*
Y125115D01*
G01X1336042Y126632D02*
X1336251Y126923D01*
X1336334Y127257D01*
X1336251Y127590D01*
X1336001Y127882D01*
X1335626Y128090D01*
X1335251Y128173D01*
X1334792D01*
X1334417Y128090D01*
X1334084Y127882D01*
X1333917Y127632D01*
X1333834Y127340D01*
X1333917Y127007D01*
X1334084Y126757D01*
X1334334Y126590D01*
X1334667Y126507D01*
X1334959Y126590D01*
X1335251Y126798D01*
X1335417Y127048D01*
X1335459Y127340D01*
X1335376Y127673D01*
X1335167Y127923D01*
X1334792Y128173D01*
G01X1331720Y118620D02*
Y132620D01*
G01X1318720Y118620D02*
X1331720D01*
G01X1318720Y132620D02*
Y118620D01*
G01X1331720Y132620D02*
X1318720D01*
G01X1317720Y128810D02*
Y141810D01*
G01X1333199Y153878D02*
X1333532Y153670D01*
X1333907Y153545D01*
X1334241D01*
X1334574Y153670D01*
X1334824Y153878D01*
X1334949Y154170D01*
X1334866Y154462D01*
X1334657Y154712D01*
X1334282Y154878D01*
X1333782Y154962D01*
X1333491Y155128D01*
X1333366Y155420D01*
X1333449Y155712D01*
X1333657Y155920D01*
X1333949Y156045D01*
X1334241D01*
X1334532Y155962D01*
X1334782Y155753D01*
G01X1335924Y156045D02*
X1336507Y153545D01*
X1337174Y156045D01*
X1337841Y153545D01*
X1338424Y156045D01*
G01X1340274Y153545D02*
Y156045D01*
X1339774Y155545D01*
G01Y153545D02*
X1340774D01*
G01X1319390Y157300D02*
X1352590D01*
Y183700D01*
X1319390D01*
Y157300D01*
G01X1335990Y180500D02*
Y173500D01*
G01Y167500D02*
Y160500D01*
G01Y173500D02*
X1337990Y168500D01*
G01X1336290Y173500D02*
G03I-300J0D01*
G01Y167500D02*
G03I-300J0D01*
G01X1334252Y149370D02*
Y151870D01*
X1335293D01*
X1335627Y151745D01*
X1335835Y151578D01*
X1335918Y151245D01*
X1335835Y150912D01*
X1335585Y150703D01*
X1335293Y150578D01*
X1334252D01*
G01X1335293D02*
X1335918Y149370D01*
G01X1337393Y150412D02*
X1337685Y150703D01*
X1337935Y150870D01*
X1338268Y150953D01*
X1338560Y150870D01*
X1338768Y150703D01*
X1338935Y150453D01*
X1338977Y150162D01*
X1338935Y149912D01*
X1338768Y149662D01*
X1338518Y149453D01*
X1338227Y149370D01*
X1337893Y149453D01*
X1337602Y149703D01*
X1337435Y150078D01*
X1337393Y150495D01*
X1337477Y151037D01*
X1337602Y151328D01*
X1337810Y151620D01*
X1338102Y151828D01*
X1338393Y151870D01*
X1338685Y151787D01*
X1338893Y151578D01*
G01X1340493Y151453D02*
X1340743Y151703D01*
X1341035Y151828D01*
X1341368Y151870D01*
X1341785Y151787D01*
X1342077Y151578D01*
X1342160Y151328D01*
X1342118Y151078D01*
X1341952Y150870D01*
X1341118Y150453D01*
X1340743Y150162D01*
X1340493Y149745D01*
X1340410Y149370D01*
X1342160D01*
G01X1343593Y150412D02*
X1343885Y150703D01*
X1344135Y150870D01*
X1344468Y150953D01*
X1344760Y150870D01*
X1344968Y150703D01*
X1345135Y150453D01*
X1345177Y150162D01*
X1345135Y149912D01*
X1344968Y149662D01*
X1344718Y149453D01*
X1344427Y149370D01*
X1344093Y149453D01*
X1343802Y149703D01*
X1343635Y150078D01*
X1343593Y150495D01*
X1343677Y151037D01*
X1343802Y151328D01*
X1344010Y151620D01*
X1344302Y151828D01*
X1344593Y151870D01*
X1344885Y151787D01*
X1345093Y151578D01*
G01X1322950Y153076D02*
X1322617Y153118D01*
X1322325Y153284D01*
X1322075Y153534D01*
X1321908Y153826D01*
X1321825Y154159D01*
Y154493D01*
X1321908Y154826D01*
X1322075Y155118D01*
X1322325Y155368D01*
X1322617Y155534D01*
X1322950Y155576D01*
X1323283Y155534D01*
X1323575Y155368D01*
X1323825Y155118D01*
X1323992Y154826D01*
X1324075Y154493D01*
Y154159D01*
X1323992Y153826D01*
X1323825Y153534D01*
X1323575Y153284D01*
X1323283Y153118D01*
X1322950Y153076D01*
G01X1323283Y153743D02*
X1323783Y153076D01*
G01X1325258Y155159D02*
X1325508Y155409D01*
X1325800Y155534D01*
X1326133Y155576D01*
X1326550Y155493D01*
X1326842Y155284D01*
X1326925Y155034D01*
X1326883Y154784D01*
X1326717Y154576D01*
X1325883Y154159D01*
X1325508Y153868D01*
X1325258Y153451D01*
X1325175Y153076D01*
X1326925D01*
G01X1329150D02*
X1329442Y153118D01*
X1329775Y153243D01*
X1329983Y153451D01*
X1330067Y153743D01*
X1329983Y154034D01*
X1329733Y154284D01*
X1329358Y154409D01*
X1328942D01*
X1328692Y154493D01*
X1328483Y154701D01*
X1328400Y154993D01*
X1328525Y155284D01*
X1328817Y155493D01*
X1329150Y155576D01*
X1329483Y155493D01*
X1329775Y155284D01*
X1329900Y154993D01*
X1329817Y154701D01*
X1329608Y154493D01*
X1329358Y154409D01*
X1328942D01*
X1328567Y154284D01*
X1328317Y154034D01*
X1328233Y153743D01*
X1328317Y153451D01*
X1328525Y153243D01*
X1328858Y153118D01*
X1329150Y153076D01*
G01X1332030Y151509D02*
X1319030D01*
G01X1330150Y197650D02*
X1348850D01*
Y187350D01*
X1330150D01*
Y197650D01*
G01Y210150D02*
X1348850D01*
Y199850D01*
X1330150D01*
Y210150D01*
G01Y235150D02*
X1348850D01*
Y224850D01*
X1330150D01*
Y235150D01*
G01Y222650D02*
X1348850D01*
Y212350D01*
X1330150D01*
Y222650D01*
G01X1345850Y249250D02*
X1350850D01*
Y254250D01*
G01X1323150D02*
Y249250D01*
X1328150D01*
G01X1324157Y255376D02*
X1321157D01*
G01X1324157Y265219D02*
X1322157D01*
G01X1320700Y272500D02*
Y276500D01*
X1313300D01*
G01X1345567Y283000D02*
Y285500D01*
X1346567D01*
X1346900Y285375D01*
X1347150Y285083D01*
X1347233Y284750D01*
X1347150Y284417D01*
X1346942Y284167D01*
X1346567Y284042D01*
X1345567D01*
G01X1348583Y285500D02*
Y283708D01*
X1348750Y283333D01*
X1349083Y283083D01*
X1349500Y283000D01*
X1349917Y283083D01*
X1350250Y283333D01*
X1350417Y283708D01*
Y285500D01*
G01X1351683Y283500D02*
X1351933Y283208D01*
X1352267Y283042D01*
X1352642Y283000D01*
X1352975Y283042D01*
X1353308Y283250D01*
X1353517Y283500D01*
X1353558Y283750D01*
X1353475Y284042D01*
X1353183Y284250D01*
X1352892Y284333D01*
X1352517D01*
G01X1352892D02*
X1353142Y284458D01*
X1353350Y284667D01*
X1353433Y284917D01*
X1353350Y285167D01*
X1353142Y285375D01*
X1352767Y285500D01*
X1352392Y285458D01*
X1352017Y285292D01*
G01X1350850Y272250D02*
Y277250D01*
X1345850D01*
G01X1332089Y285714D02*
Y288214D01*
X1333089D01*
X1333422Y288089D01*
X1333672Y287797D01*
X1333755Y287464D01*
X1333672Y287131D01*
X1333464Y286881D01*
X1333089Y286756D01*
X1332089D01*
G01X1335147Y286047D02*
X1335480Y285839D01*
X1335855Y285714D01*
X1336189D01*
X1336522Y285839D01*
X1336772Y286047D01*
X1336897Y286339D01*
X1336814Y286631D01*
X1336605Y286881D01*
X1336230Y287047D01*
X1335730Y287131D01*
X1335439Y287297D01*
X1335314Y287589D01*
X1335397Y287881D01*
X1335605Y288089D01*
X1335897Y288214D01*
X1336189D01*
X1336480Y288131D01*
X1336730Y287922D01*
G01X1338289Y285714D02*
Y288214D01*
X1339289D01*
X1339622Y288089D01*
X1339872Y287797D01*
X1339955Y287464D01*
X1339872Y287131D01*
X1339664Y286881D01*
X1339289Y286756D01*
X1338289D01*
G01X1341430Y287797D02*
X1341680Y288047D01*
X1341972Y288172D01*
X1342305Y288214D01*
X1342722Y288131D01*
X1343014Y287922D01*
X1343097Y287672D01*
X1343055Y287422D01*
X1342889Y287214D01*
X1342055Y286797D01*
X1341680Y286506D01*
X1341430Y286089D01*
X1341347Y285714D01*
X1343097D01*
G01X1318986Y308317D02*
X1316486D01*
Y309358D01*
X1316611Y309692D01*
X1316778Y309900D01*
X1317111Y309983D01*
X1317444Y309900D01*
X1317653Y309650D01*
X1317778Y309358D01*
Y308317D01*
G01Y309358D02*
X1318986Y309983D01*
G01Y312250D02*
X1318944Y312542D01*
X1318819Y312875D01*
X1318611Y313083D01*
X1318319Y313167D01*
X1318028Y313083D01*
X1317778Y312833D01*
X1317653Y312458D01*
Y312042D01*
X1317569Y311792D01*
X1317361Y311583D01*
X1317069Y311500D01*
X1316778Y311625D01*
X1316569Y311917D01*
X1316486Y312250D01*
X1316569Y312583D01*
X1316778Y312875D01*
X1317069Y313000D01*
X1317361Y312917D01*
X1317569Y312708D01*
X1317653Y312458D01*
Y312042D01*
X1317778Y311667D01*
X1318028Y311417D01*
X1318319Y311333D01*
X1318611Y311417D01*
X1318819Y311625D01*
X1318944Y311958D01*
X1318986Y312250D01*
G01X1316486Y315350D02*
X1316569Y315017D01*
X1316778Y314767D01*
X1317028Y314600D01*
X1317361Y314475D01*
X1317736Y314433D01*
X1318111Y314475D01*
X1318444Y314600D01*
X1318694Y314767D01*
X1318903Y315017D01*
X1318986Y315350D01*
X1318903Y315683D01*
X1318694Y315933D01*
X1318444Y316100D01*
X1318111Y316225D01*
X1317736Y316267D01*
X1317361Y316225D01*
X1317028Y316100D01*
X1316778Y315933D01*
X1316569Y315683D01*
X1316486Y315350D01*
G01X1315300Y296200D02*
X1319300D01*
Y303600D01*
G01X1324886Y306232D02*
X1322386D01*
Y307232D01*
X1322511Y307565D01*
X1322803Y307815D01*
X1323136Y307898D01*
X1323469Y307815D01*
X1323719Y307607D01*
X1323844Y307232D01*
Y306232D01*
G01X1324886Y309332D02*
X1322386D01*
Y310373D01*
X1322511Y310707D01*
X1322678Y310915D01*
X1323011Y310998D01*
X1323344Y310915D01*
X1323553Y310665D01*
X1323678Y310373D01*
Y309332D01*
G01Y310373D02*
X1324886Y310998D01*
G01Y313265D02*
X1322386D01*
X1322886Y312765D01*
G01X1324886D02*
Y313765D01*
G01Y316365D02*
X1324844Y316657D01*
X1324719Y316990D01*
X1324511Y317198D01*
X1324219Y317282D01*
X1323928Y317198D01*
X1323678Y316948D01*
X1323553Y316573D01*
Y316157D01*
X1323469Y315907D01*
X1323261Y315698D01*
X1322969Y315615D01*
X1322678Y315740D01*
X1322469Y316032D01*
X1322386Y316365D01*
X1322469Y316698D01*
X1322678Y316990D01*
X1322969Y317115D01*
X1323261Y317032D01*
X1323469Y316823D01*
X1323553Y316573D01*
Y316157D01*
X1323678Y315782D01*
X1323928Y315532D01*
X1324219Y315448D01*
X1324511Y315532D01*
X1324719Y315740D01*
X1324844Y316073D01*
X1324886Y316365D01*
G01X1322803Y318673D02*
X1322553Y318923D01*
X1322428Y319215D01*
X1322386Y319548D01*
X1322469Y319965D01*
X1322678Y320257D01*
X1322928Y320340D01*
X1323178Y320298D01*
X1323386Y320132D01*
X1323803Y319298D01*
X1324094Y318923D01*
X1324511Y318673D01*
X1324886Y318590D01*
Y320340D01*
G01X1319400Y296200D02*
X1323400D01*
Y303600D01*
G01X1334967Y289800D02*
Y292300D01*
X1335967D01*
X1336300Y292175D01*
X1336550Y291883D01*
X1336633Y291550D01*
X1336550Y291217D01*
X1336342Y290967D01*
X1335967Y290842D01*
X1334967D01*
G01X1338067Y289800D02*
Y292300D01*
X1339108D01*
X1339442Y292175D01*
X1339650Y292008D01*
X1339733Y291675D01*
X1339650Y291342D01*
X1339400Y291133D01*
X1339108Y291008D01*
X1338067D01*
G01X1339108D02*
X1339733Y289800D01*
G01X1342000D02*
Y292300D01*
X1341500Y291800D01*
G01Y289800D02*
X1342500D01*
G01X1344308Y290842D02*
X1344600Y291133D01*
X1344850Y291300D01*
X1345183Y291383D01*
X1345475Y291300D01*
X1345683Y291133D01*
X1345850Y290883D01*
X1345892Y290592D01*
X1345850Y290342D01*
X1345683Y290092D01*
X1345433Y289883D01*
X1345142Y289800D01*
X1344808Y289883D01*
X1344517Y290133D01*
X1344350Y290508D01*
X1344308Y290925D01*
X1344392Y291467D01*
X1344517Y291758D01*
X1344725Y292050D01*
X1345017Y292258D01*
X1345308Y292300D01*
X1345600Y292217D01*
X1345808Y292008D01*
G01X1347283Y290175D02*
X1347533Y289967D01*
X1347825Y289842D01*
X1348200Y289800D01*
X1348575Y289883D01*
X1348867Y290050D01*
X1349075Y290342D01*
X1349117Y290675D01*
X1349033Y291008D01*
X1348825Y291217D01*
X1348533Y291383D01*
X1348242Y291425D01*
X1347950Y291383D01*
X1347575Y291217D01*
X1347700Y292300D01*
X1348825D01*
G01X1323300Y292500D02*
Y288500D01*
X1330700D01*
G01X1328904Y303094D02*
Y305594D01*
X1329904D01*
X1330237Y305469D01*
X1330487Y305177D01*
X1330570Y304844D01*
X1330487Y304511D01*
X1330279Y304261D01*
X1329904Y304136D01*
X1328904D01*
G01X1332004Y303094D02*
Y305594D01*
X1333045D01*
X1333379Y305469D01*
X1333587Y305302D01*
X1333670Y304969D01*
X1333587Y304636D01*
X1333337Y304427D01*
X1333045Y304302D01*
X1332004D01*
G01X1333045D02*
X1333670Y303094D01*
G01X1335937D02*
Y305594D01*
X1335437Y305094D01*
G01Y303094D02*
X1336437D01*
G01X1338245Y304136D02*
X1338537Y304427D01*
X1338787Y304594D01*
X1339120Y304677D01*
X1339412Y304594D01*
X1339620Y304427D01*
X1339787Y304177D01*
X1339829Y303886D01*
X1339787Y303636D01*
X1339620Y303386D01*
X1339370Y303177D01*
X1339079Y303094D01*
X1338745Y303177D01*
X1338454Y303427D01*
X1338287Y303802D01*
X1338245Y304219D01*
X1338329Y304761D01*
X1338454Y305052D01*
X1338662Y305344D01*
X1338954Y305552D01*
X1339245Y305594D01*
X1339537Y305511D01*
X1339745Y305302D01*
G01X1342137Y303094D02*
Y305594D01*
X1341637Y305094D01*
G01Y303094D02*
X1342637D01*
G01X1315300Y296000D02*
Y292000D01*
X1322700D01*
G01X1313000Y276800D02*
X1317000D01*
Y284200D01*
G01X1330704Y301386D02*
X1330454Y301511D01*
X1330162Y301594D01*
X1329829D01*
X1329454Y301469D01*
X1329162Y301261D01*
X1328954Y301011D01*
X1328787Y300594D01*
X1328745Y300219D01*
X1328829Y299844D01*
X1328954Y299594D01*
X1329204Y299344D01*
X1329495Y299177D01*
X1329787Y299094D01*
X1330079D01*
X1330370Y299177D01*
X1330620Y299302D01*
X1330829Y299469D01*
G01X1332095Y301177D02*
X1332345Y301427D01*
X1332637Y301552D01*
X1332970Y301594D01*
X1333387Y301511D01*
X1333679Y301302D01*
X1333762Y301052D01*
X1333720Y300802D01*
X1333554Y300594D01*
X1332720Y300177D01*
X1332345Y299886D01*
X1332095Y299469D01*
X1332012Y299094D01*
X1333762D01*
G01X1335904D02*
X1335987Y299636D01*
X1336112Y300094D01*
X1336279Y300511D01*
X1336487Y300969D01*
X1336820Y301594D01*
X1335154D01*
G01X1339087D02*
X1338754Y301511D01*
X1338504Y301302D01*
X1338337Y301052D01*
X1338212Y300719D01*
X1338170Y300344D01*
X1338212Y299969D01*
X1338337Y299636D01*
X1338504Y299386D01*
X1338754Y299177D01*
X1339087Y299094D01*
X1339420Y299177D01*
X1339670Y299386D01*
X1339837Y299636D01*
X1339962Y299969D01*
X1340004Y300344D01*
X1339962Y300719D01*
X1339837Y301052D01*
X1339670Y301302D01*
X1339420Y301511D01*
X1339087Y301594D01*
G01X1328904Y295094D02*
Y297594D01*
X1329904D01*
X1330237Y297469D01*
X1330487Y297177D01*
X1330570Y296844D01*
X1330487Y296511D01*
X1330279Y296261D01*
X1329904Y296136D01*
X1328904D01*
G01X1333754Y297386D02*
X1333504Y297511D01*
X1333212Y297594D01*
X1332879D01*
X1332504Y297469D01*
X1332212Y297261D01*
X1332004Y297011D01*
X1331837Y296594D01*
X1331795Y296219D01*
X1331879Y295844D01*
X1332004Y295594D01*
X1332254Y295344D01*
X1332545Y295177D01*
X1332837Y295094D01*
X1333129D01*
X1333420Y295177D01*
X1333670Y295302D01*
X1333879Y295469D01*
G01X1335937Y295094D02*
Y297594D01*
X1335437Y297094D01*
G01Y295094D02*
X1336437D01*
G01X1339037D02*
X1339329Y295136D01*
X1339662Y295261D01*
X1339870Y295469D01*
X1339954Y295761D01*
X1339870Y296052D01*
X1339620Y296302D01*
X1339245Y296427D01*
X1338829D01*
X1338579Y296511D01*
X1338370Y296719D01*
X1338287Y297011D01*
X1338412Y297302D01*
X1338704Y297511D01*
X1339037Y297594D01*
X1339370Y297511D01*
X1339662Y297302D01*
X1339787Y297011D01*
X1339704Y296719D01*
X1339495Y296511D01*
X1339245Y296427D01*
X1338829D01*
X1338454Y296302D01*
X1338204Y296052D01*
X1338120Y295761D01*
X1338204Y295469D01*
X1338412Y295261D01*
X1338745Y295136D01*
X1339037Y295094D01*
G01X1341429Y295386D02*
X1341720Y295177D01*
X1342054Y295094D01*
X1342387Y295177D01*
X1342679Y295427D01*
X1342887Y295802D01*
X1342970Y296177D01*
Y296636D01*
X1342887Y297011D01*
X1342679Y297344D01*
X1342429Y297511D01*
X1342137Y297594D01*
X1341804Y297511D01*
X1341554Y297344D01*
X1341387Y297094D01*
X1341304Y296761D01*
X1341387Y296469D01*
X1341595Y296177D01*
X1341845Y296011D01*
X1342137Y295969D01*
X1342470Y296052D01*
X1342720Y296261D01*
X1342970Y296636D01*
G01X1339972Y645945D02*
X1337472D01*
Y646986D01*
X1337597Y647320D01*
X1337764Y647528D01*
X1338097Y647611D01*
X1338430Y647528D01*
X1338639Y647278D01*
X1338764Y646986D01*
Y645945D01*
G01Y646986D02*
X1339972Y647611D01*
G01Y649795D02*
X1339430Y649878D01*
X1338972Y650003D01*
X1338555Y650170D01*
X1338097Y650378D01*
X1337472Y650711D01*
Y649045D01*
G01X1339680Y652270D02*
X1339889Y652561D01*
X1339972Y652895D01*
X1339889Y653228D01*
X1339639Y653520D01*
X1339264Y653728D01*
X1338889Y653811D01*
X1338430D01*
X1338055Y653728D01*
X1337722Y653520D01*
X1337555Y653270D01*
X1337472Y652978D01*
X1337555Y652645D01*
X1337722Y652395D01*
X1337972Y652228D01*
X1338305Y652145D01*
X1338597Y652228D01*
X1338889Y652436D01*
X1339055Y652686D01*
X1339097Y652978D01*
X1339014Y653311D01*
X1338805Y653561D01*
X1338430Y653811D01*
G01X1338930Y655286D02*
X1338639Y655578D01*
X1338472Y655828D01*
X1338389Y656161D01*
X1338472Y656453D01*
X1338639Y656661D01*
X1338889Y656828D01*
X1339180Y656870D01*
X1339430Y656828D01*
X1339680Y656661D01*
X1339889Y656411D01*
X1339972Y656120D01*
X1339889Y655786D01*
X1339639Y655495D01*
X1339264Y655328D01*
X1338847Y655286D01*
X1338305Y655370D01*
X1338014Y655495D01*
X1337722Y655703D01*
X1337514Y655995D01*
X1337472Y656286D01*
X1337555Y656578D01*
X1337764Y656786D01*
G01X1339680Y658470D02*
X1339889Y658761D01*
X1339972Y659095D01*
X1339889Y659428D01*
X1339639Y659720D01*
X1339264Y659928D01*
X1338889Y660011D01*
X1338430D01*
X1338055Y659928D01*
X1337722Y659720D01*
X1337555Y659470D01*
X1337472Y659178D01*
X1337555Y658845D01*
X1337722Y658595D01*
X1337972Y658428D01*
X1338305Y658345D01*
X1338597Y658428D01*
X1338889Y658636D01*
X1339055Y658886D01*
X1339097Y659178D01*
X1339014Y659511D01*
X1338805Y659761D01*
X1338430Y660011D01*
G01X1323972Y645945D02*
X1321472D01*
Y646986D01*
X1321597Y647320D01*
X1321764Y647528D01*
X1322097Y647611D01*
X1322430Y647528D01*
X1322639Y647278D01*
X1322764Y646986D01*
Y645945D01*
G01Y646986D02*
X1323972Y647611D01*
G01Y649795D02*
X1323430Y649878D01*
X1322972Y650003D01*
X1322555Y650170D01*
X1322097Y650378D01*
X1321472Y650711D01*
Y649045D01*
G01X1323680Y652270D02*
X1323889Y652561D01*
X1323972Y652895D01*
X1323889Y653228D01*
X1323639Y653520D01*
X1323264Y653728D01*
X1322889Y653811D01*
X1322430D01*
X1322055Y653728D01*
X1321722Y653520D01*
X1321555Y653270D01*
X1321472Y652978D01*
X1321555Y652645D01*
X1321722Y652395D01*
X1321972Y652228D01*
X1322305Y652145D01*
X1322597Y652228D01*
X1322889Y652436D01*
X1323055Y652686D01*
X1323097Y652978D01*
X1323014Y653311D01*
X1322805Y653561D01*
X1322430Y653811D01*
G01X1322930Y655286D02*
X1322639Y655578D01*
X1322472Y655828D01*
X1322389Y656161D01*
X1322472Y656453D01*
X1322639Y656661D01*
X1322889Y656828D01*
X1323180Y656870D01*
X1323430Y656828D01*
X1323680Y656661D01*
X1323889Y656411D01*
X1323972Y656120D01*
X1323889Y655786D01*
X1323639Y655495D01*
X1323264Y655328D01*
X1322847Y655286D01*
X1322305Y655370D01*
X1322014Y655495D01*
X1321722Y655703D01*
X1321514Y655995D01*
X1321472Y656286D01*
X1321555Y656578D01*
X1321764Y656786D01*
G01X1323972Y659095D02*
X1323430Y659178D01*
X1322972Y659303D01*
X1322555Y659470D01*
X1322097Y659678D01*
X1321472Y660011D01*
Y658345D01*
G01X1335972Y645945D02*
X1333472D01*
Y646986D01*
X1333597Y647320D01*
X1333764Y647528D01*
X1334097Y647611D01*
X1334430Y647528D01*
X1334639Y647278D01*
X1334764Y646986D01*
Y645945D01*
G01Y646986D02*
X1335972Y647611D01*
G01Y649795D02*
X1335430Y649878D01*
X1334972Y650003D01*
X1334555Y650170D01*
X1334097Y650378D01*
X1333472Y650711D01*
Y649045D01*
G01X1335680Y652270D02*
X1335889Y652561D01*
X1335972Y652895D01*
X1335889Y653228D01*
X1335639Y653520D01*
X1335264Y653728D01*
X1334889Y653811D01*
X1334430D01*
X1334055Y653728D01*
X1333722Y653520D01*
X1333555Y653270D01*
X1333472Y652978D01*
X1333555Y652645D01*
X1333722Y652395D01*
X1333972Y652228D01*
X1334305Y652145D01*
X1334597Y652228D01*
X1334889Y652436D01*
X1335055Y652686D01*
X1335097Y652978D01*
X1335014Y653311D01*
X1334805Y653561D01*
X1334430Y653811D01*
G01X1335597Y655161D02*
X1335805Y655411D01*
X1335930Y655703D01*
X1335972Y656078D01*
X1335889Y656453D01*
X1335722Y656745D01*
X1335430Y656953D01*
X1335097Y656995D01*
X1334764Y656911D01*
X1334555Y656703D01*
X1334389Y656411D01*
X1334347Y656120D01*
X1334389Y655828D01*
X1334555Y655453D01*
X1333472Y655578D01*
Y656703D01*
G01X1335972Y659678D02*
X1333472D01*
X1335264Y658136D01*
Y660220D01*
G01X1319972Y645945D02*
X1317472D01*
Y646986D01*
X1317597Y647320D01*
X1317764Y647528D01*
X1318097Y647611D01*
X1318430Y647528D01*
X1318639Y647278D01*
X1318764Y646986D01*
Y645945D01*
G01Y646986D02*
X1319972Y647611D01*
G01Y649795D02*
X1319430Y649878D01*
X1318972Y650003D01*
X1318555Y650170D01*
X1318097Y650378D01*
X1317472Y650711D01*
Y649045D01*
G01X1319680Y652270D02*
X1319889Y652561D01*
X1319972Y652895D01*
X1319889Y653228D01*
X1319639Y653520D01*
X1319264Y653728D01*
X1318889Y653811D01*
X1318430D01*
X1318055Y653728D01*
X1317722Y653520D01*
X1317555Y653270D01*
X1317472Y652978D01*
X1317555Y652645D01*
X1317722Y652395D01*
X1317972Y652228D01*
X1318305Y652145D01*
X1318597Y652228D01*
X1318889Y652436D01*
X1319055Y652686D01*
X1319097Y652978D01*
X1319014Y653311D01*
X1318805Y653561D01*
X1318430Y653811D01*
G01X1319597Y655161D02*
X1319805Y655411D01*
X1319930Y655703D01*
X1319972Y656078D01*
X1319889Y656453D01*
X1319722Y656745D01*
X1319430Y656953D01*
X1319097Y656995D01*
X1318764Y656911D01*
X1318555Y656703D01*
X1318389Y656411D01*
X1318347Y656120D01*
X1318389Y655828D01*
X1318555Y655453D01*
X1317472Y655578D01*
Y656703D01*
G01X1319972Y659178D02*
X1317472D01*
X1317972Y658678D01*
G01X1319972D02*
Y659678D01*
G01X1331972Y645945D02*
X1329472D01*
Y646986D01*
X1329597Y647320D01*
X1329764Y647528D01*
X1330097Y647611D01*
X1330430Y647528D01*
X1330639Y647278D01*
X1330764Y646986D01*
Y645945D01*
G01Y646986D02*
X1331972Y647611D01*
G01Y649795D02*
X1331430Y649878D01*
X1330972Y650003D01*
X1330555Y650170D01*
X1330097Y650378D01*
X1329472Y650711D01*
Y649045D01*
G01X1331680Y652270D02*
X1331889Y652561D01*
X1331972Y652895D01*
X1331889Y653228D01*
X1331639Y653520D01*
X1331264Y653728D01*
X1330889Y653811D01*
X1330430D01*
X1330055Y653728D01*
X1329722Y653520D01*
X1329555Y653270D01*
X1329472Y652978D01*
X1329555Y652645D01*
X1329722Y652395D01*
X1329972Y652228D01*
X1330305Y652145D01*
X1330597Y652228D01*
X1330889Y652436D01*
X1331055Y652686D01*
X1331097Y652978D01*
X1331014Y653311D01*
X1330805Y653561D01*
X1330430Y653811D01*
G01X1331472Y655161D02*
X1331764Y655411D01*
X1331930Y655745D01*
X1331972Y656120D01*
X1331930Y656453D01*
X1331722Y656786D01*
X1331472Y656995D01*
X1331222Y657036D01*
X1330930Y656953D01*
X1330722Y656661D01*
X1330639Y656370D01*
Y655995D01*
G01Y656370D02*
X1330514Y656620D01*
X1330305Y656828D01*
X1330055Y656911D01*
X1329805Y656828D01*
X1329597Y656620D01*
X1329472Y656245D01*
X1329514Y655870D01*
X1329680Y655495D01*
G01X1331680Y658470D02*
X1331889Y658761D01*
X1331972Y659095D01*
X1331889Y659428D01*
X1331639Y659720D01*
X1331264Y659928D01*
X1330889Y660011D01*
X1330430D01*
X1330055Y659928D01*
X1329722Y659720D01*
X1329555Y659470D01*
X1329472Y659178D01*
X1329555Y658845D01*
X1329722Y658595D01*
X1329972Y658428D01*
X1330305Y658345D01*
X1330597Y658428D01*
X1330889Y658636D01*
X1331055Y658886D01*
X1331097Y659178D01*
X1331014Y659511D01*
X1330805Y659761D01*
X1330430Y660011D01*
G01X1315972Y645945D02*
X1313472D01*
Y646986D01*
X1313597Y647320D01*
X1313764Y647528D01*
X1314097Y647611D01*
X1314430Y647528D01*
X1314639Y647278D01*
X1314764Y646986D01*
Y645945D01*
G01Y646986D02*
X1315972Y647611D01*
G01Y649795D02*
X1315430Y649878D01*
X1314972Y650003D01*
X1314555Y650170D01*
X1314097Y650378D01*
X1313472Y650711D01*
Y649045D01*
G01X1315680Y652270D02*
X1315889Y652561D01*
X1315972Y652895D01*
X1315889Y653228D01*
X1315639Y653520D01*
X1315264Y653728D01*
X1314889Y653811D01*
X1314430D01*
X1314055Y653728D01*
X1313722Y653520D01*
X1313555Y653270D01*
X1313472Y652978D01*
X1313555Y652645D01*
X1313722Y652395D01*
X1313972Y652228D01*
X1314305Y652145D01*
X1314597Y652228D01*
X1314889Y652436D01*
X1315055Y652686D01*
X1315097Y652978D01*
X1315014Y653311D01*
X1314805Y653561D01*
X1314430Y653811D01*
G01X1315472Y655161D02*
X1315764Y655411D01*
X1315930Y655745D01*
X1315972Y656120D01*
X1315930Y656453D01*
X1315722Y656786D01*
X1315472Y656995D01*
X1315222Y657036D01*
X1314930Y656953D01*
X1314722Y656661D01*
X1314639Y656370D01*
Y655995D01*
G01Y656370D02*
X1314514Y656620D01*
X1314305Y656828D01*
X1314055Y656911D01*
X1313805Y656828D01*
X1313597Y656620D01*
X1313472Y656245D01*
X1313514Y655870D01*
X1313680Y655495D01*
G01X1314930Y658386D02*
X1314639Y658678D01*
X1314472Y658928D01*
X1314389Y659261D01*
X1314472Y659553D01*
X1314639Y659761D01*
X1314889Y659928D01*
X1315180Y659970D01*
X1315430Y659928D01*
X1315680Y659761D01*
X1315889Y659511D01*
X1315972Y659220D01*
X1315889Y658886D01*
X1315639Y658595D01*
X1315264Y658428D01*
X1314847Y658386D01*
X1314305Y658470D01*
X1314014Y658595D01*
X1313722Y658803D01*
X1313514Y659095D01*
X1313472Y659386D01*
X1313555Y659678D01*
X1313764Y659886D01*
G01X1327972Y645945D02*
X1325472D01*
Y646986D01*
X1325597Y647320D01*
X1325764Y647528D01*
X1326097Y647611D01*
X1326430Y647528D01*
X1326639Y647278D01*
X1326764Y646986D01*
Y645945D01*
G01Y646986D02*
X1327972Y647611D01*
G01Y649795D02*
X1327430Y649878D01*
X1326972Y650003D01*
X1326555Y650170D01*
X1326097Y650378D01*
X1325472Y650711D01*
Y649045D01*
G01X1327680Y652270D02*
X1327889Y652561D01*
X1327972Y652895D01*
X1327889Y653228D01*
X1327639Y653520D01*
X1327264Y653728D01*
X1326889Y653811D01*
X1326430D01*
X1326055Y653728D01*
X1325722Y653520D01*
X1325555Y653270D01*
X1325472Y652978D01*
X1325555Y652645D01*
X1325722Y652395D01*
X1325972Y652228D01*
X1326305Y652145D01*
X1326597Y652228D01*
X1326889Y652436D01*
X1327055Y652686D01*
X1327097Y652978D01*
X1327014Y653311D01*
X1326805Y653561D01*
X1326430Y653811D01*
G01X1325889Y655286D02*
X1325639Y655536D01*
X1325514Y655828D01*
X1325472Y656161D01*
X1325555Y656578D01*
X1325764Y656870D01*
X1326014Y656953D01*
X1326264Y656911D01*
X1326472Y656745D01*
X1326889Y655911D01*
X1327180Y655536D01*
X1327597Y655286D01*
X1327972Y655203D01*
Y656953D01*
G01X1327597Y658261D02*
X1327805Y658511D01*
X1327930Y658803D01*
X1327972Y659178D01*
X1327889Y659553D01*
X1327722Y659845D01*
X1327430Y660053D01*
X1327097Y660095D01*
X1326764Y660011D01*
X1326555Y659803D01*
X1326389Y659511D01*
X1326347Y659220D01*
X1326389Y658928D01*
X1326555Y658553D01*
X1325472Y658678D01*
Y659803D01*
G01X1344005Y645981D02*
X1341505D01*
Y647022D01*
X1341630Y647356D01*
X1341797Y647564D01*
X1342130Y647647D01*
X1342463Y647564D01*
X1342672Y647314D01*
X1342797Y647022D01*
Y645981D01*
G01Y647022D02*
X1344005Y647647D01*
G01X1343713Y649206D02*
X1343922Y649497D01*
X1344005Y649831D01*
X1343922Y650164D01*
X1343672Y650456D01*
X1343297Y650664D01*
X1342922Y650747D01*
X1342463D01*
X1342088Y650664D01*
X1341755Y650456D01*
X1341588Y650206D01*
X1341505Y649914D01*
X1341588Y649581D01*
X1341755Y649331D01*
X1342005Y649164D01*
X1342338Y649081D01*
X1342630Y649164D01*
X1342922Y649372D01*
X1343088Y649622D01*
X1343130Y649914D01*
X1343047Y650247D01*
X1342838Y650497D01*
X1342463Y650747D01*
G01X1341505Y653014D02*
X1341588Y652681D01*
X1341797Y652431D01*
X1342047Y652264D01*
X1342380Y652139D01*
X1342755Y652097D01*
X1343130Y652139D01*
X1343463Y652264D01*
X1343713Y652431D01*
X1343922Y652681D01*
X1344005Y653014D01*
X1343922Y653347D01*
X1343713Y653597D01*
X1343463Y653764D01*
X1343130Y653889D01*
X1342755Y653931D01*
X1342380Y653889D01*
X1342047Y653764D01*
X1341797Y653597D01*
X1341588Y653347D01*
X1341505Y653014D01*
G01X1343505Y655197D02*
X1343797Y655447D01*
X1343963Y655781D01*
X1344005Y656156D01*
X1343963Y656489D01*
X1343755Y656822D01*
X1343505Y657031D01*
X1343255Y657072D01*
X1342963Y656989D01*
X1342755Y656697D01*
X1342672Y656406D01*
Y656031D01*
G01Y656406D02*
X1342547Y656656D01*
X1342338Y656864D01*
X1342088Y656947D01*
X1341838Y656864D01*
X1341630Y656656D01*
X1341505Y656281D01*
X1341547Y655906D01*
X1341713Y655531D01*
G01X1344005Y659214D02*
X1343963Y659506D01*
X1343838Y659839D01*
X1343630Y660047D01*
X1343338Y660131D01*
X1343047Y660047D01*
X1342797Y659797D01*
X1342672Y659422D01*
Y659006D01*
X1342588Y658756D01*
X1342380Y658547D01*
X1342088Y658464D01*
X1341797Y658589D01*
X1341588Y658881D01*
X1341505Y659214D01*
X1341588Y659547D01*
X1341797Y659839D01*
X1342088Y659964D01*
X1342380Y659881D01*
X1342588Y659672D01*
X1342672Y659422D01*
Y659006D01*
X1342797Y658631D01*
X1343047Y658381D01*
X1343338Y658297D01*
X1343630Y658381D01*
X1343838Y658589D01*
X1343963Y658922D01*
X1344005Y659214D01*
G01X1323689Y629849D02*
X1321189D01*
Y630890D01*
X1321314Y631224D01*
X1321481Y631432D01*
X1321814Y631515D01*
X1322147Y631432D01*
X1322356Y631182D01*
X1322481Y630890D01*
Y629849D01*
G01Y630890D02*
X1323689Y631515D01*
G01X1323397Y633074D02*
X1323606Y633365D01*
X1323689Y633699D01*
X1323606Y634032D01*
X1323356Y634324D01*
X1322981Y634532D01*
X1322606Y634615D01*
X1322147D01*
X1321772Y634532D01*
X1321439Y634324D01*
X1321272Y634074D01*
X1321189Y633782D01*
X1321272Y633449D01*
X1321439Y633199D01*
X1321689Y633032D01*
X1322022Y632949D01*
X1322314Y633032D01*
X1322606Y633240D01*
X1322772Y633490D01*
X1322814Y633782D01*
X1322731Y634115D01*
X1322522Y634365D01*
X1322147Y634615D01*
G01X1321189Y636882D02*
X1321272Y636549D01*
X1321481Y636299D01*
X1321731Y636132D01*
X1322064Y636007D01*
X1322439Y635965D01*
X1322814Y636007D01*
X1323147Y636132D01*
X1323397Y636299D01*
X1323606Y636549D01*
X1323689Y636882D01*
X1323606Y637215D01*
X1323397Y637465D01*
X1323147Y637632D01*
X1322814Y637757D01*
X1322439Y637799D01*
X1322064Y637757D01*
X1321731Y637632D01*
X1321481Y637465D01*
X1321272Y637215D01*
X1321189Y636882D01*
G01X1323189Y639065D02*
X1323481Y639315D01*
X1323647Y639649D01*
X1323689Y640024D01*
X1323647Y640357D01*
X1323439Y640690D01*
X1323189Y640899D01*
X1322939Y640940D01*
X1322647Y640857D01*
X1322439Y640565D01*
X1322356Y640274D01*
Y639899D01*
G01Y640274D02*
X1322231Y640524D01*
X1322022Y640732D01*
X1321772Y640815D01*
X1321522Y640732D01*
X1321314Y640524D01*
X1321189Y640149D01*
X1321231Y639774D01*
X1321397Y639399D01*
G01X1323189Y642165D02*
X1323481Y642415D01*
X1323647Y642749D01*
X1323689Y643124D01*
X1323647Y643457D01*
X1323439Y643790D01*
X1323189Y643999D01*
X1322939Y644040D01*
X1322647Y643957D01*
X1322439Y643665D01*
X1322356Y643374D01*
Y642999D01*
G01Y643374D02*
X1322231Y643624D01*
X1322022Y643832D01*
X1321772Y643915D01*
X1321522Y643832D01*
X1321314Y643624D01*
X1321189Y643249D01*
X1321231Y642874D01*
X1321397Y642499D01*
G01X1340128Y682567D02*
X1336128D01*
Y675167D01*
G01X1324128Y682567D02*
X1320128D01*
Y675167D01*
G01X1336128Y682567D02*
X1332128D01*
Y675167D01*
G01X1320128Y682567D02*
X1316128D01*
Y675167D01*
G01X1332128Y682567D02*
X1328128D01*
Y675167D01*
G01Y682567D02*
X1324128D01*
Y675167D01*
G01X1344300Y682200D02*
X1340300D01*
Y674800D01*
G01X1324400Y675000D02*
X1320400D01*
Y667600D01*
G01X1334128Y710867D02*
Y696867D01*
G01X1312628Y724167D02*
X1316628D01*
Y731567D01*
G01X1331876Y734402D02*
X1329376D01*
Y735443D01*
X1329501Y735777D01*
X1329668Y735985D01*
X1330001Y736068D01*
X1330334Y735985D01*
X1330543Y735735D01*
X1330668Y735443D01*
Y734402D01*
G01Y735443D02*
X1331876Y736068D01*
G01Y738252D02*
X1331334Y738335D01*
X1330876Y738460D01*
X1330459Y738627D01*
X1330001Y738835D01*
X1329376Y739168D01*
Y737502D01*
G01X1331584Y740727D02*
X1331793Y741018D01*
X1331876Y741352D01*
X1331793Y741685D01*
X1331543Y741977D01*
X1331168Y742185D01*
X1330793Y742268D01*
X1330334D01*
X1329959Y742185D01*
X1329626Y741977D01*
X1329459Y741727D01*
X1329376Y741435D01*
X1329459Y741102D01*
X1329626Y740852D01*
X1329876Y740685D01*
X1330209Y740602D01*
X1330501Y740685D01*
X1330793Y740893D01*
X1330959Y741143D01*
X1331001Y741435D01*
X1330918Y741768D01*
X1330709Y742018D01*
X1330334Y742268D01*
G01X1331876Y744452D02*
X1331334Y744535D01*
X1330876Y744660D01*
X1330459Y744827D01*
X1330001Y745035D01*
X1329376Y745368D01*
Y743702D01*
G01X1331501Y746718D02*
X1331709Y746968D01*
X1331834Y747260D01*
X1331876Y747635D01*
X1331793Y748010D01*
X1331626Y748302D01*
X1331334Y748510D01*
X1331001Y748552D01*
X1330668Y748468D01*
X1330459Y748260D01*
X1330293Y747968D01*
X1330251Y747677D01*
X1330293Y747385D01*
X1330459Y747010D01*
X1329376Y747135D01*
Y748260D01*
G01X1324128Y724167D02*
X1328128D01*
Y731567D01*
G01X1335876Y734402D02*
X1333376D01*
Y735443D01*
X1333501Y735777D01*
X1333668Y735985D01*
X1334001Y736068D01*
X1334334Y735985D01*
X1334543Y735735D01*
X1334668Y735443D01*
Y734402D01*
G01Y735443D02*
X1335876Y736068D01*
G01Y738252D02*
X1335334Y738335D01*
X1334876Y738460D01*
X1334459Y738627D01*
X1334001Y738835D01*
X1333376Y739168D01*
Y737502D01*
G01X1335584Y740727D02*
X1335793Y741018D01*
X1335876Y741352D01*
X1335793Y741685D01*
X1335543Y741977D01*
X1335168Y742185D01*
X1334793Y742268D01*
X1334334D01*
X1333959Y742185D01*
X1333626Y741977D01*
X1333459Y741727D01*
X1333376Y741435D01*
X1333459Y741102D01*
X1333626Y740852D01*
X1333876Y740685D01*
X1334209Y740602D01*
X1334501Y740685D01*
X1334793Y740893D01*
X1334959Y741143D01*
X1335001Y741435D01*
X1334918Y741768D01*
X1334709Y742018D01*
X1334334Y742268D01*
G01X1334834Y743743D02*
X1334543Y744035D01*
X1334376Y744285D01*
X1334293Y744618D01*
X1334376Y744910D01*
X1334543Y745118D01*
X1334793Y745285D01*
X1335084Y745327D01*
X1335334Y745285D01*
X1335584Y745118D01*
X1335793Y744868D01*
X1335876Y744577D01*
X1335793Y744243D01*
X1335543Y743952D01*
X1335168Y743785D01*
X1334751Y743743D01*
X1334209Y743827D01*
X1333918Y743952D01*
X1333626Y744160D01*
X1333418Y744452D01*
X1333376Y744743D01*
X1333459Y745035D01*
X1333668Y745243D01*
G01X1333376Y747635D02*
X1333459Y747302D01*
X1333668Y747052D01*
X1333918Y746885D01*
X1334251Y746760D01*
X1334626Y746718D01*
X1335001Y746760D01*
X1335334Y746885D01*
X1335584Y747052D01*
X1335793Y747302D01*
X1335876Y747635D01*
X1335793Y747968D01*
X1335584Y748218D01*
X1335334Y748385D01*
X1335001Y748510D01*
X1334626Y748552D01*
X1334251Y748510D01*
X1333918Y748385D01*
X1333668Y748218D01*
X1333459Y747968D01*
X1333376Y747635D01*
G01X1328128Y724167D02*
X1332128D01*
Y731567D01*
G01X1339876Y734402D02*
X1337376D01*
Y735443D01*
X1337501Y735777D01*
X1337668Y735985D01*
X1338001Y736068D01*
X1338334Y735985D01*
X1338543Y735735D01*
X1338668Y735443D01*
Y734402D01*
G01Y735443D02*
X1339876Y736068D01*
G01Y738252D02*
X1339334Y738335D01*
X1338876Y738460D01*
X1338459Y738627D01*
X1338001Y738835D01*
X1337376Y739168D01*
Y737502D01*
G01X1339584Y740727D02*
X1339793Y741018D01*
X1339876Y741352D01*
X1339793Y741685D01*
X1339543Y741977D01*
X1339168Y742185D01*
X1338793Y742268D01*
X1338334D01*
X1337959Y742185D01*
X1337626Y741977D01*
X1337459Y741727D01*
X1337376Y741435D01*
X1337459Y741102D01*
X1337626Y740852D01*
X1337876Y740685D01*
X1338209Y740602D01*
X1338501Y740685D01*
X1338793Y740893D01*
X1338959Y741143D01*
X1339001Y741435D01*
X1338918Y741768D01*
X1338709Y742018D01*
X1338334Y742268D01*
G01X1339876Y745035D02*
X1337376D01*
X1339168Y743493D01*
Y745577D01*
G01X1338834Y746843D02*
X1338543Y747135D01*
X1338376Y747385D01*
X1338293Y747718D01*
X1338376Y748010D01*
X1338543Y748218D01*
X1338793Y748385D01*
X1339084Y748427D01*
X1339334Y748385D01*
X1339584Y748218D01*
X1339793Y747968D01*
X1339876Y747677D01*
X1339793Y747343D01*
X1339543Y747052D01*
X1339168Y746885D01*
X1338751Y746843D01*
X1338209Y746927D01*
X1337918Y747052D01*
X1337626Y747260D01*
X1337418Y747552D01*
X1337376Y747843D01*
X1337459Y748135D01*
X1337668Y748343D01*
G01X1332128Y724167D02*
X1336128D01*
Y731567D01*
G01X1343876Y734402D02*
X1341376D01*
Y735443D01*
X1341501Y735777D01*
X1341668Y735985D01*
X1342001Y736068D01*
X1342334Y735985D01*
X1342543Y735735D01*
X1342668Y735443D01*
Y734402D01*
G01Y735443D02*
X1343876Y736068D01*
G01Y738252D02*
X1343334Y738335D01*
X1342876Y738460D01*
X1342459Y738627D01*
X1342001Y738835D01*
X1341376Y739168D01*
Y737502D01*
G01X1343584Y740727D02*
X1343793Y741018D01*
X1343876Y741352D01*
X1343793Y741685D01*
X1343543Y741977D01*
X1343168Y742185D01*
X1342793Y742268D01*
X1342334D01*
X1341959Y742185D01*
X1341626Y741977D01*
X1341459Y741727D01*
X1341376Y741435D01*
X1341459Y741102D01*
X1341626Y740852D01*
X1341876Y740685D01*
X1342209Y740602D01*
X1342501Y740685D01*
X1342793Y740893D01*
X1342959Y741143D01*
X1343001Y741435D01*
X1342918Y741768D01*
X1342709Y742018D01*
X1342334Y742268D01*
G01X1343376Y743618D02*
X1343668Y743868D01*
X1343834Y744202D01*
X1343876Y744577D01*
X1343834Y744910D01*
X1343626Y745243D01*
X1343376Y745452D01*
X1343126Y745493D01*
X1342834Y745410D01*
X1342626Y745118D01*
X1342543Y744827D01*
Y744452D01*
G01Y744827D02*
X1342418Y745077D01*
X1342209Y745285D01*
X1341959Y745368D01*
X1341709Y745285D01*
X1341501Y745077D01*
X1341376Y744702D01*
X1341418Y744327D01*
X1341584Y743952D01*
G01X1341376Y747635D02*
X1341459Y747302D01*
X1341668Y747052D01*
X1341918Y746885D01*
X1342251Y746760D01*
X1342626Y746718D01*
X1343001Y746760D01*
X1343334Y746885D01*
X1343584Y747052D01*
X1343793Y747302D01*
X1343876Y747635D01*
X1343793Y747968D01*
X1343584Y748218D01*
X1343334Y748385D01*
X1343001Y748510D01*
X1342626Y748552D01*
X1342251Y748510D01*
X1341918Y748385D01*
X1341668Y748218D01*
X1341459Y747968D01*
X1341376Y747635D01*
G01X1336128Y724167D02*
X1340128D01*
Y731567D01*
G01X1324100Y732200D02*
X1328100D01*
Y739600D01*
G01X1331867Y750451D02*
X1329367D01*
Y751492D01*
X1329492Y751826D01*
X1329659Y752034D01*
X1329992Y752117D01*
X1330325Y752034D01*
X1330534Y751784D01*
X1330659Y751492D01*
Y750451D01*
G01Y751492D02*
X1331867Y752117D01*
G01X1331575Y753676D02*
X1331784Y753967D01*
X1331867Y754301D01*
X1331784Y754634D01*
X1331534Y754926D01*
X1331159Y755134D01*
X1330784Y755217D01*
X1330325D01*
X1329950Y755134D01*
X1329617Y754926D01*
X1329450Y754676D01*
X1329367Y754384D01*
X1329450Y754051D01*
X1329617Y753801D01*
X1329867Y753634D01*
X1330200Y753551D01*
X1330492Y753634D01*
X1330784Y753842D01*
X1330950Y754092D01*
X1330992Y754384D01*
X1330909Y754717D01*
X1330700Y754967D01*
X1330325Y755217D01*
G01X1329367Y757484D02*
X1329450Y757151D01*
X1329659Y756901D01*
X1329909Y756734D01*
X1330242Y756609D01*
X1330617Y756567D01*
X1330992Y756609D01*
X1331325Y756734D01*
X1331575Y756901D01*
X1331784Y757151D01*
X1331867Y757484D01*
X1331784Y757817D01*
X1331575Y758067D01*
X1331325Y758234D01*
X1330992Y758359D01*
X1330617Y758401D01*
X1330242Y758359D01*
X1329909Y758234D01*
X1329659Y758067D01*
X1329450Y757817D01*
X1329367Y757484D01*
G01X1331867Y761084D02*
X1329367D01*
X1331159Y759542D01*
Y761626D01*
G01X1331367Y762767D02*
X1331659Y763017D01*
X1331825Y763351D01*
X1331867Y763726D01*
X1331825Y764059D01*
X1331617Y764392D01*
X1331367Y764601D01*
X1331117Y764642D01*
X1330825Y764559D01*
X1330617Y764267D01*
X1330534Y763976D01*
Y763601D01*
G01Y763976D02*
X1330409Y764226D01*
X1330200Y764434D01*
X1329950Y764517D01*
X1329700Y764434D01*
X1329492Y764226D01*
X1329367Y763851D01*
X1329409Y763476D01*
X1329575Y763101D01*
G01X1313739Y818005D02*
X1313614Y817755D01*
X1313531Y817463D01*
Y817130D01*
X1313656Y816755D01*
X1313864Y816463D01*
X1314114Y816255D01*
X1314531Y816088D01*
X1314906Y816046D01*
X1315281Y816130D01*
X1315531Y816255D01*
X1315781Y816505D01*
X1315948Y816796D01*
X1316031Y817088D01*
Y817380D01*
X1315948Y817671D01*
X1315823Y817921D01*
X1315656Y818130D01*
G01X1314989Y819396D02*
X1314698Y819688D01*
X1314531Y819938D01*
X1314448Y820271D01*
X1314531Y820563D01*
X1314698Y820771D01*
X1314948Y820938D01*
X1315239Y820980D01*
X1315489Y820938D01*
X1315739Y820771D01*
X1315948Y820521D01*
X1316031Y820230D01*
X1315948Y819896D01*
X1315698Y819605D01*
X1315323Y819438D01*
X1314906Y819396D01*
X1314364Y819480D01*
X1314073Y819605D01*
X1313781Y819813D01*
X1313573Y820105D01*
X1313531Y820396D01*
X1313614Y820688D01*
X1313823Y820896D01*
G01X1316031Y823288D02*
X1313531D01*
X1314031Y822788D01*
G01X1316031D02*
Y823788D01*
G01X1326338Y818005D02*
X1326213Y817755D01*
X1326130Y817463D01*
Y817130D01*
X1326255Y816755D01*
X1326463Y816463D01*
X1326713Y816255D01*
X1327130Y816088D01*
X1327505Y816046D01*
X1327880Y816130D01*
X1328130Y816255D01*
X1328380Y816505D01*
X1328547Y816796D01*
X1328630Y817088D01*
Y817380D01*
X1328547Y817671D01*
X1328422Y817921D01*
X1328255Y818130D01*
G01Y819271D02*
X1328463Y819521D01*
X1328588Y819813D01*
X1328630Y820188D01*
X1328547Y820563D01*
X1328380Y820855D01*
X1328088Y821063D01*
X1327755Y821105D01*
X1327422Y821021D01*
X1327213Y820813D01*
X1327047Y820521D01*
X1327005Y820230D01*
X1327047Y819938D01*
X1327213Y819563D01*
X1326130Y819688D01*
Y820813D01*
G01X1328338Y822580D02*
X1328547Y822871D01*
X1328630Y823205D01*
X1328547Y823538D01*
X1328297Y823830D01*
X1327922Y824038D01*
X1327547Y824121D01*
X1327088D01*
X1326713Y824038D01*
X1326380Y823830D01*
X1326213Y823580D01*
X1326130Y823288D01*
X1326213Y822955D01*
X1326380Y822705D01*
X1326630Y822538D01*
X1326963Y822455D01*
X1327255Y822538D01*
X1327547Y822746D01*
X1327713Y822996D01*
X1327755Y823288D01*
X1327672Y823621D01*
X1327463Y823871D01*
X1327088Y824121D01*
G01X1322338Y818005D02*
X1322213Y817755D01*
X1322130Y817463D01*
Y817130D01*
X1322255Y816755D01*
X1322463Y816463D01*
X1322713Y816255D01*
X1323130Y816088D01*
X1323505Y816046D01*
X1323880Y816130D01*
X1324130Y816255D01*
X1324380Y816505D01*
X1324547Y816796D01*
X1324630Y817088D01*
Y817380D01*
X1324547Y817671D01*
X1324422Y817921D01*
X1324255Y818130D01*
G01Y819271D02*
X1324463Y819521D01*
X1324588Y819813D01*
X1324630Y820188D01*
X1324547Y820563D01*
X1324380Y820855D01*
X1324088Y821063D01*
X1323755Y821105D01*
X1323422Y821021D01*
X1323213Y820813D01*
X1323047Y820521D01*
X1323005Y820230D01*
X1323047Y819938D01*
X1323213Y819563D01*
X1322130Y819688D01*
Y820813D01*
G01X1324630Y823288D02*
X1324588Y823580D01*
X1324463Y823913D01*
X1324255Y824121D01*
X1323963Y824205D01*
X1323672Y824121D01*
X1323422Y823871D01*
X1323297Y823496D01*
Y823080D01*
X1323213Y822830D01*
X1323005Y822621D01*
X1322713Y822538D01*
X1322422Y822663D01*
X1322213Y822955D01*
X1322130Y823288D01*
X1322213Y823621D01*
X1322422Y823913D01*
X1322713Y824038D01*
X1323005Y823955D01*
X1323213Y823746D01*
X1323297Y823496D01*
Y823080D01*
X1323422Y822705D01*
X1323672Y822455D01*
X1323963Y822371D01*
X1324255Y822455D01*
X1324463Y822663D01*
X1324588Y822996D01*
X1324630Y823288D01*
G01X1338936Y818005D02*
X1338811Y817755D01*
X1338728Y817463D01*
Y817130D01*
X1338853Y816755D01*
X1339061Y816463D01*
X1339311Y816255D01*
X1339728Y816088D01*
X1340103Y816046D01*
X1340478Y816130D01*
X1340728Y816255D01*
X1340978Y816505D01*
X1341145Y816796D01*
X1341228Y817088D01*
Y817380D01*
X1341145Y817671D01*
X1341020Y817921D01*
X1340853Y818130D01*
G01Y819271D02*
X1341061Y819521D01*
X1341186Y819813D01*
X1341228Y820188D01*
X1341145Y820563D01*
X1340978Y820855D01*
X1340686Y821063D01*
X1340353Y821105D01*
X1340020Y821021D01*
X1339811Y820813D01*
X1339645Y820521D01*
X1339603Y820230D01*
X1339645Y819938D01*
X1339811Y819563D01*
X1338728Y819688D01*
Y820813D01*
G01X1341228Y823205D02*
X1340686Y823288D01*
X1340228Y823413D01*
X1339811Y823580D01*
X1339353Y823788D01*
X1338728Y824121D01*
Y822455D01*
G01X1334936Y818005D02*
X1334811Y817755D01*
X1334728Y817463D01*
Y817130D01*
X1334853Y816755D01*
X1335061Y816463D01*
X1335311Y816255D01*
X1335728Y816088D01*
X1336103Y816046D01*
X1336478Y816130D01*
X1336728Y816255D01*
X1336978Y816505D01*
X1337145Y816796D01*
X1337228Y817088D01*
Y817380D01*
X1337145Y817671D01*
X1337020Y817921D01*
X1336853Y818130D01*
G01Y819271D02*
X1337061Y819521D01*
X1337186Y819813D01*
X1337228Y820188D01*
X1337145Y820563D01*
X1336978Y820855D01*
X1336686Y821063D01*
X1336353Y821105D01*
X1336020Y821021D01*
X1335811Y820813D01*
X1335645Y820521D01*
X1335603Y820230D01*
X1335645Y819938D01*
X1335811Y819563D01*
X1334728Y819688D01*
Y820813D01*
G01X1336186Y822496D02*
X1335895Y822788D01*
X1335728Y823038D01*
X1335645Y823371D01*
X1335728Y823663D01*
X1335895Y823871D01*
X1336145Y824038D01*
X1336436Y824080D01*
X1336686Y824038D01*
X1336936Y823871D01*
X1337145Y823621D01*
X1337228Y823330D01*
X1337145Y822996D01*
X1336895Y822705D01*
X1336520Y822538D01*
X1336103Y822496D01*
X1335561Y822580D01*
X1335270Y822705D01*
X1334978Y822913D01*
X1334770Y823205D01*
X1334728Y823496D01*
X1334811Y823788D01*
X1335020Y823996D01*
G01X1367339Y153184D02*
Y155684D01*
X1368380D01*
X1368714Y155559D01*
X1368922Y155392D01*
X1369005Y155059D01*
X1368922Y154726D01*
X1368672Y154517D01*
X1368380Y154392D01*
X1367339D01*
G01X1368380D02*
X1369005Y153184D01*
G01X1371189D02*
X1371272Y153726D01*
X1371397Y154184D01*
X1371564Y154601D01*
X1371772Y155059D01*
X1372105Y155684D01*
X1370439D01*
G01X1373664Y153476D02*
X1373955Y153267D01*
X1374289Y153184D01*
X1374622Y153267D01*
X1374914Y153517D01*
X1375122Y153892D01*
X1375205Y154267D01*
Y154726D01*
X1375122Y155101D01*
X1374914Y155434D01*
X1374664Y155601D01*
X1374372Y155684D01*
X1374039Y155601D01*
X1373789Y155434D01*
X1373622Y155184D01*
X1373539Y154851D01*
X1373622Y154559D01*
X1373830Y154267D01*
X1374080Y154101D01*
X1374372Y154059D01*
X1374705Y154142D01*
X1374955Y154351D01*
X1375205Y154726D01*
G01X1377472Y155684D02*
X1377139Y155601D01*
X1376889Y155392D01*
X1376722Y155142D01*
X1376597Y154809D01*
X1376555Y154434D01*
X1376597Y154059D01*
X1376722Y153726D01*
X1376889Y153476D01*
X1377139Y153267D01*
X1377472Y153184D01*
X1377805Y153267D01*
X1378055Y153476D01*
X1378222Y153726D01*
X1378347Y154059D01*
X1378389Y154434D01*
X1378347Y154809D01*
X1378222Y155142D01*
X1378055Y155392D01*
X1377805Y155601D01*
X1377472Y155684D01*
G01X1380572Y153184D02*
X1380864Y153226D01*
X1381197Y153351D01*
X1381405Y153559D01*
X1381489Y153851D01*
X1381405Y154142D01*
X1381155Y154392D01*
X1380780Y154517D01*
X1380364D01*
X1380114Y154601D01*
X1379905Y154809D01*
X1379822Y155101D01*
X1379947Y155392D01*
X1380239Y155601D01*
X1380572Y155684D01*
X1380905Y155601D01*
X1381197Y155392D01*
X1381322Y155101D01*
X1381239Y154809D01*
X1381030Y154601D01*
X1380780Y154517D01*
X1380364D01*
X1379989Y154392D01*
X1379739Y154142D01*
X1379655Y153851D01*
X1379739Y153559D01*
X1379947Y153351D01*
X1380280Y153226D01*
X1380572Y153184D01*
G01X1361218Y170102D02*
Y166102D01*
X1368618D01*
G01X1380134Y178909D02*
X1376134D01*
Y171509D01*
G01X1367355Y156901D02*
Y159401D01*
X1368396D01*
X1368730Y159276D01*
X1368938Y159109D01*
X1369021Y158776D01*
X1368938Y158443D01*
X1368688Y158234D01*
X1368396Y158109D01*
X1367355D01*
G01X1368396D02*
X1369021Y156901D01*
G01X1370496Y157943D02*
X1370788Y158234D01*
X1371038Y158401D01*
X1371371Y158484D01*
X1371663Y158401D01*
X1371871Y158234D01*
X1372038Y157984D01*
X1372080Y157693D01*
X1372038Y157443D01*
X1371871Y157193D01*
X1371621Y156984D01*
X1371330Y156901D01*
X1370996Y156984D01*
X1370705Y157234D01*
X1370538Y157609D01*
X1370496Y158026D01*
X1370580Y158568D01*
X1370705Y158859D01*
X1370913Y159151D01*
X1371205Y159359D01*
X1371496Y159401D01*
X1371788Y159318D01*
X1371996Y159109D01*
G01X1373680Y157193D02*
X1373971Y156984D01*
X1374305Y156901D01*
X1374638Y156984D01*
X1374930Y157234D01*
X1375138Y157609D01*
X1375221Y157984D01*
Y158443D01*
X1375138Y158818D01*
X1374930Y159151D01*
X1374680Y159318D01*
X1374388Y159401D01*
X1374055Y159318D01*
X1373805Y159151D01*
X1373638Y158901D01*
X1373555Y158568D01*
X1373638Y158276D01*
X1373846Y157984D01*
X1374096Y157818D01*
X1374388Y157776D01*
X1374721Y157859D01*
X1374971Y158068D01*
X1375221Y158443D01*
G01X1377988Y156901D02*
Y159401D01*
X1376446Y157609D01*
X1378530D01*
G01X1361124Y176820D02*
X1357124D01*
Y169420D01*
G01X1367305Y161317D02*
Y163817D01*
X1368346D01*
X1368680Y163692D01*
X1368888Y163525D01*
X1368971Y163192D01*
X1368888Y162859D01*
X1368638Y162650D01*
X1368346Y162525D01*
X1367305D01*
G01X1368346D02*
X1368971Y161317D01*
G01X1371155D02*
X1371238Y161859D01*
X1371363Y162317D01*
X1371530Y162734D01*
X1371738Y163192D01*
X1372071Y163817D01*
X1370405D01*
G01X1373630Y161609D02*
X1373921Y161400D01*
X1374255Y161317D01*
X1374588Y161400D01*
X1374880Y161650D01*
X1375088Y162025D01*
X1375171Y162400D01*
Y162859D01*
X1375088Y163234D01*
X1374880Y163567D01*
X1374630Y163734D01*
X1374338Y163817D01*
X1374005Y163734D01*
X1373755Y163567D01*
X1373588Y163317D01*
X1373505Y162984D01*
X1373588Y162692D01*
X1373796Y162400D01*
X1374046Y162234D01*
X1374338Y162192D01*
X1374671Y162275D01*
X1374921Y162484D01*
X1375171Y162859D01*
G01X1377438Y163817D02*
X1377105Y163734D01*
X1376855Y163525D01*
X1376688Y163275D01*
X1376563Y162942D01*
X1376521Y162567D01*
X1376563Y162192D01*
X1376688Y161859D01*
X1376855Y161609D01*
X1377105Y161400D01*
X1377438Y161317D01*
X1377771Y161400D01*
X1378021Y161609D01*
X1378188Y161859D01*
X1378313Y162192D01*
X1378355Y162567D01*
X1378313Y162942D01*
X1378188Y163275D01*
X1378021Y163525D01*
X1377771Y163734D01*
X1377438Y163817D01*
G01X1379746Y163400D02*
X1379996Y163650D01*
X1380288Y163775D01*
X1380621Y163817D01*
X1381038Y163734D01*
X1381330Y163525D01*
X1381413Y163275D01*
X1381371Y163025D01*
X1381205Y162817D01*
X1380371Y162400D01*
X1379996Y162109D01*
X1379746Y161692D01*
X1379663Y161317D01*
X1381413D01*
G01X1361718Y184602D02*
Y170602D01*
G01X1374718D02*
Y184602D01*
G01X1361718Y170602D02*
X1374718D01*
G01X1372300Y197100D02*
X1349700D01*
G01X1372300Y186900D02*
Y197100D01*
G01X1349700Y186900D02*
X1372300D01*
G01X1349700Y197100D02*
Y186900D01*
G01X1372300Y197100D02*
X1349700D01*
G01X1372300Y186900D02*
Y197100D01*
G01X1349700Y186900D02*
X1372300D01*
G01X1349700Y197100D02*
Y186900D01*
G01X1361011Y184384D02*
X1357011D01*
Y176984D01*
G01X1377667Y202900D02*
Y205400D01*
X1378667D01*
X1379000Y205275D01*
X1379250Y204983D01*
X1379333Y204650D01*
X1379250Y204317D01*
X1379042Y204067D01*
X1378667Y203942D01*
X1377667D01*
G01X1382517Y205192D02*
X1382267Y205317D01*
X1381975Y205400D01*
X1381642D01*
X1381267Y205275D01*
X1380975Y205067D01*
X1380767Y204817D01*
X1380600Y204400D01*
X1380558Y204025D01*
X1380642Y203650D01*
X1380767Y203400D01*
X1381017Y203150D01*
X1381308Y202983D01*
X1381600Y202900D01*
X1381892D01*
X1382183Y202983D01*
X1382433Y203108D01*
X1382642Y203275D01*
G01X1383908Y204983D02*
X1384158Y205233D01*
X1384450Y205358D01*
X1384783Y205400D01*
X1385200Y205317D01*
X1385492Y205108D01*
X1385575Y204858D01*
X1385533Y204608D01*
X1385367Y204400D01*
X1384533Y203983D01*
X1384158Y203692D01*
X1383908Y203275D01*
X1383825Y202900D01*
X1385575D01*
G01X1387800D02*
Y205400D01*
X1387300Y204900D01*
G01Y202900D02*
X1388300D01*
G01X1390817D02*
X1390900Y203442D01*
X1391025Y203900D01*
X1391192Y204317D01*
X1391400Y204775D01*
X1391733Y205400D01*
X1390067D01*
G01X1373350Y198350D02*
X1354650D01*
Y208650D01*
X1373350D01*
Y198350D01*
G01X1374718Y184602D02*
X1361718D01*
G01X1377148Y239909D02*
Y242409D01*
X1378148D01*
X1378481Y242284D01*
X1378731Y241992D01*
X1378814Y241659D01*
X1378731Y241326D01*
X1378523Y241076D01*
X1378148Y240951D01*
X1377148D01*
G01X1381998Y242201D02*
X1381748Y242326D01*
X1381456Y242409D01*
X1381123D01*
X1380748Y242284D01*
X1380456Y242076D01*
X1380248Y241826D01*
X1380081Y241409D01*
X1380039Y241034D01*
X1380123Y240659D01*
X1380248Y240409D01*
X1380498Y240159D01*
X1380789Y239992D01*
X1381081Y239909D01*
X1381373D01*
X1381664Y239992D01*
X1381914Y240117D01*
X1382123Y240284D01*
G01X1384181Y239909D02*
Y242409D01*
X1383681Y241909D01*
G01Y239909D02*
X1384681D01*
G01X1386489Y240951D02*
X1386781Y241242D01*
X1387031Y241409D01*
X1387364Y241492D01*
X1387656Y241409D01*
X1387864Y241242D01*
X1388031Y240992D01*
X1388073Y240701D01*
X1388031Y240451D01*
X1387864Y240201D01*
X1387614Y239992D01*
X1387323Y239909D01*
X1386989Y239992D01*
X1386698Y240242D01*
X1386531Y240617D01*
X1386489Y241034D01*
X1386573Y241576D01*
X1386698Y241867D01*
X1386906Y242159D01*
X1387198Y242367D01*
X1387489Y242409D01*
X1387781Y242326D01*
X1387989Y242117D01*
G01X1389673Y240201D02*
X1389964Y239992D01*
X1390298Y239909D01*
X1390631Y239992D01*
X1390923Y240242D01*
X1391131Y240617D01*
X1391214Y240992D01*
Y241451D01*
X1391131Y241826D01*
X1390923Y242159D01*
X1390673Y242326D01*
X1390381Y242409D01*
X1390048Y242326D01*
X1389798Y242159D01*
X1389631Y241909D01*
X1389548Y241576D01*
X1389631Y241284D01*
X1389839Y240992D01*
X1390089Y240826D01*
X1390381Y240784D01*
X1390714Y240867D01*
X1390964Y241076D01*
X1391214Y241451D01*
G01X1377667Y216400D02*
Y218900D01*
X1378667D01*
X1379000Y218775D01*
X1379250Y218483D01*
X1379333Y218150D01*
X1379250Y217817D01*
X1379042Y217567D01*
X1378667Y217442D01*
X1377667D01*
G01X1382517Y218692D02*
X1382267Y218817D01*
X1381975Y218900D01*
X1381642D01*
X1381267Y218775D01*
X1380975Y218567D01*
X1380767Y218317D01*
X1380600Y217900D01*
X1380558Y217525D01*
X1380642Y217150D01*
X1380767Y216900D01*
X1381017Y216650D01*
X1381308Y216483D01*
X1381600Y216400D01*
X1381892D01*
X1382183Y216483D01*
X1382433Y216608D01*
X1382642Y216775D01*
G01X1383908Y218483D02*
X1384158Y218733D01*
X1384450Y218858D01*
X1384783Y218900D01*
X1385200Y218817D01*
X1385492Y218608D01*
X1385575Y218358D01*
X1385533Y218108D01*
X1385367Y217900D01*
X1384533Y217483D01*
X1384158Y217192D01*
X1383908Y216775D01*
X1383825Y216400D01*
X1385575D01*
G01X1387800D02*
Y218900D01*
X1387300Y218400D01*
G01Y216400D02*
X1388300D01*
G01X1390192Y216692D02*
X1390483Y216483D01*
X1390817Y216400D01*
X1391150Y216483D01*
X1391442Y216733D01*
X1391650Y217108D01*
X1391733Y217483D01*
Y217942D01*
X1391650Y218317D01*
X1391442Y218650D01*
X1391192Y218817D01*
X1390900Y218900D01*
X1390567Y218817D01*
X1390317Y218650D01*
X1390150Y218400D01*
X1390067Y218067D01*
X1390150Y217775D01*
X1390358Y217483D01*
X1390608Y217317D01*
X1390900Y217275D01*
X1391233Y217358D01*
X1391483Y217567D01*
X1391733Y217942D01*
G01X1373350Y211850D02*
X1354650D01*
Y222150D01*
X1373350D01*
Y211850D01*
G01X1377667Y229900D02*
Y232400D01*
X1378667D01*
X1379000Y232275D01*
X1379250Y231983D01*
X1379333Y231650D01*
X1379250Y231317D01*
X1379042Y231067D01*
X1378667Y230942D01*
X1377667D01*
G01X1382517Y232192D02*
X1382267Y232317D01*
X1381975Y232400D01*
X1381642D01*
X1381267Y232275D01*
X1380975Y232067D01*
X1380767Y231817D01*
X1380600Y231400D01*
X1380558Y231025D01*
X1380642Y230650D01*
X1380767Y230400D01*
X1381017Y230150D01*
X1381308Y229983D01*
X1381600Y229900D01*
X1381892D01*
X1382183Y229983D01*
X1382433Y230108D01*
X1382642Y230275D01*
G01X1383908Y231983D02*
X1384158Y232233D01*
X1384450Y232358D01*
X1384783Y232400D01*
X1385200Y232317D01*
X1385492Y232108D01*
X1385575Y231858D01*
X1385533Y231608D01*
X1385367Y231400D01*
X1384533Y230983D01*
X1384158Y230692D01*
X1383908Y230275D01*
X1383825Y229900D01*
X1385575D01*
G01X1387008Y231983D02*
X1387258Y232233D01*
X1387550Y232358D01*
X1387883Y232400D01*
X1388300Y232317D01*
X1388592Y232108D01*
X1388675Y231858D01*
X1388633Y231608D01*
X1388467Y231400D01*
X1387633Y230983D01*
X1387258Y230692D01*
X1387008Y230275D01*
X1386925Y229900D01*
X1388675D01*
G01X1390900Y232400D02*
X1390567Y232317D01*
X1390317Y232108D01*
X1390150Y231858D01*
X1390025Y231525D01*
X1389983Y231150D01*
X1390025Y230775D01*
X1390150Y230442D01*
X1390317Y230192D01*
X1390567Y229983D01*
X1390900Y229900D01*
X1391233Y229983D01*
X1391483Y230192D01*
X1391650Y230442D01*
X1391775Y230775D01*
X1391817Y231150D01*
X1391775Y231525D01*
X1391650Y231858D01*
X1391483Y232108D01*
X1391233Y232317D01*
X1390900Y232400D01*
G01X1373350Y225350D02*
X1354650D01*
Y235650D01*
X1373350D01*
Y225350D01*
G01X1349843Y269156D02*
X1352843D01*
G01X1349843Y259313D02*
X1351843D01*
G01X1377207Y247521D02*
Y250021D01*
X1378207D01*
X1378540Y249896D01*
X1378790Y249604D01*
X1378873Y249271D01*
X1378790Y248938D01*
X1378582Y248688D01*
X1378207Y248563D01*
X1377207D01*
G01X1382057Y249813D02*
X1381807Y249938D01*
X1381515Y250021D01*
X1381182D01*
X1380807Y249896D01*
X1380515Y249688D01*
X1380307Y249438D01*
X1380140Y249021D01*
X1380098Y248646D01*
X1380182Y248271D01*
X1380307Y248021D01*
X1380557Y247771D01*
X1380848Y247604D01*
X1381140Y247521D01*
X1381432D01*
X1381723Y247604D01*
X1381973Y247729D01*
X1382182Y247896D01*
G01X1384240Y247521D02*
Y250021D01*
X1383740Y249521D01*
G01Y247521D02*
X1384740D01*
G01X1387257D02*
X1387340Y248063D01*
X1387465Y248521D01*
X1387632Y248938D01*
X1387840Y249396D01*
X1388173Y250021D01*
X1386507D01*
G01X1389523Y248021D02*
X1389773Y247729D01*
X1390107Y247563D01*
X1390482Y247521D01*
X1390815Y247563D01*
X1391148Y247771D01*
X1391357Y248021D01*
X1391398Y248271D01*
X1391315Y248563D01*
X1391023Y248771D01*
X1390732Y248854D01*
X1390357D01*
G01X1390732D02*
X1390982Y248979D01*
X1391190Y249188D01*
X1391273Y249438D01*
X1391190Y249688D01*
X1390982Y249896D01*
X1390607Y250021D01*
X1390232Y249979D01*
X1389857Y249813D01*
G01X1367600Y262267D02*
X1365100D01*
Y263267D01*
X1365225Y263600D01*
X1365517Y263850D01*
X1365850Y263933D01*
X1366183Y263850D01*
X1366433Y263642D01*
X1366558Y263267D01*
Y262267D01*
G01X1365308Y267117D02*
X1365183Y266867D01*
X1365100Y266575D01*
Y266242D01*
X1365225Y265867D01*
X1365433Y265575D01*
X1365683Y265367D01*
X1366100Y265200D01*
X1366475Y265158D01*
X1366850Y265242D01*
X1367100Y265367D01*
X1367350Y265617D01*
X1367517Y265908D01*
X1367600Y266200D01*
Y266492D01*
X1367517Y266783D01*
X1367392Y267033D01*
X1367225Y267242D01*
G01X1367600Y269300D02*
X1365100D01*
X1365600Y268800D01*
G01X1367600D02*
Y269800D01*
G01X1367308Y271692D02*
X1367517Y271983D01*
X1367600Y272317D01*
X1367517Y272650D01*
X1367267Y272942D01*
X1366892Y273150D01*
X1366517Y273233D01*
X1366058D01*
X1365683Y273150D01*
X1365350Y272942D01*
X1365183Y272692D01*
X1365100Y272400D01*
X1365183Y272067D01*
X1365350Y271817D01*
X1365600Y271650D01*
X1365933Y271567D01*
X1366225Y271650D01*
X1366517Y271858D01*
X1366683Y272108D01*
X1366725Y272400D01*
X1366642Y272733D01*
X1366433Y272983D01*
X1366058Y273233D01*
G01X1365100Y275500D02*
X1365183Y275167D01*
X1365392Y274917D01*
X1365642Y274750D01*
X1365975Y274625D01*
X1366350Y274583D01*
X1366725Y274625D01*
X1367058Y274750D01*
X1367308Y274917D01*
X1367517Y275167D01*
X1367600Y275500D01*
X1367517Y275833D01*
X1367308Y276083D01*
X1367058Y276250D01*
X1366725Y276375D01*
X1366350Y276417D01*
X1365975Y276375D01*
X1365642Y276250D01*
X1365392Y276083D01*
X1365183Y275833D01*
X1365100Y275500D01*
G01X1362200Y276500D02*
Y280500D01*
X1354800D01*
G01X1372500Y261467D02*
X1370000D01*
Y262467D01*
X1370125Y262800D01*
X1370417Y263050D01*
X1370750Y263133D01*
X1371083Y263050D01*
X1371333Y262842D01*
X1371458Y262467D01*
Y261467D01*
G01X1372500Y264567D02*
X1370000D01*
Y265608D01*
X1370125Y265942D01*
X1370292Y266150D01*
X1370625Y266233D01*
X1370958Y266150D01*
X1371167Y265900D01*
X1371292Y265608D01*
Y264567D01*
G01Y265608D02*
X1372500Y266233D01*
G01Y268500D02*
X1370000D01*
X1370500Y268000D01*
G01X1372500D02*
Y269000D01*
G01X1372125Y270683D02*
X1372333Y270933D01*
X1372458Y271225D01*
X1372500Y271600D01*
X1372417Y271975D01*
X1372250Y272267D01*
X1371958Y272475D01*
X1371625Y272517D01*
X1371292Y272433D01*
X1371083Y272225D01*
X1370917Y271933D01*
X1370875Y271642D01*
X1370917Y271350D01*
X1371083Y270975D01*
X1370000Y271100D01*
Y272225D01*
G01X1372500Y274700D02*
X1372458Y274992D01*
X1372333Y275325D01*
X1372125Y275533D01*
X1371833Y275617D01*
X1371542Y275533D01*
X1371292Y275283D01*
X1371167Y274908D01*
Y274492D01*
X1371083Y274242D01*
X1370875Y274033D01*
X1370583Y273950D01*
X1370292Y274075D01*
X1370083Y274367D01*
X1370000Y274700D01*
X1370083Y275033D01*
X1370292Y275325D01*
X1370583Y275450D01*
X1370875Y275367D01*
X1371083Y275158D01*
X1371167Y274908D01*
Y274492D01*
X1371292Y274117D01*
X1371542Y273867D01*
X1371833Y273783D01*
X1372125Y273867D01*
X1372333Y274075D01*
X1372458Y274408D01*
X1372500Y274700D01*
G01X1359500Y264800D02*
X1363500D01*
Y272200D01*
G01X1356967Y285000D02*
Y287500D01*
X1357967D01*
X1358300Y287375D01*
X1358550Y287083D01*
X1358633Y286750D01*
X1358550Y286417D01*
X1358342Y286167D01*
X1357967Y286042D01*
X1356967D01*
G01X1360067Y285000D02*
Y287500D01*
X1361108D01*
X1361442Y287375D01*
X1361650Y287208D01*
X1361733Y286875D01*
X1361650Y286542D01*
X1361400Y286333D01*
X1361108Y286208D01*
X1360067D01*
G01X1361108D02*
X1361733Y285000D01*
G01X1364000D02*
Y287500D01*
X1363500Y287000D01*
G01Y285000D02*
X1364500D01*
G01X1366308Y286042D02*
X1366600Y286333D01*
X1366850Y286500D01*
X1367183Y286583D01*
X1367475Y286500D01*
X1367683Y286333D01*
X1367850Y286083D01*
X1367892Y285792D01*
X1367850Y285542D01*
X1367683Y285292D01*
X1367433Y285083D01*
X1367142Y285000D01*
X1366808Y285083D01*
X1366517Y285333D01*
X1366350Y285708D01*
X1366308Y286125D01*
X1366392Y286667D01*
X1366517Y286958D01*
X1366725Y287250D01*
X1367017Y287458D01*
X1367308Y287500D01*
X1367600Y287417D01*
X1367808Y287208D01*
G01X1370200Y287500D02*
X1369867Y287417D01*
X1369617Y287208D01*
X1369450Y286958D01*
X1369325Y286625D01*
X1369283Y286250D01*
X1369325Y285875D01*
X1369450Y285542D01*
X1369617Y285292D01*
X1369867Y285083D01*
X1370200Y285000D01*
X1370533Y285083D01*
X1370783Y285292D01*
X1370950Y285542D01*
X1371075Y285875D01*
X1371117Y286250D01*
X1371075Y286625D01*
X1370950Y286958D01*
X1370783Y287208D01*
X1370533Y287417D01*
X1370200Y287500D01*
G01X1351449Y818289D02*
X1351324Y818039D01*
X1351241Y817747D01*
Y817414D01*
X1351366Y817039D01*
X1351574Y816747D01*
X1351824Y816539D01*
X1352241Y816372D01*
X1352616Y816330D01*
X1352991Y816414D01*
X1353241Y816539D01*
X1353491Y816789D01*
X1353658Y817080D01*
X1353741Y817372D01*
Y817664D01*
X1353658Y817955D01*
X1353533Y818205D01*
X1353366Y818414D01*
G01Y819555D02*
X1353574Y819805D01*
X1353699Y820097D01*
X1353741Y820472D01*
X1353658Y820847D01*
X1353491Y821139D01*
X1353199Y821347D01*
X1352866Y821389D01*
X1352533Y821305D01*
X1352324Y821097D01*
X1352158Y820805D01*
X1352116Y820514D01*
X1352158Y820222D01*
X1352324Y819847D01*
X1351241Y819972D01*
Y821097D01*
G01X1353366Y822655D02*
X1353574Y822905D01*
X1353699Y823197D01*
X1353741Y823572D01*
X1353658Y823947D01*
X1353491Y824239D01*
X1353199Y824447D01*
X1352866Y824489D01*
X1352533Y824405D01*
X1352324Y824197D01*
X1352158Y823905D01*
X1352116Y823614D01*
X1352158Y823322D01*
X1352324Y822947D01*
X1351241Y823072D01*
Y824197D01*
G01X1347449Y818289D02*
X1347324Y818039D01*
X1347241Y817747D01*
Y817414D01*
X1347366Y817039D01*
X1347574Y816747D01*
X1347824Y816539D01*
X1348241Y816372D01*
X1348616Y816330D01*
X1348991Y816414D01*
X1349241Y816539D01*
X1349491Y816789D01*
X1349658Y817080D01*
X1349741Y817372D01*
Y817664D01*
X1349658Y817955D01*
X1349533Y818205D01*
X1349366Y818414D01*
G01Y819555D02*
X1349574Y819805D01*
X1349699Y820097D01*
X1349741Y820472D01*
X1349658Y820847D01*
X1349491Y821139D01*
X1349199Y821347D01*
X1348866Y821389D01*
X1348533Y821305D01*
X1348324Y821097D01*
X1348158Y820805D01*
X1348116Y820514D01*
X1348158Y820222D01*
X1348324Y819847D01*
X1347241Y819972D01*
Y821097D01*
G01X1349741Y824072D02*
X1347241D01*
X1349033Y822530D01*
Y824614D01*
G01X1385953Y176108D02*
Y178608D01*
X1386994D01*
X1387328Y178483D01*
X1387536Y178316D01*
X1387619Y177983D01*
X1387536Y177650D01*
X1387286Y177441D01*
X1386994Y177316D01*
X1385953D01*
G01X1386994D02*
X1387619Y176108D01*
G01X1389094Y177150D02*
X1389386Y177441D01*
X1389636Y177608D01*
X1389969Y177691D01*
X1390261Y177608D01*
X1390469Y177441D01*
X1390636Y177191D01*
X1390678Y176900D01*
X1390636Y176650D01*
X1390469Y176400D01*
X1390219Y176191D01*
X1389928Y176108D01*
X1389594Y176191D01*
X1389303Y176441D01*
X1389136Y176816D01*
X1389094Y177233D01*
X1389178Y177775D01*
X1389303Y178066D01*
X1389511Y178358D01*
X1389803Y178566D01*
X1390094Y178608D01*
X1390386Y178525D01*
X1390594Y178316D01*
G01X1392986Y176108D02*
X1393278Y176150D01*
X1393611Y176275D01*
X1393819Y176483D01*
X1393903Y176775D01*
X1393819Y177066D01*
X1393569Y177316D01*
X1393194Y177441D01*
X1392778D01*
X1392528Y177525D01*
X1392319Y177733D01*
X1392236Y178025D01*
X1392361Y178316D01*
X1392653Y178525D01*
X1392986Y178608D01*
X1393319Y178525D01*
X1393611Y178316D01*
X1393736Y178025D01*
X1393653Y177733D01*
X1393444Y177525D01*
X1393194Y177441D01*
X1392778D01*
X1392403Y177316D01*
X1392153Y177066D01*
X1392069Y176775D01*
X1392153Y176483D01*
X1392361Y176275D01*
X1392694Y176150D01*
X1392986Y176108D01*
G01X1395378Y176400D02*
X1395669Y176191D01*
X1396003Y176108D01*
X1396336Y176191D01*
X1396628Y176441D01*
X1396836Y176816D01*
X1396919Y177191D01*
Y177650D01*
X1396836Y178025D01*
X1396628Y178358D01*
X1396378Y178525D01*
X1396086Y178608D01*
X1395753Y178525D01*
X1395503Y178358D01*
X1395336Y178108D01*
X1395253Y177775D01*
X1395336Y177483D01*
X1395544Y177191D01*
X1395794Y177025D01*
X1396086Y176983D01*
X1396419Y177066D01*
X1396669Y177275D01*
X1396919Y177650D01*
G01X1382860Y168029D02*
X1382527Y168071D01*
X1382235Y168237D01*
X1381985Y168487D01*
X1381818Y168779D01*
X1381735Y169112D01*
Y169446D01*
X1381818Y169779D01*
X1381985Y170071D01*
X1382235Y170321D01*
X1382527Y170487D01*
X1382860Y170529D01*
X1383193Y170487D01*
X1383485Y170321D01*
X1383735Y170071D01*
X1383902Y169779D01*
X1383985Y169446D01*
Y169112D01*
X1383902Y168779D01*
X1383735Y168487D01*
X1383485Y168237D01*
X1383193Y168071D01*
X1382860Y168029D01*
G01X1383193Y168696D02*
X1383693Y168029D01*
G01X1385043Y168529D02*
X1385293Y168237D01*
X1385627Y168071D01*
X1386002Y168029D01*
X1386335Y168071D01*
X1386668Y168279D01*
X1386877Y168529D01*
X1386918Y168779D01*
X1386835Y169071D01*
X1386543Y169279D01*
X1386252Y169362D01*
X1385877D01*
G01X1386252D02*
X1386502Y169487D01*
X1386710Y169696D01*
X1386793Y169946D01*
X1386710Y170196D01*
X1386502Y170404D01*
X1386127Y170529D01*
X1385752Y170487D01*
X1385377Y170321D01*
G01X1388977Y168029D02*
X1389060Y168571D01*
X1389185Y169029D01*
X1389352Y169446D01*
X1389560Y169904D01*
X1389893Y170529D01*
X1388227D01*
G01X1385067Y190900D02*
Y193400D01*
X1386067D01*
X1386400Y193275D01*
X1386650Y192983D01*
X1386733Y192650D01*
X1386650Y192317D01*
X1386442Y192067D01*
X1386067Y191942D01*
X1385067D01*
G01X1388167Y193400D02*
Y190900D01*
X1389833D01*
G01X1392100D02*
X1392392Y190942D01*
X1392725Y191067D01*
X1392933Y191275D01*
X1393017Y191567D01*
X1392933Y191858D01*
X1392683Y192108D01*
X1392308Y192233D01*
X1391892D01*
X1391642Y192317D01*
X1391433Y192525D01*
X1391350Y192817D01*
X1391475Y193108D01*
X1391767Y193317D01*
X1392100Y193400D01*
X1392433Y193317D01*
X1392725Y193108D01*
X1392850Y192817D01*
X1392767Y192525D01*
X1392558Y192317D01*
X1392308Y192233D01*
X1391892D01*
X1391517Y192108D01*
X1391267Y191858D01*
X1391183Y191567D01*
X1391267Y191275D01*
X1391475Y191067D01*
X1391808Y190942D01*
X1392100Y190900D01*
G01X1382931Y185182D02*
X1382681Y185307D01*
X1382389Y185390D01*
X1382056D01*
X1381681Y185265D01*
X1381389Y185057D01*
X1381181Y184807D01*
X1381014Y184390D01*
X1380972Y184015D01*
X1381056Y183640D01*
X1381181Y183390D01*
X1381431Y183140D01*
X1381722Y182973D01*
X1382014Y182890D01*
X1382306D01*
X1382597Y182973D01*
X1382847Y183098D01*
X1383056Y183265D01*
G01X1384197Y183390D02*
X1384447Y183098D01*
X1384781Y182932D01*
X1385156Y182890D01*
X1385489Y182932D01*
X1385822Y183140D01*
X1386031Y183390D01*
X1386072Y183640D01*
X1385989Y183932D01*
X1385697Y184140D01*
X1385406Y184223D01*
X1385031D01*
G01X1385406D02*
X1385656Y184348D01*
X1385864Y184557D01*
X1385947Y184807D01*
X1385864Y185057D01*
X1385656Y185265D01*
X1385281Y185390D01*
X1384906Y185348D01*
X1384531Y185182D01*
G01X1387422Y184973D02*
X1387672Y185223D01*
X1387964Y185348D01*
X1388297Y185390D01*
X1388714Y185307D01*
X1389006Y185098D01*
X1389089Y184848D01*
X1389047Y184598D01*
X1388881Y184390D01*
X1388047Y183973D01*
X1387672Y183682D01*
X1387422Y183265D01*
X1387339Y182890D01*
X1389089D01*
G01X1391314D02*
Y185390D01*
X1390814Y184890D01*
G01Y182890D02*
X1391814D01*
G01X1393622Y184973D02*
X1393872Y185223D01*
X1394164Y185348D01*
X1394497Y185390D01*
X1394914Y185307D01*
X1395206Y185098D01*
X1395289Y184848D01*
X1395247Y184598D01*
X1395081Y184390D01*
X1394247Y183973D01*
X1393872Y183682D01*
X1393622Y183265D01*
X1393539Y182890D01*
X1395289D01*
G54D12*
G01X36677Y126614D02*
G02I-4700J0D01*
G01Y116614D02*
G02I-4700J0D01*
G01X32277Y151614D02*
G02I-5300J0D01*
G01X45603Y177598D02*
G02I-4000J0D01*
G01X69579D02*
G02I-4000J0D01*
G01X61587D02*
G02I-4000J0D01*
G01X53595D02*
G02I-4000J0D01*
G01X41567Y187598D02*
G02I-4000J0D01*
G01X49559D02*
G02I-4000J0D01*
G01X57551D02*
G02I-4000J0D01*
G01X68578Y237402D02*
G02I-14200J0D01*
G01X95889Y126614D02*
G02I-4700J0D01*
G01Y116614D02*
G02I-4700J0D01*
G01Y136614D02*
G02I-4700J0D01*
G01X77571Y177598D02*
G02I-4000J0D01*
G01X101489Y151614D02*
G02I-5300J0D01*
G01X85563Y177598D02*
G02I-4000J0D01*
G01X73615Y187598D02*
G02I-4000J0D01*
G01X81607D02*
G02I-4000J0D01*
G01X89599D02*
G02I-4000J0D01*
G01X128915Y142874D02*
G02I-6750J0D01*
G01X138351Y153543D02*
G02I-4100J0D01*
G01X148031Y152398D02*
G02Y154688I-3937J1145D01*
G02Y152398I3937J-1145D01*
G01X165911Y153543D02*
G02I-4100J0D01*
G01X180647Y142874D02*
G02I-6750J0D01*
G01X198100Y274372D02*
G02I-4200J0D01*
G01X188100D02*
G02I-4200J0D01*
G01X208100D02*
G02I-4200J0D01*
G01X218100D02*
G02I-4200J0D01*
G01X306700Y207200D02*
G02I-4200J0D01*
G01X296700D02*
G02I-4200J0D01*
G01X330400D02*
G02I-4200J0D01*
G01X340400D02*
G02I-4200J0D01*
G01X316700D02*
G02I-4200J0D01*
G01X350400D02*
G02I-4200J0D01*
G01X469685Y200680D02*
G02I-4200J0D01*
G01Y190680D02*
G02I-4200J0D01*
G01Y180680D02*
G02I-4200J0D01*
G01X477531Y235560D02*
G02I-4300J0D01*
G01Y274930D02*
G02I-4300J0D01*
G01X492662Y180761D02*
G02I-4200J0D01*
G01Y190761D02*
G02I-4200J0D01*
G01Y200761D02*
G02I-4200J0D01*
G01X505942Y215594D02*
G02I-4200J0D01*
G01X491704Y255245D02*
G02I-4300J0D01*
G01X525942Y215594D02*
G02I-4200J0D01*
G01X515942D02*
G02I-4200J0D01*
G01X535942D02*
G02I-4200J0D01*
G01X776500Y16200D02*
G02I-4200J0D01*
G01X766500D02*
G02I-4200J0D01*
G01X756500D02*
G02I-4200J0D01*
G01X789500Y16100D02*
G02I-4200J0D01*
G01X799500D02*
G02I-4200J0D01*
G01X809500D02*
G02I-4200J0D01*
G01X823491Y265354D02*
G02I-4200J0D01*
G01Y285354D02*
G02I-4200J0D01*
G01X915516Y5908D02*
G02I-3900J0D01*
G01X923386D02*
G02I-3900J0D01*
G01X931261D02*
G02I-3900J0D01*
G01X939136D02*
G02I-3900J0D01*
G01X947011D02*
G02I-3900J0D01*
G01X915516Y13778D02*
G02I-3900J0D01*
G01X923386D02*
G02I-3900J0D01*
G01X931261D02*
G02I-3900J0D01*
G01X939136D02*
G02I-3900J0D01*
G01X947011D02*
G02I-3900J0D01*
G01X954886Y5908D02*
G02I-3900J0D01*
G01X962756D02*
G02I-3900J0D01*
G01X954886Y13778D02*
G02I-3900J0D01*
G01X962756D02*
G02I-3900J0D01*
G01X1079397Y112126D02*
G02I-4200J0D01*
G01Y92126D02*
G02I-4200J0D01*
G01X1352985Y161642D02*
G02I-4200J0D01*
G01X1327395Y179358D02*
G02I-4200J0D01*
G01Y161642D02*
G02I-4200J0D01*
G01X1352985Y179358D02*
G02I-4200J0D01*
G54D22*
G01X25400Y220200D02*
X26500D01*
G01X28100D02*
X29200D01*
G01X26900Y432500D02*
X25800D01*
G01X24200D02*
X23100D01*
G01X34400Y203900D02*
Y205900D01*
G01X44900D02*
Y203900D01*
G01X49750Y199100D02*
Y201100D01*
G01X60250D02*
Y199100D01*
G01X63965Y370408D02*
X67965D01*
G01X40500Y412100D02*
Y413200D01*
G01Y414800D02*
Y415900D01*
G01X38500Y690500D02*
X39600D01*
G01X35800D02*
X36900D01*
G01X45800Y766400D02*
X49800D01*
G01X55500Y773300D02*
Y777300D01*
G01X62900Y773900D02*
X66900D01*
G01X81100Y205800D02*
Y203800D01*
G01X95650Y200400D02*
Y198400D01*
G01X85150D02*
Y200400D01*
G01X70600Y203800D02*
Y205800D01*
G01X70000Y262300D02*
X68900D01*
G01X67300D02*
X66200D01*
G01X77250Y702150D02*
X78350D01*
G01X74550D02*
X75650D01*
G01X88450Y701350D02*
Y700250D01*
G01Y704050D02*
Y702950D01*
G01X82800Y738400D02*
Y734400D01*
G01X82900Y751300D02*
Y747300D01*
G01X67800Y765900D02*
X71800D01*
G01X82800Y764400D02*
Y760400D01*
G01X112464Y129299D02*
X113564D01*
G01X115164D02*
X116264D01*
G01X106324Y161387D02*
X107424D01*
G01X109024D02*
X110124D01*
G01X115732Y270820D02*
Y266820D01*
G01X125680Y312714D02*
X121680D01*
G01X134400Y724800D02*
X130400D01*
G01X113400D02*
X109400D01*
G01Y735300D02*
X113400D01*
G01X130400D02*
X134400D01*
G01X125700Y763300D02*
Y759300D01*
G01Y757100D02*
Y758200D01*
G01Y754400D02*
Y755500D01*
G01X130300Y837000D02*
Y833000D01*
G01X142300Y308400D02*
Y304400D01*
G01X131800Y304500D02*
Y305600D01*
G01Y307200D02*
Y308300D01*
G01X142501Y409231D02*
Y410331D01*
G01Y411931D02*
Y413031D01*
G01X164200Y725900D02*
Y729900D01*
G01Y746900D02*
Y750900D01*
G01X157000Y781000D02*
Y785000D01*
G01Y802000D02*
Y806000D01*
G01X179938Y129211D02*
X181038D01*
G01X182638D02*
X183738D01*
G01X172994Y240961D02*
X171894D01*
G01X170294D02*
X169194D01*
G01X196500Y702000D02*
Y706000D01*
G01Y723000D02*
Y727000D01*
G01X174700Y750900D02*
Y746900D01*
G01Y729900D02*
Y725900D01*
G01X196500Y757500D02*
Y761500D01*
G01Y778500D02*
Y782500D01*
G01X167500Y785000D02*
Y781000D01*
G01Y806000D02*
Y802000D01*
G01X213000Y475500D02*
Y471500D01*
G01X211000Y531900D02*
Y530800D01*
G01Y529200D02*
Y528100D01*
G01X207000Y706000D02*
Y702000D01*
G01Y727000D02*
Y723000D01*
G01Y782500D02*
Y778500D01*
G01Y761500D02*
Y757500D01*
G01X263800Y650000D02*
Y651100D01*
G01Y652700D02*
Y653800D01*
G01X289000Y127900D02*
Y126800D01*
G01Y125200D02*
Y124100D01*
G01X285700Y632100D02*
Y631000D01*
G01Y629400D02*
Y628300D01*
G01X288200Y709300D02*
X292200D01*
G01X307839Y342401D02*
Y341301D01*
G01Y339701D02*
Y338601D01*
G01X309500Y710400D02*
Y714400D01*
G01X345900Y732900D02*
Y728900D01*
G01X473200Y365800D02*
Y369800D01*
G01X483700D02*
Y365800D01*
G01Y390800D02*
Y386800D01*
G01X473200D02*
Y390800D01*
G01X520109Y326541D02*
X519009D01*
G01X522809D02*
X521709D01*
G01X526700Y827700D02*
Y831700D01*
G01X546631Y365580D02*
X547731D01*
G01X549331D02*
X550431D01*
G01X566531Y382180D02*
Y383280D01*
G01Y384880D02*
Y385980D01*
G01X582178Y235969D02*
X578178D01*
G01X597363Y259608D02*
Y255608D01*
G01X611830Y338650D02*
X613830D01*
G01X655500Y355700D02*
Y356800D01*
G01Y358400D02*
Y359500D01*
G01X648900Y812500D02*
Y816500D01*
G01X870352Y743450D02*
Y739450D01*
G01X886600Y741800D02*
Y737800D01*
G01X888137Y814539D02*
Y810539D01*
G01X996597Y55869D02*
X992597D01*
G01X1026500Y68000D02*
X1030500D01*
G01X1172700Y812200D02*
Y816200D01*
G01X1301800Y816400D02*
Y820400D01*
G01X1344000Y244500D02*
Y248500D01*
G01X1355000Y268500D02*
X1359000D01*
G54D13*
G01X43416Y324607D02*
X48416D01*
Y329607D01*
G01X93740Y233681D02*
X96040D01*
G01X95188Y409465D02*
X98038D01*
Y406765D01*
G01X92100Y586200D02*
Y589800D01*
X96000D01*
G01X81400Y600600D02*
Y603450D01*
X84100D01*
G01X76869Y603320D02*
X79719D01*
Y600620D01*
G01X86900Y624900D02*
X84050D01*
Y627600D01*
G01X102046Y362104D02*
Y364954D01*
X104746D01*
G01X107408Y409392D02*
X110258D01*
Y406692D01*
G01X103900Y777700D02*
X102400D01*
G01X104600Y810050D02*
X110600D01*
Y815400D01*
G01X150200Y215200D02*
X146200D01*
Y221000D01*
G01X174984Y179536D02*
X173484D01*
G01X257097Y61939D02*
Y65339D01*
G01X265650Y501050D02*
Y504900D01*
X269450D01*
G01X301362Y470200D02*
Y467350D01*
X298662D01*
G01X296162Y494000D02*
X299012D01*
Y491300D01*
G01X279750Y508750D02*
Y504900D01*
X275950D01*
G01X500988Y4924D02*
X499138D01*
G01X500988Y10824D02*
X499138D01*
G01X500988Y28546D02*
X499138D01*
G01X500988Y34446D02*
X499138D01*
G01X500988Y52168D02*
X499138D01*
G01X500988Y58068D02*
X499138D01*
G01X500988Y75790D02*
X499138D01*
G01X500988Y81690D02*
X499138D01*
G01X520300Y168800D02*
X524500D01*
G01X607000Y356400D02*
Y352900D01*
X603200D01*
G01X704524Y71848D02*
X706374D01*
G01X704524Y65948D02*
X706374D01*
G01X727263Y-700D02*
X725413D01*
G01X727263Y-6600D02*
X725413D01*
G01X724209Y71848D02*
X726059D01*
G01X724209Y65948D02*
X726059D01*
G01X753600Y28600D02*
Y25750D01*
X750900D01*
G01X743894Y71848D02*
X745744D01*
G01X743894Y65948D02*
X745744D01*
G01X842434Y1135D02*
X844284D01*
G01X842434Y-4765D02*
X844284D01*
G01X896450Y59650D02*
Y53850D01*
X890650D01*
G01X1032058Y8075D02*
X1030558D01*
G01X1051650Y25050D02*
X1045850D01*
Y30850D01*
G01X1071854Y65948D02*
X1070004D01*
G01X1071854Y71848D02*
X1070004D01*
G01X1052169Y65948D02*
X1050319D01*
G01X1052169Y71848D02*
X1050319D01*
G01X1091539Y65948D02*
X1089689D01*
G01X1091539Y71848D02*
X1089689D01*
G01X1293106Y4924D02*
X1294956D01*
G01X1293106Y10824D02*
X1294956D01*
G01X1293106Y34446D02*
X1294956D01*
G01X1293106Y28546D02*
X1294956D01*
G01X1293106Y58068D02*
X1294956D01*
G01X1293106Y52168D02*
X1294956D01*
G01X1293106Y81690D02*
X1294956D01*
G01X1293106Y75790D02*
X1294956D01*
G01X1286720Y181193D02*
Y182693D01*
G54D14*
G01X276006Y739398D02*
Y732398D01*
G01X489506Y791398D02*
Y784398D01*
G01X859006Y768398D02*
Y761398D01*
G01X1263000Y359400D02*
Y352400D01*
G01X1303728Y696867D02*
Y689867D01*
G54D15*
G01X0Y212205D02*
Y237402D01*
G01Y431890D02*
Y406693D01*
G01Y601181D02*
Y626378D01*
G01Y795669D02*
Y820866D01*
G01X32016Y360757D02*
Y368507D01*
G01X123622Y102402D02*
X98425D01*
G01X232077Y0D02*
X257274D01*
G01X204528Y29961D02*
Y55157D01*
G01X269679Y346490D02*
X277429D01*
G01X287038Y575315D02*
X279288D01*
G01X459636Y0D02*
X434439D01*
G01X517459Y321191D02*
X509709D01*
G01X707234Y-19685D02*
X732431D01*
G01X895423D02*
X870226D01*
G01X871450Y48850D02*
X879200D01*
G01X1097785Y-19685D02*
X1072589D01*
G01X1361283Y0D02*
X1336086D01*
G01X1400000Y30709D02*
Y13026D01*
G01Y219685D02*
Y244882D01*
G01Y439370D02*
Y414173D01*
G01Y626378D02*
Y608661D01*
G01Y795669D02*
Y820866D01*
G54D16*
G01X182400Y280872D02*
X177400D01*
Y275872D01*
G01X286700Y208600D02*
Y213600D01*
X291700D01*
G01X338941Y332030D02*
X332241D01*
G01X352000Y205800D02*
Y200800D01*
X347000D01*
G01X464085Y174880D02*
X459085D01*
Y179880D01*
G01X467431Y212895D02*
Y207895D01*
X472431D01*
G01X489862Y206561D02*
X494862D01*
Y201561D01*
G01X533242Y209094D02*
X538242D01*
Y214094D01*
G01X746500Y17600D02*
Y22600D01*
X751500D01*
G01X811100Y14700D02*
Y9700D01*
X806100D01*
G01X819399Y3500D02*
Y-3500D01*
G01X820731Y291426D02*
X825731D01*
Y286426D01*
G01X1024800Y52600D02*
X1017100D01*
G01X1073757Y86054D02*
X1068757D01*
Y91054D01*
G01X1323290Y184800D02*
X1318290D01*
Y179800D01*
G54D17*
G01X128600Y733900D02*
Y741500D01*
G01X173300Y731700D02*
X180900D01*
G01X166100Y786800D02*
X173700D01*
G01X205600Y707800D02*
X213200D01*
G01X205600Y763300D02*
X213200D01*
G01X482300Y371600D02*
X489900D01*
G54D18*
G01X625350Y656000D02*
G03I-16350J0D01*
G54D19*
G01X45500Y481000D02*
Y477600D01*
G01X50500Y486500D02*
Y489900D01*
G01X217638Y428845D02*
X214238D01*
G01X247500Y356400D02*
X250900D01*
G01X259900Y425600D02*
X256500D01*
G01X264100Y470300D02*
Y473700D01*
M02*
